G04 ================== begin FILE IDENTIFICATION RECORD ==================*
G04 Layout Name:  E:/<user>/9332_F0TG_MB_C/brd/0417/9332_F0TG_MB_C_V02_0417_0820.brd*
G04 Film Name:    gnd2*
G04 File Format:  Gerber RS274X*
G04 File Origin:  Cadence Allegro 17.2-S081*
G04 Origin Date:  Wed Apr 19 14:50:08 2023*
G04 *
G04 Layer:  DRAWING FORMAT/TITLE_BLOCK_A*
G04 Layer:  PIN/SPECIAL_DRILL*
G04 Layer:  VIA CLASS/GND2*
G04 Layer:  PIN/GND2*
G04 Layer:  MANUFACTURING/PHOTOPLOT_OUTLINE*
G04 Layer:  ETCH/GND2*
G04 Layer:  DRAWING FORMAT/TITLE_BLOCK*
G04 Layer:  DRAWING FORMAT/TITLE_DATA_GND2*
G04 *
G04 Offset:    (0.00 0.00)*
G04 Mirror:    No*
G04 Mode:      Negative*
G04 Rotation:  0*
G04 FullContactRelief:  No*
G04 UndefLineWidth:     6.00*
G04 ================== end FILE IDENTIFICATION RECORD ====================*
%FSLAX25Y25*MOIN*%
%IR0*IPPOS*OFA0.00000B0.00000*MIA0B0*SFA1.00000B1.00000*%
%ADD14C,.03*%
%ADD39C,.06*%
%ADD30C,.024*%
%ADD67C,.052*%
%ADD25C,.061*%
%AMMACRO53*
4,1,36,0.0,.01,
-.001736,.009848,
-.00342,.009397,
-.005,.00866,
-.006428,.00766,
-.00766,.006428,
-.00866,.005,
-.009397,.00342,
-.009848,.001736,
-.01,0.0,
-.009848,-.001736,
-.009397,-.00342,
-.00866,-.005,
-.00766,-.006428,
-.006428,-.00766,
-.005,-.00866,
-.00342,-.009397,
-.001736,-.009848,
0.0,-.01,
.001736,-.009848,
.00342,-.009397,
.005,-.00866,
.006428,-.00766,
.00766,-.006428,
.00866,-.005,
.009397,-.00342,
.009848,-.001736,
.01,0.0,
.009848,.001736,
.009397,.00342,
.00866,.005,
.00766,.006428,
.006428,.00766,
.005,.00866,
.00342,.009397,
.001736,.009848,
0.0,.01,
0.0*
%
%ADD53MACRO53*%
%ADD42C,.071*%
%ADD23C,.026*%
%ADD63C,.064*%
%AMMACRO28*
4,1,36,.0025,0.0,
.002462,.000434,
.002349,.000855,
.002165,.00125,
.001915,.001607,
.001607,.001915,
.00125,.002165,
.000855,.002349,
.000434,.002462,
0.0,.0025,
-.000434,.002462,
-.000855,.002349,
-.00125,.002165,
-.001607,.001915,
-.001915,.001607,
-.002165,.00125,
-.002349,.000855,
-.002462,.000434,
-.0025,0.0,
-.002462,-.000434,
-.002349,-.000855,
-.002165,-.00125,
-.001915,-.001607,
-.001607,-.001915,
-.00125,-.002165,
-.000855,-.002349,
-.000434,-.002462,
0.0,-.0025,
.000434,-.002462,
.000855,-.002349,
.00125,-.002165,
.001607,-.001915,
.001915,-.001607,
.002165,-.00125,
.002349,-.000855,
.002462,-.000434,
.0025,0.0,
135.*
%
%ADD28MACRO28*%
%ADD24C,.028*%
%AMMACRO19*
4,1,36,.0025,0.0,
.002462,.000434,
.002349,.000855,
.002165,.00125,
.001915,.001607,
.001607,.001915,
.00125,.002165,
.000855,.002349,
.000434,.002462,
0.0,.0025,
-.000434,.002462,
-.000855,.002349,
-.00125,.002165,
-.001607,.001915,
-.001915,.001607,
-.002165,.00125,
-.002349,.000855,
-.002462,.000434,
-.0025,0.0,
-.002462,-.000434,
-.002349,-.000855,
-.002165,-.00125,
-.001915,-.001607,
-.001607,-.001915,
-.00125,-.002165,
-.000855,-.002349,
-.000434,-.002462,
0.0,-.0025,
.000434,-.002462,
.000855,-.002349,
.00125,-.002165,
.001607,-.001915,
.001915,-.001607,
.002165,-.00125,
.002349,-.000855,
.002462,-.000434,
.0025,0.0,
180.*
%
%ADD19MACRO19*%
%AMMACRO17*
4,1,36,.0025,0.0,
.002462,.000434,
.002349,.000855,
.002165,.00125,
.001915,.001607,
.001607,.001915,
.00125,.002165,
.000855,.002349,
.000434,.002462,
0.0,.0025,
-.000434,.002462,
-.000855,.002349,
-.00125,.002165,
-.001607,.001915,
-.001915,.001607,
-.002165,.00125,
-.002349,.000855,
-.002462,.000434,
-.0025,0.0,
-.002462,-.000434,
-.002349,-.000855,
-.002165,-.00125,
-.001915,-.001607,
-.001607,-.001915,
-.00125,-.002165,
-.000855,-.002349,
-.000434,-.002462,
0.0,-.0025,
.000434,-.002462,
.000855,-.002349,
.00125,-.002165,
.001607,-.001915,
.001915,-.001607,
.002165,-.00125,
.002349,-.000855,
.002462,-.000434,
.0025,0.0,
225.*
%
%ADD17MACRO17*%
%AMMACRO10*
4,1,36,.0025,0.0,
.002462,.000434,
.002349,.000855,
.002165,.00125,
.001915,.001607,
.001607,.001915,
.00125,.002165,
.000855,.002349,
.000434,.002462,
0.0,.0025,
-.000434,.002462,
-.000855,.002349,
-.00125,.002165,
-.001607,.001915,
-.001915,.001607,
-.002165,.00125,
-.002349,.000855,
-.002462,.000434,
-.0025,0.0,
-.002462,-.000434,
-.002349,-.000855,
-.002165,-.00125,
-.001915,-.001607,
-.001607,-.001915,
-.00125,-.002165,
-.000855,-.002349,
-.000434,-.002462,
0.0,-.0025,
.000434,-.002462,
.000855,-.002349,
.00125,-.002165,
.001607,-.001915,
.001915,-.001607,
.002165,-.00125,
.002349,-.000855,
.002462,-.000434,
.0025,0.0,
270.*
%
%ADD10MACRO10*%
%AMMACRO81*
4,1,36,.003,0.0,
.002954,.000521,
.002819,.001026,
.002598,.0015,
.002298,.001928,
.001928,.002298,
.0015,.002598,
.001026,.002819,
.000521,.002954,
0.0,.003,
-.000521,.002954,
-.001026,.002819,
-.0015,.002598,
-.001928,.002298,
-.002298,.001928,
-.002598,.0015,
-.002819,.001026,
-.002954,.000521,
-.003,0.0,
-.002954,-.000521,
-.002819,-.001026,
-.002598,-.0015,
-.002298,-.001928,
-.001928,-.002298,
-.0015,-.002598,
-.001026,-.002819,
-.000521,-.002954,
0.0,-.003,
.000521,-.002954,
.001026,-.002819,
.0015,-.002598,
.001928,-.002298,
.002298,-.001928,
.002598,-.0015,
.002819,-.001026,
.002954,-.000521,
.003,0.0,
270.*
%
%ADD81MACRO81*%
%AMMACRO43*
4,1,36,-.0025,0.0,
-.002462,.000434,
-.002349,.000855,
-.002165,.00125,
-.001915,.001607,
-.001607,.001915,
-.00125,.002165,
-.000855,.002349,
-.000434,.002462,
0.0,.0025,
.000434,.002462,
.000855,.002349,
.00125,.002165,
.001607,.001915,
.001915,.001607,
.002165,.00125,
.002349,.000855,
.002462,.000434,
.0025,0.0,
.002462,-.000434,
.002349,-.000855,
.002165,-.00125,
.001915,-.001607,
.001607,-.001915,
.00125,-.002165,
.000855,-.002349,
.000434,-.002462,
0.0,-.0025,
-.000434,-.002462,
-.000855,-.002349,
-.00125,-.002165,
-.001607,-.001915,
-.001915,-.001607,
-.002165,-.00125,
-.002349,-.000855,
-.002462,-.000434,
-.0025,0.0,
180.*
%
%ADD43MACRO43*%
%AMMACRO31*
4,1,36,.003,0.0,
.002954,.000521,
.002819,.001026,
.002598,.0015,
.002298,.001928,
.001928,.002298,
.0015,.002598,
.001026,.002819,
.000521,.002954,
0.0,.003,
-.000521,.002954,
-.001026,.002819,
-.0015,.002598,
-.001928,.002298,
-.002298,.001928,
-.002598,.0015,
-.002819,.001026,
-.002954,.000521,
-.003,0.0,
-.002954,-.000521,
-.002819,-.001026,
-.002598,-.0015,
-.002298,-.001928,
-.001928,-.002298,
-.0015,-.002598,
-.001026,-.002819,
-.000521,-.002954,
0.0,-.003,
.000521,-.002954,
.001026,-.002819,
.0015,-.002598,
.001928,-.002298,
.002298,-.001928,
.002598,-.0015,
.002819,-.001026,
.002954,-.000521,
.003,0.0,
180.*
%
%ADD31MACRO31*%
%ADD22C,.074*%
%ADD20C,.0263*%
%AMMACRO80*
4,1,36,-.003,0.0,
-.002954,.000521,
-.002819,.001026,
-.002598,.0015,
-.002298,.001928,
-.001928,.002298,
-.0015,.002598,
-.001026,.002819,
-.000521,.002954,
0.0,.003,
.000521,.002954,
.001026,.002819,
.0015,.002598,
.001928,.002298,
.002298,.001928,
.002598,.0015,
.002819,.001026,
.002954,.000521,
.003,0.0,
.002954,-.000521,
.002819,-.001026,
.002598,-.0015,
.002298,-.001928,
.001928,-.002298,
.0015,-.002598,
.001026,-.002819,
.000521,-.002954,
0.0,-.003,
-.000521,-.002954,
-.001026,-.002819,
-.0015,-.002598,
-.001928,-.002298,
-.002298,-.001928,
-.002598,-.0015,
-.002819,-.001026,
-.002954,-.000521,
-.003,0.0,
270.*
%
%ADD80MACRO80*%
%ADD79C,.0435*%
%ADD66C,.075*%
%ADD61C,.06015*%
%ADD47C,.066*%
%ADD50C,.076*%
%ADD49C,.095*%
%ADD41C,.0248*%
%ADD73C,.087*%
%ADD33C,.03417*%
%AMMACRO13*
4,1,18,.09673,.06845,
.107147,.050613,
.114308,.031238,
.117996,.010914,
.118098,-.009741,
.114613,-.030101,
.107644,-.049546,
.097406,-.067485,
.09673,-.06845,
.10175,-.07347,
.112962,-.054685,
.120742,-.034239,
.124853,-.012752,
.125171,.009122,
.121685,.030719,
.114502,.051383,
.10384,.070486,
.10175,.07347,
.09673,.06845,
0.0*
4,1,18,.06845,-.09673,
.050613,-.107147,
.031238,-.114308,
.010914,-.117996,
-.009741,-.118098,
-.030101,-.114613,
-.049546,-.107644,
-.067485,-.097406,
-.06845,-.09673,
-.07347,-.10175,
-.054685,-.112962,
-.034239,-.120742,
-.012752,-.124853,
.009122,-.125171,
.030719,-.121685,
.051383,-.114502,
.070486,-.10384,
.07347,-.10175,
.06845,-.09673,
0.0*
4,1,18,-.09673,-.06845,
-.107147,-.050613,
-.114308,-.031238,
-.117996,-.010914,
-.118098,.009741,
-.114613,.030101,
-.107644,.049546,
-.097406,.067485,
-.09673,.06845,
-.10175,.07347,
-.112962,.054685,
-.120742,.034239,
-.124853,.012752,
-.125171,-.009122,
-.121685,-.030719,
-.114502,-.051383,
-.10384,-.070486,
-.10175,-.07347,
-.09673,-.06845,
0.0*
4,1,18,-.06845,.09673,
-.050613,.107147,
-.031238,.114308,
-.010914,.117996,
.009741,.118098,
.030101,.114613,
.049546,.107644,
.067485,.097406,
.06845,.09673,
.07347,.10175,
.054685,.112962,
.034239,.120742,
.012752,.124853,
-.009122,.125171,
-.030719,.121685,
-.051383,.114502,
-.070486,.10384,
-.07347,.10175,
-.06845,.09673,
0.0*
%
%ADD13MACRO13*%
%AMMACRO35*
4,1,16,.0711,.04282,
.077455,.029823,
.081457,.01592,
.082984,.001533,
.08199,-.0129,
.078504,-.026942,
.072633,-.040164,
.0711,-.04282,
.07619,-.04791,
.083352,-.033952,
.087981,-.018962,
.089937,-.003396,
.089161,.012273,
.085675,.027569,
.079586,.042027,
.07619,.04791,
.0711,.04282,
0.0*
4,1,16,.04282,-.0711,
.029823,-.077455,
.01592,-.081457,
.001533,-.082984,
-.0129,-.08199,
-.026942,-.078504,
-.040164,-.072633,
-.04282,-.0711,
-.04791,-.07619,
-.033952,-.083352,
-.018962,-.087981,
-.003396,-.089937,
.012273,-.089161,
.027569,-.085675,
.042027,-.079586,
.04791,-.07619,
.04282,-.0711,
0.0*
4,1,16,-.0711,-.04282,
-.077455,-.029823,
-.081457,-.01592,
-.082984,-.001533,
-.08199,.0129,
-.078504,.026942,
-.072633,.040164,
-.0711,.04282,
-.07619,.04791,
-.083352,.033952,
-.087981,.018962,
-.089937,.003396,
-.089161,-.012273,
-.085675,-.027569,
-.079586,-.042027,
-.07619,-.04791,
-.0711,-.04282,
0.0*
4,1,16,-.04282,.0711,
-.029823,.077455,
-.01592,.081457,
-.001533,.082984,
.0129,.08199,
.026942,.078504,
.040164,.072633,
.04282,.0711,
.04791,.07619,
.033952,.083352,
.018962,.087981,
.003396,.089937,
-.012273,.089161,
-.027569,.085675,
-.042027,.079586,
-.04791,.07619,
-.04282,.0711,
0.0*
%
%ADD35MACRO35*%
%AMMACRO64*
4,1,16,.02584,.01524,
.028094,.010521,
.029494,.005483,
.029998,.000278,
.029591,-.004935,
.028284,-.009999,
.026118,-.014758,
.02584,-.01524,
.03092,-.02032,
.033979,-.014642,
.036005,-.008519,
.036938,-.002138,
.036748,.004309,
.035441,.010625,
.033058,.016618,
.03092,.02032,
.02584,.01524,
90.*
4,1,16,.01524,-.02584,
.010521,-.028094,
.005483,-.029494,
.000278,-.029998,
-.004935,-.029591,
-.009999,-.028284,
-.014758,-.026118,
-.01524,-.02584,
-.02032,-.03092,
-.014642,-.033979,
-.008519,-.036005,
-.002138,-.036938,
.004309,-.036748,
.010625,-.035441,
.016618,-.033058,
.02032,-.03092,
.01524,-.02584,
90.*
4,1,16,-.02584,-.01524,
-.028094,-.010521,
-.029494,-.005483,
-.029998,-.000278,
-.029591,.004935,
-.028284,.009999,
-.026118,.014758,
-.02584,.01524,
-.03092,.02032,
-.033979,.014642,
-.036005,.008519,
-.036938,.002138,
-.036748,-.004309,
-.035441,-.010625,
-.033058,-.016618,
-.03092,-.02032,
-.02584,-.01524,
90.*
4,1,16,-.01524,.02584,
-.010521,.028094,
-.005483,.029494,
-.000278,.029998,
.004935,.029591,
.009999,.028284,
.014758,.026118,
.01524,.02584,
.02032,.03092,
.014642,.033979,
.008519,.036005,
.002138,.036938,
-.004309,.036748,
-.010625,.035441,
-.016618,.033058,
-.02032,.03092,
-.01524,.02584,
90.*
%
%ADD64MACRO64*%
%AMMACRO46*
4,1,15,.02438,.01377,
.026401,.009327,
.027619,.004601,
.027999,-.000265,
.027527,-.005123,
.02622,-.009825,
.02438,-.01377,
.02948,-.01887,
.032309,-.013464,
.034156,-.007649,
.034965,-.001602,
.034712,.004494,
.033405,.010454,
.031082,.016095,
.02948,.01887,
.02438,.01377,
90.*
4,1,15,.01377,-.02438,
.009327,-.026401,
.004601,-.027619,
-.000265,-.027999,
-.005123,-.027527,
-.009825,-.02622,
-.01377,-.02438,
-.01887,-.02948,
-.013464,-.032309,
-.007649,-.034156,
-.001602,-.034965,
.004494,-.034712,
.010454,-.033405,
.016095,-.031082,
.01887,-.02948,
.01377,-.02438,
90.*
4,1,15,-.02438,-.01377,
-.026401,-.009327,
-.027619,-.004601,
-.027999,.000265,
-.027527,.005123,
-.02622,.009825,
-.02438,.01377,
-.02948,.01887,
-.032309,.013464,
-.034156,.007649,
-.034965,.001602,
-.034712,-.004494,
-.033405,-.010454,
-.031082,-.016095,
-.02948,-.01887,
-.02438,-.01377,
90.*
4,1,15,-.01377,.02438,
-.009327,.026401,
-.004601,.027619,
.000265,.027999,
.005123,.027527,
.009825,.02622,
.01377,.02438,
.01887,.02948,
.013464,.032309,
.007649,.034156,
.001602,.034965,
-.004494,.034712,
-.010454,.033405,
-.016095,.031082,
-.01887,.02948,
-.01377,.02438,
90.*
%
%ADD46MACRO46*%
%AMMACRO16*
4,1,16,.07001,.04172,
.076191,.028929,
.080057,.015259,
.08149,.001126,
.080448,-.013042,
.076961,-.026814,
.071136,-.03977,
.07001,-.04172,
.0751,-.04682,
.082089,-.033068,
.086584,-.018311,
.088449,-.002997,
.087625,.012407,
.08414,.027435,
.078097,.041629,
.0751,.04682,
.07001,.04172,
0.0*
4,1,16,.04172,-.07001,
.028929,-.076191,
.015259,-.080057,
.001126,-.08149,
-.013042,-.080448,
-.026814,-.076961,
-.03977,-.071136,
-.04172,-.07001,
-.04682,-.0751,
-.033068,-.082089,
-.018311,-.086584,
-.002997,-.088449,
.012407,-.087625,
.027435,-.08414,
.041629,-.078097,
.04682,-.0751,
.04172,-.07001,
0.0*
4,1,16,-.07001,-.04172,
-.076191,-.028929,
-.080057,-.015259,
-.08149,-.001126,
-.080448,.013042,
-.076961,.026814,
-.071136,.03977,
-.07001,.04172,
-.0751,.04682,
-.082089,.033068,
-.086584,.018311,
-.088449,.002997,
-.087625,-.012407,
-.08414,-.027435,
-.078097,-.041629,
-.0751,-.04682,
-.07001,-.04172,
0.0*
4,1,16,-.04172,.07001,
-.028929,.076191,
-.015259,.080057,
-.001126,.08149,
.013042,.080448,
.026814,.076961,
.03977,.071136,
.04172,.07001,
.04682,.0751,
.033068,.082089,
.018311,.086584,
.002997,.088449,
-.012407,.087625,
-.027435,.08414,
-.041629,.078097,
-.04682,.0751,
-.04172,.07001,
0.0*
%
%ADD16MACRO16*%
%AMMACRO65*
4,1,15,.02142,.01082,
.022973,.006936,
.023829,.002841,
.02396,-.00134,
.023364,-.00548,
.022057,-.009454,
.02142,-.01082,
.02657,-.01597,
.02894,-.011114,
.03043,-.005919,
.030995,-.000545,
.030619,.004845,
.029313,.010088,
.027115,.015025,
.02657,.01597,
.02142,.01082,
0.0*
4,1,15,.01082,-.02142,
.006936,-.022973,
.002841,-.023829,
-.00134,-.02396,
-.00548,-.023364,
-.009454,-.022057,
-.01082,-.02142,
-.01597,-.02657,
-.011114,-.02894,
-.005919,-.03043,
-.000545,-.030995,
.004845,-.030619,
.010088,-.029313,
.015025,-.027115,
.01597,-.02657,
.01082,-.02142,
0.0*
4,1,15,-.02142,-.01082,
-.022973,-.006936,
-.023829,-.002841,
-.02396,.00134,
-.023364,.00548,
-.022057,.009454,
-.02142,.01082,
-.02657,.01597,
-.02894,.011114,
-.03043,.005919,
-.030995,.000545,
-.030619,-.004845,
-.029313,-.010088,
-.027115,-.015025,
-.02657,-.01597,
-.02142,-.01082,
0.0*
4,1,15,-.01082,.02142,
-.006936,.022973,
-.002841,.023829,
.00134,.02396,
.00548,.023364,
.009454,.022057,
.01082,.02142,
.01597,.02657,
.011114,.02894,
.005919,.03043,
.000545,.030995,
-.004845,.030619,
-.010088,.029313,
-.015025,.027115,
-.01597,.02657,
-.01082,.02142,
0.0*
%
%ADD65MACRO65*%
%AMMACRO51*
4,1,15,.02475,.01414,
.026829,.009627,
.028094,.004822,
.028504,-.000129,
.028049,-.005077,
.026741,-.009871,
.02475,-.01414,
.02984,-.01923,
.032726,-.013756,
.034617,-.007864,
.035457,-.001734,
.03522,.00445,
.033912,.010498,
.031574,.016227,
.02984,.01923,
.02475,.01414,
0.0*
4,1,15,.01414,-.02475,
.009627,-.026829,
.004822,-.028094,
-.000129,-.028504,
-.005077,-.028049,
-.009871,-.026741,
-.01414,-.02475,
-.01923,-.02984,
-.013756,-.032726,
-.007864,-.034617,
-.001734,-.035457,
.00445,-.03522,
.010498,-.033912,
.016227,-.031574,
.01923,-.02984,
.01414,-.02475,
0.0*
4,1,15,-.02475,-.01414,
-.026829,-.009627,
-.028094,-.004822,
-.028504,.000129,
-.028049,.005077,
-.026741,.009871,
-.02475,.01414,
-.02984,.01923,
-.032726,.013756,
-.034617,.007864,
-.035457,.001734,
-.03522,-.00445,
-.033912,-.010498,
-.031574,-.016227,
-.02984,-.01923,
-.02475,-.01414,
0.0*
4,1,15,-.01414,.02475,
-.009627,.026829,
-.004822,.028094,
.000129,.028504,
.005077,.028049,
.009871,.026741,
.01414,.02475,
.01923,.02984,
.013756,.032726,
.007864,.034617,
.001734,.035457,
-.00445,.03522,
-.010498,.033912,
-.016227,.031574,
-.01923,.02984,
-.01414,.02475,
0.0*
%
%ADD51MACRO51*%
%AMMACRO76*
4,1,15,.03682,.01914,
.039584,.012455,
.041146,.005393,
.041457,-.001834,
.040509,-.009005,
.03833,-.015903,
.03682,-.01914,
.04197,-.0243,
.045552,-.016643,
.04775,-.00848,
.048497,-.000059,
.047771,.008363,
.045593,.016531,
.042029,.024197,
.04197,.0243,
.03682,.01914,
0.0*
4,1,15,.01914,-.03682,
.012455,-.039584,
.005393,-.041146,
-.001834,-.041457,
-.009005,-.040509,
-.015903,-.03833,
-.01914,-.03682,
-.0243,-.04197,
-.016643,-.045552,
-.00848,-.04775,
-.000059,-.048497,
.008363,-.047771,
.016531,-.045593,
.024197,-.042029,
.0243,-.04197,
.01914,-.03682,
0.0*
4,1,15,-.03682,-.01914,
-.039584,-.012455,
-.041146,-.005393,
-.041457,.001834,
-.040509,.009005,
-.03833,.015903,
-.03682,.01914,
-.04197,.0243,
-.045552,.016643,
-.04775,.00848,
-.048497,.000059,
-.047771,-.008363,
-.045593,-.016531,
-.042029,-.024197,
-.04197,-.0243,
-.03682,-.01914,
0.0*
4,1,15,-.01914,.03682,
-.012455,.039584,
-.005393,.041146,
.001834,.041457,
.009005,.040509,
.015903,.03833,
.01914,.03682,
.0243,.04197,
.016643,.045552,
.00848,.04775,
.000059,.048497,
-.008363,.047771,
-.016531,.045593,
-.024197,.042029,
-.0243,.04197,
-.01914,.03682,
0.0*
%
%ADD76MACRO76*%
%AMMACRO72*
4,1,36,.0025,0.0,
.002462,.000434,
.002349,.000855,
.002165,.00125,
.001915,.001607,
.001607,.001915,
.00125,.002165,
.000855,.002349,
.000434,.002462,
0.0,.0025,
-.000434,.002462,
-.000855,.002349,
-.00125,.002165,
-.001607,.001915,
-.001915,.001607,
-.002165,.00125,
-.002349,.000855,
-.002462,.000434,
-.0025,0.0,
-.002462,-.000434,
-.002349,-.000855,
-.002165,-.00125,
-.001915,-.001607,
-.001607,-.001915,
-.00125,-.002165,
-.000855,-.002349,
-.000434,-.002462,
0.0,-.0025,
.000434,-.002462,
.000855,-.002349,
.00125,-.002165,
.001607,-.001915,
.001915,-.001607,
.002165,-.00125,
.002349,-.000855,
.002462,-.000434,
.0025,0.0,
134.996*
%
%ADD72MACRO72*%
%AMMACRO74*
4,1,15,-.03682,.01914,
-.039584,.012455,
-.041146,.005393,
-.041457,-.001834,
-.040509,-.009005,
-.03833,-.015903,
-.03682,-.01914,
-.04197,-.0243,
-.045552,-.016643,
-.04775,-.00848,
-.048497,-.000059,
-.047771,.008363,
-.045593,.016531,
-.042029,.024197,
-.04197,.0243,
-.03682,.01914,
0.0*
4,1,15,-.01914,-.03682,
-.012455,-.039584,
-.005393,-.041146,
.001834,-.041457,
.009005,-.040509,
.015903,-.03833,
.01914,-.03682,
.0243,-.04197,
.016643,-.045552,
.00848,-.04775,
.000059,-.048497,
-.008363,-.047771,
-.016531,-.045593,
-.024197,-.042029,
-.0243,-.04197,
-.01914,-.03682,
0.0*
4,1,15,.03682,-.01914,
.039584,-.012455,
.041146,-.005393,
.041457,.001834,
.040509,.009005,
.03833,.015903,
.03682,.01914,
.04197,.0243,
.045552,.016643,
.04775,.00848,
.048497,.000059,
.047771,-.008363,
.045593,-.016531,
.042029,-.024197,
.04197,-.0243,
.03682,-.01914,
0.0*
4,1,15,.01914,.03682,
.012455,.039584,
.005393,.041146,
-.001834,.041457,
-.009005,.040509,
-.015903,.03833,
-.01914,.03682,
-.0243,.04197,
-.016643,.045552,
-.00848,.04775,
-.000059,.048497,
.008363,.047771,
.016531,.045593,
.024197,.042029,
.0243,.04197,
.01914,.03682,
0.0*
%
%ADD74MACRO74*%
%AMMACRO37*
4,1,36,.003,0.0,
.002954,.000521,
.002819,.001026,
.002598,.0015,
.002298,.001928,
.001928,.002298,
.0015,.002598,
.001026,.002819,
.000521,.002954,
0.0,.003,
-.000521,.002954,
-.001026,.002819,
-.0015,.002598,
-.001928,.002298,
-.002298,.001928,
-.002598,.0015,
-.002819,.001026,
-.002954,.000521,
-.003,0.0,
-.002954,-.000521,
-.002819,-.001026,
-.002598,-.0015,
-.002298,-.001928,
-.001928,-.002298,
-.0015,-.002598,
-.001026,-.002819,
-.000521,-.002954,
0.0,-.003,
.000521,-.002954,
.001026,-.002819,
.0015,-.002598,
.001928,-.002298,
.002298,-.001928,
.002598,-.0015,
.002819,-.001026,
.002954,-.000521,
.003,0.0,
179.996*
%
%ADD37MACRO37*%
%ADD59O,.285X.23*%
%ADD71C,.142*%
%AMMACRO60*
4,1,36,0.0,.01,
-.001736,.009848,
-.00342,.009397,
-.005,.00866,
-.006428,.00766,
-.00766,.006428,
-.00866,.005,
-.009397,.00342,
-.009848,.001736,
-.01,0.0,
-.009848,-.001736,
-.009397,-.00342,
-.00866,-.005,
-.00766,-.006428,
-.006428,-.00766,
-.005,-.00866,
-.00342,-.009397,
-.001736,-.009848,
0.0,-.01,
.001736,-.009848,
.00342,-.009397,
.005,-.00866,
.006428,-.00766,
.00766,-.006428,
.00866,-.005,
.009397,-.00342,
.009848,-.001736,
.01,0.0,
.009848,.001736,
.009397,.00342,
.00866,.005,
.00766,.006428,
.006428,.00766,
.005,.00866,
.00342,.009397,
.001736,.009848,
0.0,.01,
180.*
%
%ADD60MACRO60*%
%ADD34O,.219X.156*%
%ADD11C,.125*%
%ADD27C,.424*%
%ADD18C,.155*%
%ADD52C,.291*%
%ADD54C,.247*%
%ADD45C,.256*%
%AMMACRO32*
4,1,36,0.0,.0085,
.001476,.008371,
.002907,.007987,
.00425,.007361,
.005464,.006511,
.006511,.005464,
.007361,.00425,
.007987,.002907,
.008371,.001476,
.0085,0.0,
.008371,-.001476,
.007987,-.002907,
.007361,-.00425,
.006511,-.005464,
.005464,-.006511,
.00425,-.007361,
.002907,-.007987,
.001476,-.008371,
0.0,-.0085,
-.001476,-.008371,
-.002907,-.007987,
-.00425,-.007361,
-.005464,-.006511,
-.006511,-.005464,
-.007361,-.00425,
-.007987,-.002907,
-.008371,-.001476,
-.0085,0.0,
-.008371,.001476,
-.007987,.002907,
-.007361,.00425,
-.006511,.005464,
-.005464,.006511,
-.00425,.007361,
-.002907,.007987,
-.001476,.008371,
0.0,.0085,
180.*
%
%ADD32MACRO32*%
%AMMACRO58*
4,1,20,-.0075,-.05555,
-.0075,-.06273,
-.013677,-.060878,
-.019439,-.057981,
-.024611,-.054127,
-.029034,-.049434,
-.032576,-.044045,
-.035127,-.038122,
-.036612,-.031846,
-.037,-.0265,
-.037,-.0075,
-.03,-.0075,
-.03,-.0265,
-.029544,-.03171,
-.028191,-.036762,
-.02598,-.041502,
-.022981,-.045786,
-.019282,-.049484,
-.014998,-.052484,
-.010258,-.054694,
-.0075,-.05555,
90.*
4,1,20,.0075,-.06273,
.0075,-.05555,
.01243,-.053806,
.016983,-.051232,
.02102,-.047906,
.024418,-.043931,
.027073,-.039425,
.028906,-.034527,
.029861,-.029385,
.03,-.0265,
.03,-.0075,
.037,-.0075,
.037,-.0265,
.036438,-.032925,
.034769,-.039154,
.032043,-.044999,
.028344,-.050282,
.023784,-.054842,
.018501,-.058541,
.012656,-.061266,
.0075,-.06273,
90.*
4,1,20,-.0075,.06273,
-.0075,.05555,
-.01243,.053806,
-.016983,.051232,
-.02102,.047906,
-.024418,.043931,
-.027073,.039425,
-.028906,.034527,
-.029861,.029385,
-.03,.0265,
-.03,.0075,
-.037,.0075,
-.037,.0265,
-.036438,.032925,
-.034769,.039154,
-.032043,.044999,
-.028344,.050282,
-.023784,.054842,
-.018501,.058541,
-.012656,.061266,
-.0075,.06273,
90.*
4,1,20,.0075,.05555,
.0075,.06273,
.013677,.060878,
.019439,.057981,
.024611,.054127,
.029034,.049434,
.032576,.044045,
.035127,.038122,
.036612,.031846,
.037,.0265,
.037,.0075,
.03,.0075,
.03,.0265,
.029544,.03171,
.028191,.036762,
.02598,.041502,
.022981,.045786,
.019282,.049484,
.014998,.052484,
.010258,.054694,
.0075,.05555,
90.*
%
%ADD58MACRO58*%
%AMMACRO15*
4,1,36,.0025,0.0,
.002462,.000434,
.002349,.000855,
.002165,.00125,
.001915,.001607,
.001607,.001915,
.00125,.002165,
.000855,.002349,
.000434,.002462,
0.0,.0025,
-.000434,.002462,
-.000855,.002349,
-.00125,.002165,
-.001607,.001915,
-.001915,.001607,
-.002165,.00125,
-.002349,.000855,
-.002462,.000434,
-.0025,0.0,
-.002462,-.000434,
-.002349,-.000855,
-.002165,-.00125,
-.001915,-.001607,
-.001607,-.001915,
-.00125,-.002165,
-.000855,-.002349,
-.000434,-.002462,
0.0,-.0025,
.000434,-.002462,
.000855,-.002349,
.00125,-.002165,
.001607,-.001915,
.001915,-.001607,
.002165,-.00125,
.002349,-.000855,
.002462,-.000434,
.0025,0.0,
90.*
%
%ADD15MACRO15*%
%AMMACRO55*
4,1,36,0.0,.019,
-.003299,.018711,
-.006498,.017854,
-.0095,.016454,
-.012213,.014555,
-.014555,.012213,
-.016454,.0095,
-.017854,.006498,
-.018711,.003299,
-.019,0.0,
-.018711,-.003299,
-.017854,-.006498,
-.016454,-.0095,
-.014555,-.012213,
-.012213,-.014555,
-.0095,-.016454,
-.006498,-.017854,
-.003299,-.018711,
0.0,-.019,
.003299,-.018711,
.006498,-.017854,
.0095,-.016454,
.012213,-.014555,
.014555,-.012213,
.016454,-.0095,
.017854,-.006498,
.018711,-.003299,
.019,0.0,
.018711,.003299,
.017854,.006498,
.016454,.0095,
.014555,.012213,
.012213,.014555,
.0095,.016454,
.006498,.017854,
.003299,.018711,
0.0,.019,
270.*
%
%ADD55MACRO55*%
%AMMACRO38*
4,1,36,.003,0.0,
.002954,.000521,
.002819,.001026,
.002598,.0015,
.002298,.001928,
.001928,.002298,
.0015,.002598,
.001026,.002819,
.000521,.002954,
0.0,.003,
-.000521,.002954,
-.001026,.002819,
-.0015,.002598,
-.001928,.002298,
-.002298,.001928,
-.002598,.0015,
-.002819,.001026,
-.002954,.000521,
-.003,0.0,
-.002954,-.000521,
-.002819,-.001026,
-.002598,-.0015,
-.002298,-.001928,
-.001928,-.002298,
-.0015,-.002598,
-.001026,-.002819,
-.000521,-.002954,
0.0,-.003,
.000521,-.002954,
.001026,-.002819,
.0015,-.002598,
.001928,-.002298,
.002298,-.001928,
.002598,-.0015,
.002819,-.001026,
.002954,-.000521,
.003,0.0,
90.*
%
%ADD38MACRO38*%
%AMMACRO12*
4,1,36,.0025,0.0,
.002462,.000434,
.002349,.000855,
.002165,.00125,
.001915,.001607,
.001607,.001915,
.00125,.002165,
.000855,.002349,
.000434,.002462,
0.0,.0025,
-.000434,.002462,
-.000855,.002349,
-.00125,.002165,
-.001607,.001915,
-.001915,.001607,
-.002165,.00125,
-.002349,.000855,
-.002462,.000434,
-.0025,0.0,
-.002462,-.000434,
-.002349,-.000855,
-.002165,-.00125,
-.001915,-.001607,
-.001607,-.001915,
-.00125,-.002165,
-.000855,-.002349,
-.000434,-.002462,
0.0,-.0025,
.000434,-.002462,
.000855,-.002349,
.00125,-.002165,
.001607,-.001915,
.001915,-.001607,
.002165,-.00125,
.002349,-.000855,
.002462,-.000434,
.0025,0.0,
0.0*
%
%ADD12MACRO12*%
%AMMACRO78*
4,1,36,-.003,0.0,
-.002954,.000521,
-.002819,.001026,
-.002598,.0015,
-.002298,.001928,
-.001928,.002298,
-.0015,.002598,
-.001026,.002819,
-.000521,.002954,
0.0,.003,
.000521,.002954,
.001026,.002819,
.0015,.002598,
.001928,.002298,
.002298,.001928,
.002598,.0015,
.002819,.001026,
.002954,.000521,
.003,0.0,
.002954,-.000521,
.002819,-.001026,
.002598,-.0015,
.002298,-.001928,
.001928,-.002298,
.0015,-.002598,
.001026,-.002819,
.000521,-.002954,
0.0,-.003,
-.000521,-.002954,
-.001026,-.002819,
-.0015,-.002598,
-.001928,-.002298,
-.002298,-.001928,
-.002598,-.0015,
-.002819,-.001026,
-.002954,-.000521,
-.003,0.0,
90.*
%
%ADD78MACRO78*%
%AMMACRO44*
4,1,36,-.0025,0.0,
-.002462,.000434,
-.002349,.000855,
-.002165,.00125,
-.001915,.001607,
-.001607,.001915,
-.00125,.002165,
-.000855,.002349,
-.000434,.002462,
0.0,.0025,
.000434,.002462,
.000855,.002349,
.00125,.002165,
.001607,.001915,
.001915,.001607,
.002165,.00125,
.002349,.000855,
.002462,.000434,
.0025,0.0,
.002462,-.000434,
.002349,-.000855,
.002165,-.00125,
.001915,-.001607,
.001607,-.001915,
.00125,-.002165,
.000855,-.002349,
.000434,-.002462,
0.0,-.0025,
-.000434,-.002462,
-.000855,-.002349,
-.00125,-.002165,
-.001607,-.001915,
-.001915,-.001607,
-.002165,-.00125,
-.002349,-.000855,
-.002462,-.000434,
-.0025,0.0,
0.0*
%
%ADD44MACRO44*%
%ADD36C,.188*%
%AMMACRO29*
4,1,36,.003,0.0,
.002954,.000521,
.002819,.001026,
.002598,.0015,
.002298,.001928,
.001928,.002298,
.0015,.002598,
.001026,.002819,
.000521,.002954,
0.0,.003,
-.000521,.002954,
-.001026,.002819,
-.0015,.002598,
-.001928,.002298,
-.002298,.001928,
-.002598,.0015,
-.002819,.001026,
-.002954,.000521,
-.003,0.0,
-.002954,-.000521,
-.002819,-.001026,
-.002598,-.0015,
-.002298,-.001928,
-.001928,-.002298,
-.0015,-.002598,
-.001026,-.002819,
-.000521,-.002954,
0.0,-.003,
.000521,-.002954,
.001026,-.002819,
.0015,-.002598,
.001928,-.002298,
.002298,-.001928,
.002598,-.0015,
.002819,-.001026,
.002954,-.000521,
.003,0.0,
0.0*
%
%ADD29MACRO29*%
%AMMACRO21*
4,1,16,.02584,.01524,
.028094,.010521,
.029494,.005483,
.029998,.000278,
.029591,-.004935,
.028284,-.009999,
.026118,-.014758,
.02584,-.01524,
.03092,-.02032,
.033979,-.014642,
.036005,-.008519,
.036938,-.002138,
.036748,.004309,
.035441,.010625,
.033058,.016618,
.03092,.02032,
.02584,.01524,
180.*
4,1,16,.01524,-.02584,
.010521,-.028094,
.005483,-.029494,
.000278,-.029998,
-.004935,-.029591,
-.009999,-.028284,
-.014758,-.026118,
-.01524,-.02584,
-.02032,-.03092,
-.014642,-.033979,
-.008519,-.036005,
-.002138,-.036938,
.004309,-.036748,
.010625,-.035441,
.016618,-.033058,
.02032,-.03092,
.01524,-.02584,
180.*
4,1,16,-.02584,-.01524,
-.028094,-.010521,
-.029494,-.005483,
-.029998,-.000278,
-.029591,.004935,
-.028284,.009999,
-.026118,.014758,
-.02584,.01524,
-.03092,.02032,
-.033979,.014642,
-.036005,.008519,
-.036938,.002138,
-.036748,-.004309,
-.035441,-.010625,
-.033058,-.016618,
-.03092,-.02032,
-.02584,-.01524,
180.*
4,1,16,-.01524,.02584,
-.010521,.028094,
-.005483,.029494,
-.000278,.029998,
.004935,.029591,
.009999,.028284,
.014758,.026118,
.01524,.02584,
.02032,.03092,
.014642,.033979,
.008519,.036005,
.002138,.036938,
-.004309,.036748,
-.010625,.035441,
-.016618,.033058,
-.02032,.03092,
-.01524,.02584,
180.*
%
%ADD21MACRO21*%
%AMMACRO62*
4,1,15,.02438,.01377,
.026401,.009327,
.027619,.004601,
.027999,-.000265,
.027527,-.005123,
.02622,-.009825,
.02438,-.01377,
.02948,-.01887,
.032309,-.013464,
.034156,-.007649,
.034965,-.001602,
.034712,.004494,
.033405,.010454,
.031082,.016095,
.02948,.01887,
.02438,.01377,
270.*
4,1,15,.01377,-.02438,
.009327,-.026401,
.004601,-.027619,
-.000265,-.027999,
-.005123,-.027527,
-.009825,-.02622,
-.01377,-.02438,
-.01887,-.02948,
-.013464,-.032309,
-.007649,-.034156,
-.001602,-.034965,
.004494,-.034712,
.010454,-.033405,
.016095,-.031082,
.01887,-.02948,
.01377,-.02438,
270.*
4,1,15,-.02438,-.01377,
-.026401,-.009327,
-.027619,-.004601,
-.027999,.000265,
-.027527,.005123,
-.02622,.009825,
-.02438,.01377,
-.02948,.01887,
-.032309,.013464,
-.034156,.007649,
-.034965,.001602,
-.034712,-.004494,
-.033405,-.010454,
-.031082,-.016095,
-.02948,-.01887,
-.02438,-.01377,
270.*
4,1,15,-.01377,.02438,
-.009327,.026401,
-.004601,.027619,
.000265,.027999,
.005123,.027527,
.009825,.02622,
.01377,.02438,
.01887,.02948,
.013464,.032309,
.007649,.034156,
.001602,.034965,
-.004494,.034712,
-.010454,.033405,
-.016095,.031082,
-.01887,.02948,
-.01377,.02438,
270.*
%
%ADD62MACRO62*%
%AMMACRO40*
4,1,15,.02438,.01377,
.026401,.009327,
.027619,.004601,
.027999,-.000265,
.027527,-.005123,
.02622,-.009825,
.02438,-.01377,
.02948,-.01887,
.032309,-.013464,
.034156,-.007649,
.034965,-.001602,
.034712,.004494,
.033405,.010454,
.031082,.016095,
.02948,.01887,
.02438,.01377,
180.*
4,1,15,.01377,-.02438,
.009327,-.026401,
.004601,-.027619,
-.000265,-.027999,
-.005123,-.027527,
-.009825,-.02622,
-.01377,-.02438,
-.01887,-.02948,
-.013464,-.032309,
-.007649,-.034156,
-.001602,-.034965,
.004494,-.034712,
.010454,-.033405,
.016095,-.031082,
.01887,-.02948,
.01377,-.02438,
180.*
4,1,15,-.02438,-.01377,
-.026401,-.009327,
-.027619,-.004601,
-.027999,.000265,
-.027527,.005123,
-.02622,.009825,
-.02438,.01377,
-.02948,.01887,
-.032309,.013464,
-.034156,.007649,
-.034965,.001602,
-.034712,-.004494,
-.033405,-.010454,
-.031082,-.016095,
-.02948,-.01887,
-.02438,-.01377,
180.*
4,1,15,-.01377,.02438,
-.009327,.026401,
-.004601,.027619,
.000265,.027999,
.005123,.027527,
.009825,.02622,
.01377,.02438,
.01887,.02948,
.013464,.032309,
.007649,.034156,
.001602,.034965,
-.004494,.034712,
-.010454,.033405,
-.016095,.031082,
-.01887,.02948,
-.01377,.02438,
180.*
%
%ADD40MACRO40*%
%AMMACRO26*
4,1,20,-.039,.0245,
-.038408,.031272,
-.036648,.037838,
-.033775,.043999,
-.029876,.049567,
-.02507,.054374,
-.019501,.058273,
-.01334,.061146,
-.0075,.06277,
-.0075,.05561,
-.012788,.053835,
-.017688,.051168,
-.02205,.047691,
-.025742,.04351,
-.028652,.038751,
-.030691,.033558,
-.031798,.028091,
-.032,.0245,
-.032,.0075,
-.039,.0075,
-.039,.0245,
90.*
4,1,20,-.039,-.0075,
-.032,-.0075,
-.032,-.0245,
-.031514,-.030057,
-.03007,-.035445,
-.027713,-.040501,
-.024513,-.04507,
-.020569,-.049015,
-.015999,-.052214,
-.010944,-.054572,
-.0075,-.05561,
-.0075,-.06277,
-.014032,-.060887,
-.020137,-.057898,
-.025631,-.053894,
-.030345,-.048997,
-.034138,-.043356,
-.036894,-.037142,
-.038529,-.030544,
-.039,-.0245,
-.039,-.0075,
90.*
4,1,20,.0075,.06277,
.014032,.060887,
.020137,.057898,
.025631,.053894,
.030345,.048997,
.034138,.043356,
.036894,.037142,
.038529,.030544,
.039,.0245,
.039,.0075,
.032,.0075,
.032,.0245,
.031514,.030057,
.03007,.035445,
.027713,.040501,
.024513,.04507,
.020569,.049015,
.015999,.052214,
.010944,.054572,
.0075,.05561,
.0075,.06277,
90.*
4,1,20,.0075,-.05561,
.012788,-.053835,
.017688,-.051168,
.02205,-.047691,
.025742,-.04351,
.028652,-.038751,
.030691,-.033558,
.031798,-.028091,
.032,-.0245,
.032,-.0075,
.039,-.0075,
.039,-.0245,
.038408,-.031272,
.036648,-.037838,
.033775,-.043999,
.029876,-.049567,
.02507,-.054374,
.019501,-.058273,
.01334,-.061146,
.0075,-.06277,
.0075,-.05561,
90.*
%
%ADD26MACRO26*%
%AMMACRO70*
4,1,15,.02475,.01414,
.026829,.009627,
.028094,.004822,
.028504,-.000129,
.028049,-.005077,
.026741,-.009871,
.02475,-.01414,
.02984,-.01923,
.032726,-.013756,
.034617,-.007864,
.035457,-.001734,
.03522,.00445,
.033912,.010498,
.031574,.016227,
.02984,.01923,
.02475,.01414,
270.*
4,1,15,.01414,-.02475,
.009627,-.026829,
.004822,-.028094,
-.000129,-.028504,
-.005077,-.028049,
-.009871,-.026741,
-.01414,-.02475,
-.01923,-.02984,
-.013756,-.032726,
-.007864,-.034617,
-.001734,-.035457,
.00445,-.03522,
.010498,-.033912,
.016227,-.031574,
.01923,-.02984,
.01414,-.02475,
270.*
4,1,15,-.02475,-.01414,
-.026829,-.009627,
-.028094,-.004822,
-.028504,.000129,
-.028049,.005077,
-.026741,.009871,
-.02475,.01414,
-.02984,.01923,
-.032726,.013756,
-.034617,.007864,
-.035457,.001734,
-.03522,-.00445,
-.033912,-.010498,
-.031574,-.016227,
-.02984,-.01923,
-.02475,-.01414,
270.*
4,1,15,-.01414,.02475,
-.009627,.026829,
-.004822,.028094,
.000129,.028504,
.005077,.028049,
.009871,.026741,
.01414,.02475,
.01923,.02984,
.013756,.032726,
.007864,.034617,
.001734,.035457,
-.00445,.03522,
-.010498,.033912,
-.016227,.031574,
-.01923,.02984,
-.01414,.02475,
270.*
%
%ADD70MACRO70*%
%AMMACRO69*
4,1,15,.02142,.01082,
.022973,.006936,
.023829,.002841,
.02396,-.00134,
.023364,-.00548,
.022057,-.009454,
.02142,-.01082,
.02657,-.01597,
.02894,-.011114,
.03043,-.005919,
.030995,-.000545,
.030619,.004845,
.029313,.010088,
.027115,.015025,
.02657,.01597,
.02142,.01082,
180.*
4,1,15,.01082,-.02142,
.006936,-.022973,
.002841,-.023829,
-.00134,-.02396,
-.00548,-.023364,
-.009454,-.022057,
-.01082,-.02142,
-.01597,-.02657,
-.011114,-.02894,
-.005919,-.03043,
-.000545,-.030995,
.004845,-.030619,
.010088,-.029313,
.015025,-.027115,
.01597,-.02657,
.01082,-.02142,
180.*
4,1,15,-.02142,-.01082,
-.022973,-.006936,
-.023829,-.002841,
-.02396,.00134,
-.023364,.00548,
-.022057,.009454,
-.02142,.01082,
-.02657,.01597,
-.02894,.011114,
-.03043,.005919,
-.030995,.000545,
-.030619,-.004845,
-.029313,-.010088,
-.027115,-.015025,
-.02657,-.01597,
-.02142,-.01082,
180.*
4,1,15,-.01082,.02142,
-.006936,.022973,
-.002841,.023829,
.00134,.02396,
.00548,.023364,
.009454,.022057,
.01082,.02142,
.01597,.02657,
.011114,.02894,
.005919,.03043,
.000545,.030995,
-.004845,.030619,
-.010088,.029313,
-.015025,.027115,
-.01597,.02657,
-.01082,.02142,
180.*
%
%ADD69MACRO69*%
%AMMACRO68*
4,1,15,.02475,.01414,
.026829,.009627,
.028094,.004822,
.028504,-.000129,
.028049,-.005077,
.026741,-.009871,
.02475,-.01414,
.02984,-.01923,
.032726,-.013756,
.034617,-.007864,
.035457,-.001734,
.03522,.00445,
.033912,.010498,
.031574,.016227,
.02984,.01923,
.02475,.01414,
180.*
4,1,15,.01414,-.02475,
.009627,-.026829,
.004822,-.028094,
-.000129,-.028504,
-.005077,-.028049,
-.009871,-.026741,
-.01414,-.02475,
-.01923,-.02984,
-.013756,-.032726,
-.007864,-.034617,
-.001734,-.035457,
.00445,-.03522,
.010498,-.033912,
.016227,-.031574,
.01923,-.02984,
.01414,-.02475,
180.*
4,1,15,-.02475,-.01414,
-.026829,-.009627,
-.028094,-.004822,
-.028504,.000129,
-.028049,.005077,
-.026741,.009871,
-.02475,.01414,
-.02984,.01923,
-.032726,.013756,
-.034617,.007864,
-.035457,.001734,
-.03522,-.00445,
-.033912,-.010498,
-.031574,-.016227,
-.02984,-.01923,
-.02475,-.01414,
180.*
4,1,15,-.01414,.02475,
-.009627,.026829,
-.004822,.028094,
.000129,.028504,
.005077,.028049,
.009871,.026741,
.01414,.02475,
.01923,.02984,
.013756,.032726,
.007864,.034617,
.001734,.035457,
-.00445,.03522,
-.010498,.033912,
-.016227,.031574,
-.01923,.02984,
-.01414,.02475,
180.*
%
%ADD68MACRO68*%
%AMMACRO56*
4,1,18,.07103,.05689,
.07983,.043691,
.086204,.029165,
.089959,.013753,
.09098,-.002077,
.089237,-.017844,
.084783,-.033069,
.077753,-.047289,
.07103,-.05689,
.07601,-.06186,
.085597,-.047721,
.092583,-.032132,
.096757,-.015567,
.09799,.001471,
.096246,.018464,
.091577,.034897,
.084126,.050269,
.07601,.06186,
.07103,.05689,
270.*
4,1,18,.05689,-.07103,
.043691,-.07983,
.029165,-.086204,
.013753,-.089959,
-.002077,-.09098,
-.017844,-.089237,
-.033069,-.084783,
-.047289,-.077753,
-.05689,-.07103,
-.06186,-.07601,
-.047721,-.085597,
-.032132,-.092583,
-.015567,-.096757,
.001471,-.09799,
.018464,-.096246,
.034897,-.091577,
.050269,-.084126,
.06186,-.07601,
.05689,-.07103,
270.*
4,1,18,-.07103,-.05689,
-.07983,-.043691,
-.086204,-.029165,
-.089959,-.013753,
-.09098,.002077,
-.089237,.017844,
-.084783,.033069,
-.077753,.047289,
-.07103,.05689,
-.07601,.06186,
-.085597,.047721,
-.092583,.032132,
-.096757,.015567,
-.09799,-.001471,
-.096246,-.018464,
-.091577,-.034897,
-.084126,-.050269,
-.07601,-.06186,
-.07103,-.05689,
270.*
4,1,18,-.05689,.07103,
-.043691,.07983,
-.029165,.086204,
-.013753,.089959,
.002077,.09098,
.017844,.089237,
.033069,.084783,
.047289,.077753,
.05689,.07103,
.06186,.07601,
.047721,.085597,
.032132,.092583,
.015567,.096757,
-.001471,.09799,
-.018464,.096246,
-.034897,.091577,
-.050269,.084126,
-.06186,.07601,
-.05689,.07103,
270.*
%
%ADD56MACRO56*%
%AMMACRO48*
4,1,16,.02657,.01597,
.02894,.011114,
.03043,.005919,
.030995,.000545,
.030619,-.004845,
.029313,-.010088,
.027115,-.015025,
.02657,-.01597,
.03164,-.02104,
.034813,-.015226,
.036928,-.00895,
.037921,-.002401,
.037762,.00422,
.036455,.010713,
.034041,.016881,
.03164,.02104,
.02657,.01597,
180.*
4,1,16,.01597,-.02657,
.011114,-.02894,
.005919,-.03043,
.000545,-.030995,
-.004845,-.030619,
-.010088,-.029313,
-.015025,-.027115,
-.01597,-.02657,
-.02104,-.03164,
-.015226,-.034813,
-.00895,-.036928,
-.002401,-.037921,
.00422,-.037762,
.010713,-.036455,
.016881,-.034041,
.02104,-.03164,
.01597,-.02657,
180.*
4,1,16,-.02657,-.01597,
-.02894,-.011114,
-.03043,-.005919,
-.030995,-.000545,
-.030619,.004845,
-.029313,.010088,
-.027115,.015025,
-.02657,.01597,
-.03164,.02104,
-.034813,.015226,
-.036928,.00895,
-.037921,.002401,
-.037762,-.00422,
-.036455,-.010713,
-.034041,-.016881,
-.03164,-.02104,
-.02657,-.01597,
180.*
4,1,16,-.01597,.02657,
-.011114,.02894,
-.005919,.03043,
-.000545,.030995,
.004845,.030619,
.010088,.029313,
.015025,.027115,
.01597,.02657,
.02104,.03164,
.015226,.034813,
.00895,.036928,
.002401,.037921,
-.00422,.037762,
-.010713,.036455,
-.016881,.034041,
-.02104,.03164,
-.01597,.02657,
180.*
%
%ADD48MACRO48*%
%AMMACRO57*
4,1,15,.04124,.02356,
.044705,.016041,
.046811,.008034,
.047495,-.000216,
.046736,-.008461,
.044557,-.016448,
.04124,-.02356,
.04635,-.02867,
.050624,-.020186,
.05336,-.011088,
.054475,-.001654,
.053935,.007831,
.051756,.017077,
.048004,.025805,
.04635,.02867,
.04124,.02356,
0.0*
4,1,15,.02356,-.04124,
.016041,-.044705,
.008034,-.046811,
-.000216,-.047495,
-.008461,-.046736,
-.016448,-.044557,
-.02356,-.04124,
-.02867,-.04635,
-.020186,-.050624,
-.011088,-.05336,
-.001654,-.054475,
.007831,-.053935,
.017077,-.051756,
.025805,-.048004,
.02867,-.04635,
.02356,-.04124,
0.0*
4,1,15,-.04124,-.02356,
-.044705,-.016041,
-.046811,-.008034,
-.047495,.000216,
-.046736,.008461,
-.044557,.016448,
-.04124,.02356,
-.04635,.02867,
-.050624,.020186,
-.05336,.011088,
-.054475,.001654,
-.053935,-.007831,
-.051756,-.017077,
-.048004,-.025805,
-.04635,-.02867,
-.04124,-.02356,
0.0*
4,1,15,-.02356,.04124,
-.016041,.044705,
-.008034,.046811,
.000216,.047495,
.008461,.046736,
.016448,.044557,
.02356,.04124,
.02867,.04635,
.020186,.050624,
.011088,.05336,
.001654,.054475,
-.007831,.053935,
-.017077,.051756,
-.025805,.048004,
-.02867,.04635,
-.02356,.04124,
0.0*
%
%ADD57MACRO57*%
%AMMACRO77*
4,1,15,.03682,.01914,
.039584,.012455,
.041146,.005393,
.041457,-.001834,
.040509,-.009005,
.03833,-.015903,
.03682,-.01914,
.04197,-.0243,
.045552,-.016643,
.04775,-.00848,
.048497,-.000059,
.047771,.008363,
.045593,.016531,
.042029,.024197,
.04197,.0243,
.03682,.01914,
180.*
4,1,15,.01914,-.03682,
.012455,-.039584,
.005393,-.041146,
-.001834,-.041457,
-.009005,-.040509,
-.015903,-.03833,
-.01914,-.03682,
-.0243,-.04197,
-.016643,-.045552,
-.00848,-.04775,
-.000059,-.048497,
.008363,-.047771,
.016531,-.045593,
.024197,-.042029,
.0243,-.04197,
.01914,-.03682,
180.*
4,1,15,-.03682,-.01914,
-.039584,-.012455,
-.041146,-.005393,
-.041457,.001834,
-.040509,.009005,
-.03833,.015903,
-.03682,.01914,
-.04197,.0243,
-.045552,.016643,
-.04775,.00848,
-.048497,.000059,
-.047771,-.008363,
-.045593,-.016531,
-.042029,-.024197,
-.04197,-.0243,
-.03682,-.01914,
180.*
4,1,15,-.01914,.03682,
-.012455,.039584,
-.005393,.041146,
.001834,.041457,
.009005,.040509,
.015903,.03833,
.01914,.03682,
.0243,.04197,
.016643,.045552,
.00848,.04775,
.000059,.048497,
-.008363,.047771,
-.016531,.045593,
-.024197,.042029,
-.0243,.04197,
-.01914,.03682,
180.*
%
%ADD77MACRO77*%
%AMMACRO75*
4,1,15,-.03682,.01914,
-.039584,.012455,
-.041146,.005393,
-.041457,-.001834,
-.040509,-.009005,
-.03833,-.015903,
-.03682,-.01914,
-.04197,-.0243,
-.045552,-.016643,
-.04775,-.00848,
-.048497,-.000059,
-.047771,.008363,
-.045593,.016531,
-.042029,.024197,
-.04197,.0243,
-.03682,.01914,
180.*
4,1,15,-.01914,-.03682,
-.012455,-.039584,
-.005393,-.041146,
.001834,-.041457,
.009005,-.040509,
.015903,-.03833,
.01914,-.03682,
.0243,-.04197,
.016643,-.045552,
.00848,-.04775,
.000059,-.048497,
-.008363,-.047771,
-.016531,-.045593,
-.024197,-.042029,
-.0243,-.04197,
-.01914,-.03682,
180.*
4,1,15,.03682,-.01914,
.039584,-.012455,
.041146,-.005393,
.041457,.001834,
.040509,.009005,
.03833,.015903,
.03682,.01914,
.04197,.0243,
.045552,.016643,
.04775,.00848,
.048497,.000059,
.047771,-.008363,
.045593,-.016531,
.042029,-.024197,
.04197,-.0243,
.03682,-.01914,
180.*
4,1,15,.01914,.03682,
.012455,.039584,
.005393,.041146,
-.001834,.041457,
-.009005,.040509,
-.015903,.03833,
-.01914,.03682,
-.0243,.04197,
-.016643,.045552,
-.00848,.04775,
-.000059,.048497,
.008363,.047771,
.016531,.045593,
.024197,.042029,
.0243,.04197,
.01914,.03682,
180.*
%
%ADD75MACRO75*%
%ADD82C,.006*%
%ADD92C,.07005*%
%ADD99C,.07006*%
%ADD108C,.0761*%
%ADD86C,.07306*%
%ADD93C,.07608*%
%ADD96C,.07808*%
%ADD97C,.09708*%
%ADD104C,.311*%
%ADD107O,.03004X.07004*%
%ADD98C,.11006*%
%ADD103O,.03004X.06404*%
%ADD109C,.31502*%
%ADD102O,.03006X.06406*%
%ADD106O,.03004X.06904*%
%ADD90C,.16206*%
%ADD94C,.43406*%
%ADD84O,.03404X.06804*%
%ADD83C,.16506*%
%ADD105O,.03006X.06906*%
%ADD101O,.2363X.2993*%
%ADD95C,.25806*%
%ADD85O,.03406X.06806*%
%ADD89C,.19806*%
%ADD88C,.19807*%
%ADD87C,.19809*%
%ADD91C,.19786*%
%ADD100O,.43374X.77626*%
G75*
%LPD*%
G75*
G36*
G01X-476840Y-884638D02*
X5911000D01*
Y2768362D01*
X-476840D01*
Y-884638D01*
G37*
%LPC*%
G75*
G36*
G01X1007087Y132327D02*
G02X1009020Y130394I0J-1933D01*
G01Y46378D01*
G03X1018898Y36500I9878J0D01*
G01X1510244D01*
G02X1516114Y30630I0J-5870D01*
G01Y-1575D01*
G03X1525992Y-11453I9878J0D01*
G01X1796071D01*
G03X1805949Y-1575I0J9878D01*
G01Y30630D01*
G02X1811819Y36500I5870J0D01*
G01X1849606D01*
G02X1855476Y30630I0J-5870D01*
G01Y-40945D01*
G02X1849606Y-46815I-5870J0D01*
G01X7874D01*
G02X2004Y-40945I0J5870D01*
G01Y30630D01*
G02X7874Y36500I5870J0D01*
G01X35835D01*
G02X41705Y30630I0J-5870D01*
G01Y-1575D01*
G03X51583Y-11453I9878J0D01*
G01X321661D01*
G03X331539Y-1575I0J9878D01*
G01Y30630D01*
G02X337409Y36500I5870J0D01*
G01X480717D01*
G02X486587Y30630I0J-5870D01*
G01Y19212D01*
G03X496465Y9334I9878J0D01*
G01X766543D01*
G03X776421Y19212I0J9878D01*
G01Y30630D01*
G02X782291Y36500I5870J0D01*
G01X879134D01*
G03X889012Y46378I0J9878D01*
G01Y130394D01*
G02X890945Y132327I1933J0D01*
G01X1007087D01*
G37*
G36*
G01X1855476Y54252D02*
G02X1849606Y48382I-5870J0D01*
G01X1803945D01*
G03X1794067Y38504I0J-9878D01*
G01Y2204D01*
G02X1793867Y2004I-200J0D01*
G01X1528196D01*
G02X1527996Y2204I0J200D01*
G01Y38504D01*
G03X1518118Y48382I-9878J0D01*
G01X1026772D01*
G02X1020902Y54252I0J5870D01*
G01Y134331D01*
G03X1011024Y144209I-9878J0D01*
G01X887008D01*
G03X877130Y134331I0J-9878D01*
G01Y54252D01*
G02X871260Y48382I-5870J0D01*
G01X774417D01*
G03X764539Y38504I0J-9878D01*
G01Y22991D01*
G02X764339Y22791I-200J0D01*
G01X498669D01*
G02X498469Y22991I0J200D01*
G01Y38504D01*
G03X488591Y48382I-9878J0D01*
G01X329535D01*
G03X319657Y38504I0J-9878D01*
G01Y2204D01*
G02X319457Y2004I-200J0D01*
G01X53787D01*
G02X53587Y2204I0J200D01*
G01Y38504D01*
G03X43709Y48382I-9878J0D01*
G01X7874D01*
G02X2004Y54252I0J5870D01*
G01Y305795D01*
G02X3723Y309944I5869J-1D01*
G01X6985Y313206D01*
G03X9878Y320190I-6985J6985D01*
G01Y1588078D01*
G02X11597Y1592228I5870J-1D01*
G01X24701Y1605332D01*
G03X27595Y1612317I-6985J6986D01*
G01Y1732244D01*
G02X33465Y1738114I5870J0D01*
G01X765532D01*
G02X765732Y1737914I0J-200D01*
G01Y1736890D01*
G03X769705Y1732917I3973J0D01*
G01X1087854D01*
G03X1091827Y1736890I0J3973D01*
G01Y1737914D01*
G02X1092027Y1738114I200J0D01*
G01X1824016D01*
G02X1829886Y1732244I0J-5870D01*
G01Y1612316D01*
G03X1832779Y1605332I9878J1D01*
G01X1839978Y1598133D01*
G02X1841697Y1593984I-4150J-4150D01*
G01Y326095D01*
G03X1844590Y319111I9878J1D01*
G01X1853757Y309944D01*
G02X1855476Y305795I-4150J-4150D01*
G01Y54252D01*
G37*
G36*
G01X1873228Y1820942D02*
X2093700D01*
G02X2099570Y1815072I0J-5870D01*
G01Y1791450D01*
G02X2093700Y1785580I-5870J0D01*
G01X2031574D01*
G03X2021696Y1775702I0J-9878D01*
G01Y1229954D01*
G03X2031574Y1220076I9878J0D01*
G01X2093700D01*
G02X2099570Y1214206I0J-5870D01*
G01Y-40945D01*
G02X2093700Y-46815I-5870J0D01*
G01X1873228D01*
G02X1867358Y-40945I0J5870D01*
G01Y305795D01*
G03X1862159Y318346I-17750J0D01*
G01X1855299Y325206D01*
G02X1853579Y329357I4150J4151D01*
G01Y1593984D01*
G03X1848380Y1606535I-17750J0D01*
G01X1843487Y1611428D01*
G02X1841768Y1615578I4151J4150D01*
G01Y1732244D01*
G02X1847638Y1738114I5870J0D01*
G01X1857480D01*
G03X1867358Y1747992I0J9878D01*
G01Y1815072D01*
G02X1873228Y1820942I5870J0D01*
G37*
%LPD*%
G75*
G36*
G01X741579Y1609865D02*
G02X742998Y1610166I1421J-3202D01*
G02X744417Y1609865I-2J-3503D01*
G03X744579I81J183D01*
G02X745998Y1610166I1421J-3202D01*
G02X749500Y1606663I-1J-3503D01*
G01Y1606661D01*
G02X749200Y1605244I-3502J1D01*
G03Y1605082I183J-81D01*
G02X749500Y1603663I-3202J-1418D01*
G02X749157Y1602149I-3502J-2D01*
G03Y1601977I180J-86D01*
G02X749500Y1600463I-3159J-1512D01*
G02X749200Y1599044I-3502J-1D01*
G03Y1598882I183J-81D01*
G02X749500Y1597463I-3202J-1418D01*
G02X749200Y1596044I-3502J-1D01*
G03Y1595882I183J-81D01*
G02X749500Y1594463I-3202J-1418D01*
G02X745998Y1590960I-3502J-1D01*
G02X744579Y1591261I2J3503D01*
G03X744417I-81J-183D01*
G02X742998Y1590960I-1421J3202D01*
G02X741579Y1591261I2J3503D01*
G03X741417I-81J-183D01*
G02X740970Y1591098I-1421J3201D01*
G01X740913Y1591082D01*
X740837Y1590996D01*
X740770Y1590580D01*
G03X740855Y1590383I198J-32D01*
G02X742382Y1587491I-1975J-2892D01*
G02X741459Y1585121I-3504J0D01*
G03X741406Y1584986I147J-136D01*
G01Y1584866D01*
G03X741459Y1584731I200J1D01*
G02Y1579991I-2580J-2370D01*
G03X741406Y1579856I147J-136D01*
G01Y1579736D01*
G03X741459Y1579601I200J1D01*
G02X742382Y1577231I-2581J-2370D01*
G01Y1577229D01*
G02X738880Y1573728I-3502J1D01*
G02X736412Y1574746I1J3503D01*
G01X736411Y1574747D01*
G03X736271Y1574804I-140J-143D01*
G01X735989D01*
G03X735849Y1574747I0J-200D01*
G01X735848Y1574746D01*
G02X733380Y1573728I-2469J2485D01*
G02X730867Y1574791I0J3502D01*
G03X730723Y1574852I-144J-139D01*
G01X730437D01*
G03X730293Y1574791I0J-200D01*
G02X727780Y1573728I-2513J2439D01*
G02X724278Y1577231I1J3503D01*
G02X725201Y1579601I3504J0D01*
G03X725254Y1579736I-147J136D01*
G01Y1579856D01*
G03X725201Y1579991I-200J-1D01*
G02Y1584731I2580J2370D01*
G03X725254Y1584866I-147J136D01*
G01Y1584986D01*
G03X725201Y1585121I-200J-1D01*
G02X724278Y1587491I2581J2370D01*
G01Y1587493D01*
G02X727780Y1590994I3502J-1D01*
G02X730293Y1589931I0J-3502D01*
G03X730437Y1589870I144J139D01*
G01X730723D01*
G03X730867Y1589931I0J200D01*
G02X731217Y1590246I2513J-2440D01*
G03X731283Y1590468I-123J157D01*
G01X731161Y1590826D01*
G03X730973Y1590961I-189J-65D01*
G02X727496Y1594463I25J3502D01*
G01Y1594465D01*
G02X727796Y1595882I3502J-1D01*
G03Y1596044I-183J81D01*
G02X727496Y1597463I3202J1418D01*
G02X727796Y1598882I3502J1D01*
G03Y1599044I-183J81D01*
G02X727496Y1600463I3202J1418D01*
G02X727839Y1601977I3502J2D01*
G03Y1602149I-180J86D01*
G02X727496Y1603663I3159J1512D01*
G02X727796Y1605082I3502J1D01*
G03Y1605244I-183J81D01*
G02X727496Y1606663I3202J1418D01*
G02X730998Y1610166I3502J1D01*
G02X732417Y1609865I-2J-3503D01*
G03X732579I81J183D01*
G02X733998Y1610166I1421J-3202D01*
G02X735417Y1609865I-2J-3503D01*
G03X735579I81J183D01*
G02X736998Y1610166I1421J-3202D01*
G02X738417Y1609865I-2J-3503D01*
G03X738579I81J183D01*
G02X739998Y1610166I1421J-3202D01*
G02X741417Y1609865I-2J-3503D01*
G03X741579I81J183D01*
G37*
G36*
G01X916131Y1609735D02*
G02X917550Y1610036I1421J-3202D01*
G02X918969Y1609735I-2J-3503D01*
G03X919131I81J183D01*
G02X920550Y1610036I1421J-3202D01*
G02X924052Y1606533I-1J-3503D01*
G01Y1606531D01*
G02X923752Y1605114I-3502J1D01*
G03Y1604952I183J-81D01*
G02X924052Y1603535I-3202J-1418D01*
G01Y1603533D01*
G02X921161Y1600084I-3503J0D01*
G03X920999Y1599922I35J-197D01*
G02X920752Y1599114I-3449J612D01*
G03Y1598952I183J-81D01*
G02X921052Y1597533I-3202J-1418D01*
G02X920752Y1596114I-3502J-1D01*
G03Y1595952I183J-81D01*
G02X921052Y1594533I-3202J-1418D01*
G02X918832Y1591273I-3503J-1D01*
G01X918777Y1591252D01*
X918709Y1591159D01*
X918681Y1590740D01*
G03X918783Y1590552I200J-13D01*
G02X920580Y1587493I-1705J-3059D01*
G02X919656Y1585123I-3503J1D01*
G03X919603Y1584988I147J-136D01*
G01Y1584868D01*
G03X919656Y1584733I200J1D01*
G02X920580Y1582363I-2579J-2371D01*
G02X919656Y1579993I-3503J1D01*
G03X919603Y1579858I147J-136D01*
G01Y1579738D01*
G03X919656Y1579603I200J1D01*
G02X920580Y1577233I-2579J-2371D01*
G02X917077Y1573730I-3503J0D01*
G02X914609Y1574748I1J3503D01*
G01X914608Y1574749D01*
G03X914468Y1574806I-140J-143D01*
G01X914186D01*
G03X914046Y1574749I0J-200D01*
G01X914045Y1574748D01*
G02X911577Y1573730I-2469J2485D01*
G02X909064Y1574793I0J3502D01*
G03X908920Y1574854I-144J-139D01*
G01X908634D01*
G03X908490Y1574793I0J-200D01*
G02X905977Y1573730I-2513J2439D01*
G02X902474Y1577233I0J3503D01*
G02X903398Y1579603I3503J-1D01*
G03X903451Y1579738I-147J136D01*
G01Y1579858D01*
G03X903398Y1579993I-200J-1D01*
G02X902474Y1582363I2579J2371D01*
G02X903398Y1584733I3503J-1D01*
G03X903451Y1584868I-147J136D01*
G01Y1584988D01*
G03X903398Y1585123I-200J-1D01*
G02X902474Y1587493I2579J2371D01*
G02X904288Y1590561I3503J-1D01*
G03X904391Y1590748I-97J175D01*
G01X904370Y1591109D01*
G03X904244Y1591283I-200J-12D01*
G02X902048Y1594533I1307J3250D01*
G01Y1594535D01*
G02X902348Y1595952I3502J-1D01*
G03Y1596114I-183J81D01*
G02X902048Y1597533I3202J1418D01*
G02X902348Y1598952I3502J1D01*
G03Y1599114I-183J81D01*
G02X902101Y1599922I3202J1420D01*
G03X901939Y1600084I-197J-35D01*
G02X899101Y1602922I611J3449D01*
G03X898939Y1603084I-197J-35D01*
G02X896048Y1606533I612J3449D01*
G01Y1606535D01*
G02X899550Y1610036I3502J-1D01*
G02X900969Y1609735I-2J-3503D01*
G03X901131I81J183D01*
G02X902550Y1610036I1421J-3202D01*
G02X903969Y1609735I-2J-3503D01*
G03X904131I81J183D01*
G02X905550Y1610036I1421J-3202D01*
G02X906969Y1609735I-2J-3503D01*
G03X907131I81J183D01*
G02X908550Y1610036I1421J-3202D01*
G02X909969Y1609735I-2J-3503D01*
G03X910131I81J183D01*
G02X911550Y1610036I1421J-3202D01*
G02X912969Y1609735I-2J-3503D01*
G03X913131I81J183D01*
G02X914550Y1610036I1421J-3202D01*
G02X915969Y1609735I-2J-3503D01*
G03X916131I81J183D01*
G37*
G36*
G01X874131D02*
G02X875550Y1610036I1421J-3202D01*
G02X876969Y1609735I-2J-3503D01*
G03X877131I81J183D01*
G02X878550Y1610036I1421J-3202D01*
G02X882052Y1606533I-1J-3503D01*
G01Y1606531D01*
G02X881752Y1605114I-3502J1D01*
G03Y1604952I183J-81D01*
G02X882052Y1603535I-3202J-1418D01*
G01Y1603533D01*
G02X879161Y1600084I-3503J0D01*
G03X878999Y1599922I35J-197D01*
G02X878752Y1599114I-3449J612D01*
G03Y1598952I183J-81D01*
G02X879052Y1597533I-3202J-1418D01*
G02X878752Y1596114I-3502J-1D01*
G03Y1595952I183J-81D01*
G02X879052Y1594533I-3202J-1418D01*
G02X876832Y1591273I-3503J-1D01*
G01X876777Y1591252D01*
X876709Y1591159D01*
X876681Y1590740D01*
G03X876783Y1590552I200J-13D01*
G02X878580Y1587493I-1705J-3059D01*
G02X877656Y1585123I-3503J1D01*
G03X877603Y1584988I147J-136D01*
G01Y1584868D01*
G03X877656Y1584733I200J1D01*
G02X878580Y1582363I-2579J-2371D01*
G02X877656Y1579993I-3503J1D01*
G03X877603Y1579858I147J-136D01*
G01Y1579738D01*
G03X877656Y1579603I200J1D01*
G02X878580Y1577233I-2579J-2371D01*
G02X875077Y1573730I-3503J0D01*
G02X872609Y1574748I1J3503D01*
G01X872608Y1574749D01*
G03X872468Y1574806I-140J-143D01*
G01X872186D01*
G03X872046Y1574749I0J-200D01*
G01X872045Y1574748D01*
G02X869577Y1573730I-2469J2485D01*
G02X867064Y1574793I0J3502D01*
G03X866920Y1574854I-144J-139D01*
G01X866634D01*
G03X866490Y1574793I0J-200D01*
G02X863977Y1573730I-2513J2439D01*
G02X860474Y1577233I0J3503D01*
G02X861398Y1579603I3503J-1D01*
G03X861451Y1579738I-147J136D01*
G01Y1579858D01*
G03X861398Y1579993I-200J-1D01*
G02X860474Y1582363I2579J2371D01*
G02X861398Y1584733I3503J-1D01*
G03X861451Y1584868I-147J136D01*
G01Y1584988D01*
G03X861398Y1585123I-200J-1D01*
G02X860474Y1587493I2579J2371D01*
G02X862288Y1590561I3503J-1D01*
G03X862391Y1590748I-97J175D01*
G01X862370Y1591109D01*
G03X862244Y1591283I-200J-12D01*
G02X860048Y1594533I1307J3250D01*
G01Y1594535D01*
G02X860348Y1595952I3502J-1D01*
G03Y1596114I-183J81D01*
G02X860048Y1597533I3202J1418D01*
G02X860348Y1598952I3502J1D01*
G03Y1599114I-183J81D01*
G02X860101Y1599922I3202J1420D01*
G03X859939Y1600084I-197J-35D01*
G02X857101Y1602922I611J3449D01*
G03X856939Y1603084I-197J-35D01*
G02X854048Y1606533I612J3449D01*
G01Y1606535D01*
G02X857550Y1610036I3502J-1D01*
G02X858969Y1609735I-2J-3503D01*
G03X859131I81J183D01*
G02X860550Y1610036I1421J-3202D01*
G02X861969Y1609735I-2J-3503D01*
G03X862131I81J183D01*
G02X863550Y1610036I1421J-3202D01*
G02X864969Y1609735I-2J-3503D01*
G03X865131I81J183D01*
G02X866550Y1610036I1421J-3202D01*
G02X867969Y1609735I-2J-3503D01*
G03X868131I81J183D01*
G02X869550Y1610036I1421J-3202D01*
G02X870969Y1609735I-2J-3503D01*
G03X871131I81J183D01*
G02X872550Y1610036I1421J-3202D01*
G02X873969Y1609735I-2J-3503D01*
G03X874131I81J183D01*
G37*
G36*
G01X832131D02*
G02X833550Y1610036I1421J-3202D01*
G02X834969Y1609735I-2J-3503D01*
G03X835131I81J183D01*
G02X836550Y1610036I1421J-3202D01*
G02X840052Y1606533I-1J-3503D01*
G01Y1606531D01*
G02X839752Y1605114I-3502J1D01*
G03Y1604952I183J-81D01*
G02X840052Y1603535I-3202J-1418D01*
G01Y1603533D01*
G02X837161Y1600084I-3503J0D01*
G03X836999Y1599922I35J-197D01*
G02X836752Y1599114I-3449J612D01*
G03Y1598952I183J-81D01*
G02X837052Y1597533I-3202J-1418D01*
G02X836752Y1596114I-3502J-1D01*
G03Y1595952I183J-81D01*
G02X837052Y1594533I-3202J-1418D01*
G02X834832Y1591273I-3503J-1D01*
G01X834777Y1591252D01*
X834709Y1591159D01*
X834681Y1590740D01*
G03X834783Y1590552I200J-13D01*
G02X836580Y1587493I-1705J-3059D01*
G02X835656Y1585123I-3503J1D01*
G03X835603Y1584988I147J-136D01*
G01Y1584868D01*
G03X835656Y1584733I200J1D01*
G02X836580Y1582363I-2579J-2371D01*
G02X835656Y1579993I-3503J1D01*
G03X835603Y1579858I147J-136D01*
G01Y1579738D01*
G03X835656Y1579603I200J1D01*
G02X836580Y1577233I-2579J-2371D01*
G02X833077Y1573730I-3503J0D01*
G02X830609Y1574748I1J3503D01*
G01X830608Y1574749D01*
G03X830468Y1574806I-140J-143D01*
G01X830186D01*
G03X830046Y1574749I0J-200D01*
G01X830045Y1574748D01*
G02X827577Y1573730I-2469J2485D01*
G02X825064Y1574793I0J3502D01*
G03X824920Y1574854I-144J-139D01*
G01X824634D01*
G03X824490Y1574793I0J-200D01*
G02X821977Y1573730I-2513J2439D01*
G02X818474Y1577233I0J3503D01*
G02X819398Y1579603I3503J-1D01*
G03X819451Y1579738I-147J136D01*
G01Y1579858D01*
G03X819398Y1579993I-200J-1D01*
G02X818474Y1582363I2579J2371D01*
G02X819398Y1584733I3503J-1D01*
G03X819451Y1584868I-147J136D01*
G01Y1584988D01*
G03X819398Y1585123I-200J-1D01*
G02X818474Y1587493I2579J2371D01*
G02X820288Y1590561I3503J-1D01*
G03X820391Y1590748I-97J175D01*
G01X820370Y1591109D01*
G03X820244Y1591283I-200J-12D01*
G02X818048Y1594533I1307J3250D01*
G01Y1594535D01*
G02X818348Y1595952I3502J-1D01*
G03Y1596114I-183J81D01*
G02X818048Y1597533I3202J1418D01*
G02X818348Y1598952I3502J1D01*
G03Y1599114I-183J81D01*
G02X818101Y1599922I3202J1420D01*
G03X817939Y1600084I-197J-35D01*
G02X815101Y1602922I611J3449D01*
G03X814939Y1603084I-197J-35D01*
G02X812048Y1606533I612J3449D01*
G01Y1606535D01*
G02X815550Y1610036I3502J-1D01*
G02X816969Y1609735I-2J-3503D01*
G03X817131I81J183D01*
G02X818550Y1610036I1421J-3202D01*
G02X819969Y1609735I-2J-3503D01*
G03X820131I81J183D01*
G02X821550Y1610036I1421J-3202D01*
G02X822969Y1609735I-2J-3503D01*
G03X823131I81J183D01*
G02X824550Y1610036I1421J-3202D01*
G02X825969Y1609735I-2J-3503D01*
G03X826131I81J183D01*
G02X827550Y1610036I1421J-3202D01*
G02X828969Y1609735I-2J-3503D01*
G03X829131I81J183D01*
G02X830550Y1610036I1421J-3202D01*
G02X831969Y1609735I-2J-3503D01*
G03X832131I81J183D01*
G37*
G36*
G01X787131D02*
G02X788550Y1610036I1421J-3202D01*
G02X789969Y1609735I-2J-3503D01*
G03X790131I81J183D01*
G02X791550Y1610036I1421J-3202D01*
G02X795052Y1606533I-1J-3503D01*
G01Y1606531D01*
G02X794752Y1605114I-3502J1D01*
G03Y1604952I183J-81D01*
G02X795052Y1603533I-3202J-1418D01*
G02X794752Y1602114I-3502J-1D01*
G03Y1601952I183J-81D01*
G02X795052Y1600533I-3202J-1418D01*
G02X794752Y1599114I-3502J-1D01*
G03Y1598952I183J-81D01*
G02X795052Y1597533I-3202J-1418D01*
G02X794752Y1596114I-3502J-1D01*
G03Y1595952I183J-81D01*
G02X795052Y1594533I-3202J-1418D01*
G02X792832Y1591273I-3503J-1D01*
G01X792777Y1591252D01*
X792709Y1591159D01*
X792681Y1590740D01*
G03X792783Y1590552I200J-13D01*
G02X794580Y1587493I-1705J-3059D01*
G02X793656Y1585123I-3503J1D01*
G03X793603Y1584988I147J-136D01*
G01Y1584868D01*
G03X793656Y1584733I200J1D01*
G02X794580Y1582363I-2579J-2371D01*
G02X793656Y1579993I-3503J1D01*
G03X793603Y1579858I147J-136D01*
G01Y1579738D01*
G03X793656Y1579603I200J1D01*
G02X794580Y1577233I-2579J-2371D01*
G02X791077Y1573730I-3503J0D01*
G02X788609Y1574748I1J3503D01*
G01X788608Y1574749D01*
G03X788468Y1574806I-140J-143D01*
G01X788186D01*
G03X788046Y1574749I0J-200D01*
G01X788045Y1574748D01*
G02X785577Y1573730I-2469J2485D01*
G02X783064Y1574793I0J3502D01*
G03X782920Y1574854I-144J-139D01*
G01X782634D01*
G03X782490Y1574793I0J-200D01*
G02X779977Y1573730I-2513J2439D01*
G02X776474Y1577233I0J3503D01*
G02X777398Y1579603I3503J-1D01*
G03X777451Y1579738I-147J136D01*
G01Y1579858D01*
G03X777398Y1579993I-200J-1D01*
G02X776474Y1582363I2579J2371D01*
G02X777398Y1584733I3503J-1D01*
G03X777451Y1584868I-147J136D01*
G01Y1584988D01*
G03X777398Y1585123I-200J-1D01*
G02X776474Y1587493I2579J2371D01*
G02X778288Y1590561I3503J-1D01*
G03X778391Y1590748I-97J175D01*
G01X778370Y1591109D01*
G03X778244Y1591283I-200J-12D01*
G02X778131Y1591331I1313J3247D01*
G03X777969I-81J-183D01*
G02X776550Y1591030I-1421J3202D01*
G02X773048Y1594533I1J3503D01*
G01Y1594535D01*
G02X773348Y1595952I3502J-1D01*
G03Y1596114I-183J81D01*
G02X773048Y1597533I3202J1418D01*
G02X773348Y1598952I3502J1D01*
G03Y1599114I-183J81D01*
G02X773048Y1600533I3202J1418D01*
G02X773348Y1601952I3502J1D01*
G03Y1602114I-183J81D01*
G02X773048Y1603533I3202J1418D01*
G02X773348Y1604952I3502J1D01*
G03Y1605114I-183J81D01*
G02X773048Y1606533I3202J1418D01*
G02X776550Y1610036I3502J1D01*
G02X777969Y1609735I-2J-3503D01*
G03X778131I81J183D01*
G02X779550Y1610036I1421J-3202D01*
G02X780969Y1609735I-2J-3503D01*
G03X781131I81J183D01*
G02X782550Y1610036I1421J-3202D01*
G02X783969Y1609735I-2J-3503D01*
G03X784131I81J183D01*
G02X785550Y1610036I1421J-3202D01*
G02X786969Y1609735I-2J-3503D01*
G03X787131I81J183D01*
G37*
G36*
G01X1028439Y1536432D02*
X1028441D01*
G02X1029859Y1536132I0J-3502D01*
G03X1030021I81J183D01*
G02X1031438Y1536432I1418J-3202D01*
G01X1031440D01*
G02X1034942Y1532930I0J-3502D01*
G01Y1532928D01*
G02X1033668Y1530227I-3502J1D01*
G01X1033622Y1530190D01*
X1033586Y1530079D01*
X1033692Y1529672D01*
G03X1033850Y1529525I194J50D01*
G02X1036720Y1526080I-633J-3445D01*
G01Y1526078D01*
G02X1036420Y1524661I-3502J1D01*
G03Y1524499I183J-81D01*
G02X1036720Y1523080I-3202J-1418D01*
G02X1036420Y1521661I-3502J-1D01*
G03Y1521499I183J-81D01*
G02X1036720Y1520082I-3202J-1418D01*
G01Y1520080D01*
G02X1029716I-3502J0D01*
G01Y1520082D01*
G02X1030016Y1521499I3502J-1D01*
G03Y1521661I-183J81D01*
G02X1029716Y1523080I3202J1418D01*
G02X1030016Y1524499I3502J1D01*
G03Y1524661I-183J81D01*
G02X1029716Y1526080I3202J1418D01*
G02X1030990Y1528783I3502J1D01*
G01X1031036Y1528820D01*
X1031072Y1528931D01*
X1030966Y1529338D01*
G03X1030808Y1529485I-194J-50D01*
G02X1030021Y1529728I633J3445D01*
G03X1029859I-81J-183D01*
G02X1028441Y1529428I-1418J3202D01*
G01X1028439D01*
G02X1027021Y1529728I0J3502D01*
G03X1026859I-81J-183D01*
G02X1025441Y1529428I-1418J3202D01*
G01X1025439D01*
G02X1024021Y1529728I0J3502D01*
G03X1023859I-81J-183D01*
G02X1022441Y1529428I-1418J3202D01*
G01X1022439D01*
G02X1021021Y1529728I0J3502D01*
G03X1020859I-81J-183D01*
G02X1019442Y1529428I-1418J3202D01*
G01X1019440D01*
G02Y1536432I0J3502D01*
G01X1019442D01*
G02X1020859Y1536132I-1J-3502D01*
G03X1021021I81J183D01*
G02X1022439Y1536432I1418J-3202D01*
G01X1022441D01*
G02X1023859Y1536132I0J-3502D01*
G03X1024021I81J183D01*
G02X1025439Y1536432I1418J-3202D01*
G01X1025441D01*
G02X1026859Y1536132I0J-3502D01*
G03X1027021I81J183D01*
G02X1028439Y1536432I1418J-3202D01*
G37*
G36*
G01X1729836Y56026D02*
G02X1731332Y54658I0J-1502D01*
G03X1731443Y54496I199J18D01*
G02X1733398Y51354I-1547J-3142D01*
G02X1733316Y50602I-3503J1D01*
G03X1733334Y50465I195J-44D01*
G02X1733744Y48822I-3093J-1644D01*
G02X1733586Y47785I-3503J3D01*
G01X1733567Y47725D01*
X1733604Y47607D01*
X1733950Y47338D01*
G03X1734177Y47325I123J158D01*
G02X1736004Y47840I1828J-2987D01*
G01X1736006D01*
G02X1739508Y44338I0J-3502D01*
G01Y44335D01*
G02X1739303Y43155I-3502J1D01*
G03Y43021I188J-67D01*
G02X1739508Y41841I-3297J-1181D01*
G01Y41838D01*
G02X1732504I-3502J0D01*
G01Y41841D01*
G02X1732709Y43021I3502J-1D01*
G03Y43155I-188J67D01*
G02X1732504Y44335I3297J1181D01*
G01Y44338D01*
G02X1732661Y45375I3503J0D01*
G01X1732680Y45435D01*
X1732643Y45553D01*
X1732297Y45822D01*
G03X1732070Y45835I-123J-158D01*
G02X1730241Y45320I-1828J2987D01*
G02X1728585Y45735I-2J3502D01*
G03X1728397I-94J-176D01*
G02X1726741Y45320I-1654J3087D01*
G02X1725085Y45735I-2J3502D01*
G03X1724897I-94J-176D01*
G02X1723241Y45320I-1654J3087D01*
G02X1719738Y48822I-1J3502D01*
G02X1721117Y51607I3503J0D01*
G03X1721195Y51749I-121J159D01*
G02X1724685Y54956I3490J-295D01*
G02X1725575Y54842I4J-3502D01*
G03X1725722Y54860I51J193D01*
G01X1725828Y54918D01*
G03X1725920Y55026I-96J175D01*
G02X1727336Y56026I1416J-503D01*
G02X1728323Y55656I0J-1501D01*
G01X1728324D01*
Y55655D01*
G03X1728454Y55607I130J152D01*
G01X1728718D01*
G03X1728848Y55655I0J200D01*
G01X1728849Y55656D01*
G02X1729836Y56026I987J-1131D01*
G37*
G36*
G01X1421732Y1712135D02*
X1421691Y1712101D01*
X1421654Y1712004D01*
X1421716Y1711612D01*
G03X1421837Y1711458I198J31D01*
G02X1430690Y1698268I-5399J-13190D01*
G02X1402184I-14253J0D01*
G02X1402186Y1698468I14253J-43D01*
G01X1402185D01*
G02X1411037Y1711458I14252J-201D01*
G01X1411086Y1711478D01*
X1411150Y1711560D01*
X1411219Y1712004D01*
X1411182Y1712102D01*
X1411142Y1712135D01*
G02X1421732I5295J6330D01*
G37*
G36*
G01X446338D02*
X446297Y1712101D01*
X446260Y1712004D01*
X446322Y1711612D01*
G03X446443Y1711458I198J31D01*
G02X455296Y1698268I-5399J-13190D01*
G02X426790I-14253J0D01*
G02X435643Y1711458I14252J0D01*
G01X435692Y1711478D01*
X435756Y1711560D01*
X435826Y1712004D01*
X435789Y1712101D01*
X435748Y1712135D01*
G02X446338I5295J6330D01*
G37*
G36*
G01X408078Y1575148D02*
Y1575462D01*
G03X408001Y1575620I-200J0D01*
G02X407422Y1576805I923J1185D01*
G02X410428I1503J0D01*
G02X409849Y1575620I-1502J0D01*
G03X409772Y1575462I123J-158D01*
G01Y1575148D01*
G03X409849Y1574990I200J0D01*
G02X410428Y1573805I-923J-1185D01*
G02X407422I-1503J0D01*
G02X408001Y1574990I1502J0D01*
G03X408078Y1575148I-123J158D01*
G37*
G36*
G01X1060109Y1536352D02*
X1060111D01*
G02X1061529Y1536052I0J-3502D01*
G03X1061691I81J183D01*
G02X1063108Y1536352I1418J-3202D01*
G01X1063110D01*
G02Y1529348I0J-3502D01*
G01X1063108D01*
G02X1061691Y1529648I1J3502D01*
G03X1061529I-81J-183D01*
G02X1060111Y1529348I-1418J3202D01*
G01X1060109D01*
G02X1058691Y1529648I0J3502D01*
G03X1058529I-81J-183D01*
G02X1058372Y1529583I-1418J3203D01*
G03X1058244Y1529412I71J-187D01*
G01X1058236Y1529302D01*
G03X1058335Y1529114I199J-15D01*
G02X1060086Y1526080I-1753J-3034D01*
G01Y1526078D01*
G02X1059786Y1524661I-3502J1D01*
G03Y1524499I183J-81D01*
G02X1060086Y1523080I-3202J-1418D01*
G02X1059786Y1521661I-3502J-1D01*
G03Y1521499I183J-81D01*
G02X1060086Y1520082I-3202J-1418D01*
G01Y1520080D01*
G02X1053082I-3502J0D01*
G01Y1520082D01*
G02X1053382Y1521499I3502J-1D01*
G03Y1521661I-183J81D01*
G02X1053082Y1523080I3202J1418D01*
G02X1053382Y1524499I3502J1D01*
G03Y1524661I-183J81D01*
G02X1053082Y1526080I3202J1418D01*
G02X1054212Y1528657I3502J1D01*
G01X1054257Y1528698D01*
X1054285Y1528815D01*
X1054138Y1529220D01*
G03X1053959Y1529351I-188J-69D01*
G01X1053958D01*
G02X1052691Y1529648I152J3499D01*
G03X1052529I-81J-183D01*
G02X1051112Y1529348I-1418J3202D01*
G01X1051110D01*
G02Y1536352I0J3502D01*
G01X1051112D01*
G02X1052529Y1536052I-1J-3502D01*
G03X1052691I81J183D01*
G02X1054109Y1536352I1418J-3202D01*
G01X1054111D01*
G02X1055529Y1536052I0J-3502D01*
G03X1055691I81J183D01*
G02X1057109Y1536352I1418J-3202D01*
G01X1057111D01*
G02X1058529Y1536052I0J-3502D01*
G03X1058691I81J183D01*
G02X1060109Y1536352I1418J-3202D01*
G37*
G36*
G01X997279Y1536262D02*
X997281D01*
G02X998699Y1535962I0J-3502D01*
G03X998861I81J183D01*
G02X1000278Y1536262I1418J-3202D01*
G01X1000280D01*
G02Y1529258I0J-3502D01*
G01X1000278D01*
G02X998861Y1529558I1J3502D01*
G03X998699I-81J-183D01*
G02X997281Y1529258I-1418J3202D01*
G01X997279D01*
G02X995861Y1529558I0J3502D01*
G03X995699I-81J-183D01*
G02X994281Y1529258I-1418J3202D01*
G01X994279D01*
G02X992861Y1529558I0J3502D01*
G03X992699I-81J-183D01*
G02X991281Y1529258I-1418J3202D01*
G01X991279D01*
G02X989861Y1529558I0J3502D01*
G03X989699I-81J-183D01*
G02X989042Y1529341I-1422J3201D01*
G01X988987Y1529329D01*
X988907Y1529252D01*
X988786Y1528802D01*
X988817Y1528695D01*
X988858Y1528657D01*
G02X989988Y1526080I-2372J-2576D01*
G02X989688Y1524661I-3502J-1D01*
G03Y1524499I183J-81D01*
G02X989988Y1523080I-3202J-1418D01*
G02X989688Y1521661I-3502J-1D01*
G03Y1521499I183J-81D01*
G02X989988Y1520082I-3202J-1418D01*
G01Y1520080D01*
G02X982984I-3502J0D01*
G01Y1520082D01*
G02X983284Y1521499I3502J-1D01*
G03Y1521661I-183J81D01*
G02X982984Y1523080I3202J1418D01*
G02X983284Y1524499I3502J1D01*
G03Y1524661I-183J81D01*
G02X982984Y1526078I3202J1418D01*
G01Y1526080D01*
G02X985724Y1529499I3503J0D01*
G01X985779Y1529511D01*
X985859Y1529588D01*
X985980Y1530038D01*
X985949Y1530145D01*
X985908Y1530183D01*
G02X984778Y1532759I2372J2576D01*
G01Y1532760D01*
G02X988280Y1536262I3502J0D01*
G01X988282D01*
G02X989699Y1535962I-1J-3502D01*
G03X989861I81J183D01*
G02X991279Y1536262I1418J-3202D01*
G01X991281D01*
G02X992699Y1535962I0J-3502D01*
G03X992861I81J183D01*
G02X994279Y1536262I1418J-3202D01*
G01X994281D01*
G02X995699Y1535962I0J-3502D01*
G03X995861I81J183D01*
G02X997279Y1536262I1418J-3202D01*
G37*
G36*
G01X964349D02*
X964351D01*
G02X965769Y1535962I0J-3502D01*
G03X965931I81J183D01*
G02X967348Y1536262I1418J-3202D01*
G01X967350D01*
G02Y1529258I0J-3502D01*
G01X967348D01*
G02X965931Y1529558I1J3502D01*
G03X965769I-81J-183D01*
G02X965495Y1529450I-1420J3202D01*
G01X965444Y1529432D01*
X965374Y1529351D01*
X965300Y1528955D01*
G03X965369Y1528765I197J-36D01*
G02X966622Y1526080I-2250J-2685D01*
G01Y1526078D01*
G02X966322Y1524661I-3502J1D01*
G03Y1524499I183J-81D01*
G02X966622Y1523080I-3202J-1418D01*
G02X966322Y1521661I-3502J-1D01*
G03Y1521499I183J-81D01*
G02X966622Y1520082I-3202J-1418D01*
G01Y1520080D01*
G02X959618I-3502J0D01*
G01Y1520082D01*
G02X959918Y1521499I3502J-1D01*
G03Y1521661I-183J81D01*
G02X959618Y1523080I3202J1418D01*
G02X959918Y1524499I3502J1D01*
G03Y1524661I-183J81D01*
G02X959618Y1526080I3202J1418D01*
G02X960752Y1528661I3502J1D01*
G01X960793Y1528698D01*
X960824Y1528805D01*
X960704Y1529256D01*
X960626Y1529332D01*
X960571Y1529345D01*
G02X959931Y1529558I781J3414D01*
G03X959769I-81J-183D01*
G02X958351Y1529258I-1418J3202D01*
G01X958349D01*
G02X956931Y1529558I0J3502D01*
G03X956769I-81J-183D01*
G02X955352Y1529258I-1418J3202D01*
G01X955350D01*
G02Y1536262I0J3502D01*
G01X955352D01*
G02X956769Y1535962I-1J-3502D01*
G03X956931I81J183D01*
G02X958349Y1536262I1418J-3202D01*
G01X958351D01*
G02X959769Y1535962I0J-3502D01*
G03X959931I81J183D01*
G02X961349Y1536262I1418J-3202D01*
G01X961351D01*
G02X962769Y1535962I0J-3502D01*
G03X962931I81J183D01*
G02X964349Y1536262I1418J-3202D01*
G37*
G36*
G01X1093299Y1536162D02*
X1093301D01*
G02X1094719Y1535862I0J-3502D01*
G03X1094881I81J183D01*
G02X1096298Y1536162I1418J-3202D01*
G01X1096300D01*
G02Y1529158I0J-3502D01*
G01X1096298D01*
G02X1094881Y1529458I1J3502D01*
G03X1094719I-81J-183D01*
G02X1093301Y1529158I-1418J3202D01*
G01X1093299D01*
G02X1091881Y1529458I0J3502D01*
G03X1091719I-81J-183D01*
G02X1090301Y1529158I-1418J3202D01*
G01X1090299D01*
G02X1088881Y1529458I0J3502D01*
G03X1088719I-81J-183D01*
G02X1087302Y1529158I-1418J3202D01*
G01X1087300D01*
G02Y1536162I0J3502D01*
G01X1087302D01*
G02X1088719Y1535862I-1J-3502D01*
G03X1088881I81J183D01*
G02X1090299Y1536162I1418J-3202D01*
G01X1090301D01*
G02X1091719Y1535862I0J-3502D01*
G03X1091881I81J183D01*
G02X1093299Y1536162I1418J-3202D01*
G37*
G36*
G01X1006350Y1523080D02*
G02X1006650Y1524499I3502J1D01*
G03Y1524661I-183J81D01*
G02X1006350Y1526078I3202J1418D01*
G01Y1526080D01*
G02X1013354I3502J0D01*
G01Y1526078D01*
G02X1013054Y1524661I-3502J1D01*
G03Y1524499I183J-81D01*
G02X1013354Y1523080I-3202J-1418D01*
G02X1013054Y1521661I-3502J-1D01*
G03Y1521499I183J-81D01*
G02X1013354Y1520082I-3202J-1418D01*
G01Y1520080D01*
G02X1006350I-3502J0D01*
G01Y1520082D01*
G02X1006650Y1521499I3502J-1D01*
G03Y1521661I-183J81D01*
G02X1006350Y1523080I3202J1418D01*
G37*
G36*
G01X728916Y1423122D02*
G02X729216Y1424541I3502J1D01*
G03Y1424703I-183J81D01*
G02X728916Y1426120I3202J1418D01*
G01Y1426122D01*
G02X732418Y1429624I3502J0D01*
G01X732420D01*
G02X733837Y1429324I-1J-3502D01*
G03X733999I81J183D01*
G02X735416Y1429624I1418J-3202D01*
G01X735418D01*
G02X738920Y1426122I0J-3502D01*
G01Y1426120D01*
G02X738620Y1424703I-3502J1D01*
G03Y1424541I183J-81D01*
G02X738920Y1423122I-3202J-1418D01*
G02X738620Y1421703I-3502J-1D01*
G03Y1421541I183J-81D01*
G02X738920Y1420124I-3202J-1418D01*
G01Y1420122D01*
G02X735418Y1416620I-3502J0D01*
G01X735416D01*
G02X733999Y1416920I1J3502D01*
G03X733837I-81J-183D01*
G02X732420Y1416620I-1418J3202D01*
G01X732418D01*
G02X728916Y1420122I0J3502D01*
G01Y1420124D01*
G02X729216Y1421541I3502J-1D01*
G03Y1421703I-183J81D01*
G02X728916Y1423122I3202J1418D01*
G37*
G36*
G01X1710944Y1420213D02*
G02X1711245Y1421632I3503J-2D01*
G03Y1421794I-183J81D01*
G02X1710944Y1423213I3202J1421D01*
G02X1714447Y1426716I3503J0D01*
G02X1715866Y1426415I-2J-3503D01*
G03X1716028I81J183D01*
G02X1717447Y1426716I1421J-3202D01*
G02X1720950Y1423213I0J-3503D01*
G02X1720649Y1421794I-3503J2D01*
G03Y1421632I183J-81D01*
G02X1720950Y1420213I-3202J-1421D01*
G02X1720649Y1418794I-3503J2D01*
G03Y1418632I183J-81D01*
G02X1720950Y1417213I-3202J-1421D01*
G02X1717447Y1413710I-3503J0D01*
G02X1716028Y1414011I2J3503D01*
G03X1715866I-81J-183D01*
G02X1714447Y1413710I-1421J3202D01*
G02X1710944Y1417213I0J3503D01*
G02X1711245Y1418632I3503J-2D01*
G03Y1418794I-183J81D01*
G02X1710944Y1420213I3202J1421D01*
G37*
G36*
G01X159370Y1411611D02*
G02X159748Y1413192I3503J-2D01*
G03X159760Y1413343I-178J90D01*
G02X159596Y1414400I3339J1059D01*
G02X166602I3503J0D01*
G02X166224Y1412819I-3503J2D01*
G03X166212Y1412668I178J-90D01*
G02X166376Y1411611I-3339J-1059D01*
G02X166238Y1410639I-3503J2D01*
G03X166249Y1410501I192J-54D01*
G02X166564Y1409048I-3188J-1452D01*
G02X166358Y1407866I-3503J2D01*
G03Y1407730I188J-68D01*
G02X166564Y1406548I-3297J-1184D01*
G02X159558I-3503J0D01*
G02X159764Y1407730I3503J-2D01*
G03Y1407866I-188J68D01*
G02X159558Y1409048I3297J1184D01*
G02X159696Y1410020I3503J-2D01*
G03X159685Y1410158I-192J54D01*
G02X159370Y1411611I3188J1452D01*
G37*
G36*
G01X169474Y1411460D02*
G02X169851Y1413041I3502J0D01*
G03X169863Y1413192I-178J90D01*
G02X169700Y1414249I3340J1056D01*
G02X176704I3502J0D01*
G01Y1414248D01*
G02X176327Y1412668I-3502J1D01*
G03X176315Y1412517I178J-90D01*
G02X176478Y1411460I-3340J-1056D01*
G02X176341Y1410488I-3502J-2D01*
G03X176351Y1410350I192J-55D01*
G02X176666Y1408897I-3187J-1452D01*
G02X176461Y1407714I-3502J-2D01*
G03Y1407580I188J-67D01*
G02X176666Y1406400I-3297J-1181D01*
G01Y1406397D01*
G02X169662I-3502J0D01*
G01Y1406400D01*
G02X169867Y1407580I3502J-1D01*
G03Y1407714I-188J67D01*
G02X169662Y1408897I3297J1181D01*
G02X169799Y1409869I3502J2D01*
G03X169789Y1410007I-192J55D01*
G02X169474Y1411460I3187J1452D01*
G37*
G36*
G01X194307Y1413378D02*
G02X195490Y1413173I2J-3502D01*
G03X195624I67J188D01*
G02X196807Y1413378I1181J-3297D01*
G02X197990Y1413173I2J-3502D01*
G03X198124I67J188D01*
G02X199307Y1413378I1181J-3297D01*
G02X202810Y1409876I1J-3502D01*
G02X202672Y1408904I-3503J2D01*
G03X202683Y1408766I192J-54D01*
G02X202998Y1407313I-3188J-1452D01*
G02X202792Y1406131I-3503J2D01*
G03Y1405995I188J-68D01*
G02X202998Y1404813I-3297J-1184D01*
G02X199495Y1401310I-3503J0D01*
G02X198313Y1401516I2J3503D01*
G03X198177I-68J-188D01*
G02X196995Y1401310I-1184J3297D01*
G02X195813Y1401516I2J3503D01*
G03X195677I-68J-188D01*
G02X194495Y1401310I-1184J3297D01*
G02X193313Y1401516I2J3503D01*
G03X193177I-68J-188D01*
G02X191995Y1401310I-1184J3297D01*
G02X190434Y1401678I2J3503D01*
G03X190256I-89J-179D01*
G02X188695Y1401310I-1563J3135D01*
G02X185192Y1404813I0J3503D01*
G02X185398Y1405995I3503J-2D01*
G03Y1406131I-188J68D01*
G02X185192Y1407313I3297J1184D01*
G02X185330Y1408285I3503J-2D01*
G03X185319Y1408423I-192J54D01*
G02X185004Y1409876I3188J1452D01*
G02X188507Y1413378I3503J-1D01*
G02X190068Y1413011I0J-3503D01*
G03X190246I89J179D01*
G02X191807Y1413378I1561J-3136D01*
G01X191810D01*
G02X192990Y1413173I-1J-3502D01*
G03X193124I67J188D01*
G02X194307Y1413378I1181J-3297D01*
G37*
G36*
G01X1132465Y1407380D02*
G02X1133647Y1407174I-2J-3503D01*
G03X1133783I68J188D01*
G02X1134965Y1407380I1184J-3297D01*
G02X1136147Y1407174I-2J-3503D01*
G03X1136283I68J188D01*
G02X1137465Y1407380I1184J-3297D01*
G02X1140968Y1403877I0J-3503D01*
G02X1140762Y1402695I-3503J2D01*
G03Y1402559I188J-68D01*
G02X1140968Y1401377I-3297J-1184D01*
G02X1140718Y1400079I-3503J2D01*
G03X1140716Y1399936I186J-74D01*
G02X1140928Y1398737I-3291J-1200D01*
G02X1137425Y1395234I-3503J0D01*
G02X1136243Y1395440I2J3503D01*
G03X1136107I-68J-188D01*
G02X1134925Y1395234I-1184J3297D01*
G02X1133743Y1395440I2J3503D01*
G03X1133607I-68J-188D01*
G02X1132425Y1395234I-1184J3297D01*
G02X1131243Y1395440I2J3503D01*
G03X1131107I-68J-188D01*
G02X1129925Y1395234I-1184J3297D01*
G02X1128743Y1395440I2J3503D01*
G03X1128607I-68J-188D01*
G02X1127425Y1395234I-1184J3297D01*
G02X1123922Y1398737I0J3503D01*
G02X1124172Y1400035I3503J-2D01*
G03X1124174Y1400178I-186J74D01*
G02X1123962Y1401377I3291J1200D01*
G02X1124168Y1402559I3503J-2D01*
G03Y1402695I-188J68D01*
G02X1123962Y1403877I3297J1184D01*
G02X1127465Y1407380I3503J0D01*
G02X1128647Y1407174I-2J-3503D01*
G03X1128783I68J188D01*
G02X1129965Y1407380I1184J-3297D01*
G02X1131147Y1407174I-2J-3503D01*
G03X1131283I68J188D01*
G02X1132465Y1407380I1184J-3297D01*
G37*
G36*
G01X758089Y1394448D02*
G02X759238Y1394253I3J-3467D01*
G03X759370I66J189D01*
G02X759781Y1394369I1146J-3273D01*
G02X759780Y1394414I3501J100D01*
G01Y1394418D01*
G02X760060Y1395788I3503J-2D01*
G03Y1395944I-184J78D01*
G02X759780Y1397316I3223J1372D01*
G02X763283Y1400818I3503J-1D01*
G01X763284D01*
G02X765454Y1400064I-1J-3502D01*
G03X765685Y1400052I124J157D01*
G02X767549Y1400588I1862J-2967D01*
G02X771052Y1397086I1J-3502D01*
G02X770772Y1395714I-3503J0D01*
G03Y1395558I184J-78D01*
G02X771052Y1394186I-3223J-1372D01*
G02X770772Y1392814I-3503J0D01*
G03Y1392658I184J-78D01*
G02X771052Y1391286I-3223J-1372D01*
G02X767549Y1387784I-3503J1D01*
G02X764748Y1389183I0J3504D01*
G03X764631Y1389258I-160J-120D01*
G02X764581Y1389269I728J3426D01*
G01X764422Y1389099D01*
G03X764373Y1388913I145J-138D01*
G02X764482Y1388046I-3393J-867D01*
G02X764202Y1386674I-3502J0D01*
G03Y1386518I184J-78D01*
G02X764482Y1385147I-3222J-1372D01*
G01Y1385146D01*
G02X757478I-3502J0D01*
G01Y1385147D01*
G02X757758Y1386518I3502J-1D01*
G03X757757Y1386674I-185J77D01*
G02X757533Y1387427I3224J1369D01*
G03X757377Y1387587I-197J-36D01*
G02X756940Y1387709I712J3394D01*
G03X756808I-66J-189D01*
G02X755663Y1387514I-1146J3272D01*
G01X755659D01*
G02Y1394448I0J3467D01*
G01X755663D01*
G02X756808Y1394253I-1J-3467D01*
G03X756940I66J189D01*
G02X758089Y1394448I1146J-3272D01*
G37*
G36*
G01X725307Y1394348D02*
G02X726456Y1394153I3J-3467D01*
G03X726588I66J189D01*
G02X726999Y1394269I1146J-3273D01*
G02X726998Y1394314I3501J100D01*
G01Y1394318D01*
G02X727278Y1395688I3503J-2D01*
G03Y1395844I-184J78D01*
G02X726998Y1397216I3223J1372D01*
G02X730501Y1400718I3503J-1D01*
G01X730502D01*
G02X732672Y1399964I-1J-3502D01*
G03X732903Y1399952I124J157D01*
G02X734767Y1400488I1862J-2967D01*
G02X738270Y1396986I1J-3502D01*
G02X737990Y1395614I-3503J0D01*
G03Y1395458I184J-78D01*
G02X738270Y1394086I-3223J-1372D01*
G02X737990Y1392714I-3503J0D01*
G03Y1392558I184J-78D01*
G02X738270Y1391186I-3223J-1372D01*
G02X734767Y1387684I-3503J1D01*
G02X731966Y1389083I0J3504D01*
G03X731849Y1389158I-160J-120D01*
G02X731821Y1389164I720J3428D01*
G01X731661Y1388997D01*
G03X731611Y1388814I145J-138D01*
G02X731700Y1388026I-3413J-785D01*
G02X731420Y1386654I-3502J0D01*
G03Y1386498I184J-78D01*
G02X731700Y1385127I-3222J-1372D01*
G01Y1385126D01*
G02X724696I-3502J0D01*
G01Y1385127D01*
G02X724976Y1386498I3502J-1D01*
G03Y1386654I-184J78D01*
G02X724766Y1387328I3222J1373D01*
G03X724610Y1387484I-196J-40D01*
G02X724158Y1387609I696J3397D01*
G03X724026I-66J-189D01*
G02X722881Y1387414I-1146J3272D01*
G01X722877D01*
G02Y1394348I0J3467D01*
G01X722881D01*
G02X724026Y1394153I-1J-3467D01*
G03X724158I66J189D01*
G02X725307Y1394348I1146J-3272D01*
G37*
G36*
G01X1707794Y1395233D02*
G02X1707514Y1396605I3222J1372D01*
G02X1711016Y1400108I3502J1D01*
G02X1713187Y1399353I-1J-3503D01*
G03X1713418Y1399341I124J157D01*
G02X1715282Y1399878I1864J-2967D01*
G02X1718784Y1396375I-1J-3503D01*
G01Y1396374D01*
G02X1718504Y1395003I-3502J1D01*
G03Y1394847I184J-78D01*
G02X1718784Y1393475I-3222J-1372D01*
G02X1718504Y1392103I-3502J0D01*
G03Y1391947I184J-78D01*
G02X1718784Y1390575I-3222J-1372D01*
G02X1715282Y1387072I-3502J-1D01*
G02X1712481Y1388472I0J3502D01*
G03X1712363Y1388547I-159J-121D01*
G02X1712314Y1388558I743J3423D01*
G01X1712155Y1388389D01*
G03X1712107Y1388202I146J-137D01*
G02X1712216Y1387335I-3394J-867D01*
G02X1711936Y1385963I-3503J0D01*
G03Y1385807I184J-78D01*
G02X1712216Y1384435I-3223J-1372D01*
G02X1705210I-3503J0D01*
G02X1705490Y1385807I3503J0D01*
G03Y1385963I-184J78D01*
G02X1705266Y1386716I3224J1369D01*
G03X1705110Y1386876I-197J-36D01*
G02X1704673Y1386998I712J3394D01*
G03X1704541I-66J-189D01*
G02X1703392Y1386802I-1149J3272D01*
G02Y1393738I0J3468D01*
G02X1704541Y1393542I0J-3468D01*
G03X1704673I66J189D01*
G02X1705822Y1393738I1149J-3272D01*
G02X1706971Y1393542I0J-3468D01*
G03X1707103I66J189D01*
G02X1707514Y1393658I1146J-3273D01*
G01Y1393705D01*
G02X1707794Y1395077I3502J0D01*
G03Y1395233I-184J78D01*
G37*
G36*
G01X1675012Y1395133D02*
G02X1674732Y1396505I3222J1372D01*
G02X1678234Y1400008I3502J1D01*
G02X1680405Y1399253I-1J-3503D01*
G03X1680636Y1399241I124J157D01*
G02X1682500Y1399778I1864J-2967D01*
G02X1686002Y1396275I-1J-3503D01*
G01Y1396274D01*
G02X1685722Y1394903I-3502J1D01*
G03Y1394747I184J-78D01*
G02X1686002Y1393375I-3222J-1372D01*
G02X1685722Y1392003I-3502J0D01*
G03Y1391847I184J-78D01*
G02X1686002Y1390475I-3222J-1372D01*
G02X1682500Y1386972I-3502J-1D01*
G02X1679699Y1388372I0J3502D01*
G03X1679581Y1388447I-159J-121D01*
G02X1679532Y1388458I743J3423D01*
G01X1679373Y1388289D01*
G03X1679325Y1388102I146J-137D01*
G02X1679434Y1387235I-3394J-867D01*
G02X1679154Y1385863I-3503J0D01*
G03Y1385707I184J-78D01*
G02X1679434Y1384335I-3223J-1372D01*
G02X1672428I-3503J0D01*
G02X1672708Y1385707I3503J0D01*
G03Y1385863I-184J78D01*
G02X1672484Y1386616I3224J1369D01*
G03X1672328Y1386776I-197J-36D01*
G02X1671891Y1386898I712J3394D01*
G03X1671759I-66J-189D01*
G02X1670610Y1386702I-1149J3272D01*
G02Y1393638I0J3468D01*
G02X1671759Y1393442I0J-3468D01*
G03X1671891I66J189D01*
G02X1673040Y1393638I1149J-3272D01*
G02X1674189Y1393442I0J-3468D01*
G03X1674321I66J189D01*
G02X1674732Y1393558I1146J-3273D01*
G01Y1393605D01*
G02X1675012Y1394977I3502J0D01*
G03Y1395133I-184J78D01*
G37*
G36*
G01X291182Y1387040D02*
G02X291534Y1388572I3502J2D01*
G03Y1388747I-180J88D01*
G02X291180Y1390281I3149J1535D01*
G02X298186I3503J0D01*
G02X297833Y1388748I-3504J0D01*
G03Y1388574I180J-87D01*
G02X298186Y1387040I-3149J-1532D01*
G02X297879Y1385605I-3502J-1D01*
G03X297871Y1385462I183J-82D01*
G02X298036Y1384401I-3338J-1062D01*
G02X297860Y1383305I-3503J0D01*
G03X297870Y1383154I190J-63D01*
G02X298228Y1381612I-3145J-1543D01*
G02X291222I-3503J0D01*
G02X291398Y1382708I3503J0D01*
G03X291388Y1382859I-190J63D01*
G02X291030Y1384401I3145J1543D01*
G02X291338Y1385836I3503J-1D01*
G03X291346Y1385979I-183J82D01*
G02X291182Y1387040I3338J1059D01*
G37*
G36*
G01X1343712Y1393306D02*
G02X1344895Y1393101I2J-3502D01*
G03X1345029I67J188D01*
G02X1346212Y1393306I1181J-3297D01*
G02X1347395Y1393101I2J-3502D01*
G03X1347529I67J188D01*
G02X1348712Y1393306I1181J-3297D01*
G02X1350387Y1392879I-1J-3502D01*
G03X1350577I95J176D01*
G02X1352225Y1393290I1646J-3091D01*
G02X1355728Y1389788I1J-3502D01*
G02X1355431Y1388378I-3503J2D01*
G03Y1388216I183J-81D01*
G02X1355728Y1386804I-3205J-1411D01*
G02X1355428Y1385385I-3502J-1D01*
G03Y1385223I183J-81D01*
G02X1355728Y1383806I-3202J-1418D01*
G01Y1383804D01*
G02X1352226Y1380302I-3502J0D01*
G02X1351121Y1380480I-3J3502D01*
G03X1350977Y1380473I-63J-190D01*
G02X1349556Y1380172I-1420J3201D01*
G02X1348137Y1380472I-1J3502D01*
G03X1347975I-81J-183D01*
G02X1346556Y1380172I-1418J3202D01*
G02X1345137Y1380472I-1J3502D01*
G03X1344975I-81J-183D01*
G02X1343556Y1380172I-1418J3202D01*
G02X1342137Y1380472I-1J3502D01*
G03X1341975I-81J-183D01*
G02X1340556Y1380172I-1418J3202D01*
G02X1339137Y1380472I-1J3502D01*
G03X1338975I-81J-183D01*
G02X1337558Y1380172I-1418J3202D01*
G01X1337556D01*
G02X1334054Y1383674I0J3502D01*
G01Y1383676D01*
G02X1334354Y1385093I3502J-1D01*
G03Y1385255I-183J81D01*
G02X1334054Y1386674I3202J1418D01*
G02X1334350Y1388084I3502J1D01*
G03Y1388246I-183J81D01*
G02X1334052Y1389658I3205J1414D01*
G02X1337555Y1393160I3503J-1D01*
G01X1337556D01*
G02X1339163Y1392769I-1J-3502D01*
G03X1339360Y1392777I91J178D01*
G02X1341212Y1393306I1851J-2973D01*
G02X1342395Y1393101I2J-3502D01*
G03X1342529I67J188D01*
G02X1343712Y1393306I1181J-3297D01*
G37*
G36*
G01X301660Y1386889D02*
G02X301918Y1388209I3503J1D01*
G03Y1388359I-185J75D01*
G02X301660Y1389678I3245J1319D01*
G02X308666I3503J0D01*
G02X308408Y1388359I-3503J0D01*
G03Y1388209I185J-75D01*
G02X308666Y1386889I-3245J-1319D01*
G02X308358Y1385454I-3503J1D01*
G03X308350Y1385311I183J-82D01*
G02X308514Y1384250I-3338J-1059D01*
G02X308338Y1383153I-3502J-1D01*
G03X308349Y1383003I190J-61D01*
G02X308706Y1381463I-3145J-1541D01*
G01Y1381461D01*
G02X301702I-3502J0D01*
G01Y1381465D01*
G02X301878Y1382558I3502J-3D01*
G03X301867Y1382708I-190J61D01*
G02X301510Y1384250I3145J1541D01*
G02X301817Y1385685I3502J1D01*
G03X301825Y1385828I-183J82D01*
G02X301660Y1386889I3338J1062D01*
G37*
G36*
G01X320208Y1376259D02*
G02X320560Y1377791I3502J2D01*
G03Y1377966I-180J88D01*
G02X320206Y1379500I3149J1535D01*
G02X327212I3503J0D01*
G02X326859Y1377967I-3504J0D01*
G03Y1377793I180J-87D01*
G02X327212Y1376259I-3149J-1532D01*
G02X326905Y1374824I-3502J-1D01*
G03X326897Y1374681I183J-82D01*
G02X327062Y1373620I-3338J-1062D01*
G02X326886Y1372524I-3503J0D01*
G03X326896Y1372373I190J-63D01*
G02X327254Y1370831I-3145J-1543D01*
G02X320248I-3503J0D01*
G02X320424Y1371927I3503J0D01*
G03X320414Y1372078I-190J63D01*
G02X320056Y1373620I3145J1543D01*
G02X320364Y1375055I3503J-1D01*
G03X320372Y1375198I-183J82D01*
G02X320208Y1376259I3338J1059D01*
G37*
G36*
G01X250442Y1376309D02*
G02X250722Y1377679I3503J-2D01*
G03Y1377835I-184J78D01*
G02X250442Y1379207I3223J1372D01*
G02X253945Y1382710I3503J0D01*
G02X256116Y1381955I-1J-3503D01*
G03X256347Y1381943I124J157D01*
G02X258211Y1382480I1864J-2967D01*
G02X261714Y1378977I0J-3503D01*
G02X261434Y1377605I-3503J0D01*
G03Y1377449I184J-78D01*
G02X261714Y1376077I-3223J-1372D01*
G02X261434Y1374705I-3503J0D01*
G03Y1374549I184J-78D01*
G02X261714Y1373177I-3223J-1372D01*
G02X258211Y1369674I-3503J0D01*
G02X256286Y1370251I1J3503D01*
G01X256285Y1370252D01*
G03X256088Y1370264I-109J-168D01*
G01X255731Y1370090D01*
X255671Y1370002D01*
X255667Y1369950D01*
G02X255396Y1368861I-3456J282D01*
G03Y1368703I184J-79D01*
G02X255678Y1367335I-3185J-1370D01*
G01Y1367332D01*
G02X248744I-3467J0D01*
G01Y1367335D01*
G02X249026Y1368703I3467J-2D01*
G03Y1368861I-184J79D01*
G02X248843Y1369406I3184J1372D01*
G02X248752Y1369404I-122J3465D01*
G01X248750D01*
G02X247602Y1369600I1J3468D01*
G03X247470I-66J-189D01*
G02X246321Y1369404I-1149J3272D01*
G02Y1376340I0J3468D01*
G02X247470Y1376144I0J-3468D01*
G03X247602I66J189D01*
G02X248751Y1376340I1149J-3272D01*
G02X249900Y1376144I0J-3468D01*
G03X250032I66J189D01*
G02X250443Y1376260I1146J-3273D01*
G02X250442Y1376305I3501J100D01*
G01Y1376309D01*
G37*
G36*
G01X217642D02*
G02X217922Y1377679I3503J-2D01*
G03Y1377835I-184J78D01*
G02X217642Y1379207I3223J1372D01*
G02X221145Y1382710I3503J0D01*
G02X223316Y1381955I-1J-3503D01*
G03X223547Y1381943I124J157D01*
G02X225411Y1382480I1864J-2967D01*
G02X228914Y1378977I0J-3503D01*
G02X228634Y1377605I-3503J0D01*
G03Y1377449I184J-78D01*
G02X228914Y1376077I-3223J-1372D01*
G02X228634Y1374705I-3503J0D01*
G03Y1374549I184J-78D01*
G02X228914Y1373177I-3223J-1372D01*
G02X225411Y1369674I-3503J0D01*
G02X223516Y1370231I0J3502D01*
G01X223471Y1370260D01*
X223364Y1370266D01*
X222960Y1370056D01*
X222902Y1369966D01*
X222900Y1369913D01*
G02X222624Y1368695I-3499J153D01*
G03Y1368539I184J-78D01*
G02X222904Y1367167I-3223J-1372D01*
G02X215898I-3503J0D01*
G02X216178Y1368539I3503J0D01*
G03X216179Y1368695I-184J79D01*
G02X215962Y1369405I3222J1373D01*
G01X215960D01*
G02X215942Y1369404I-20J199D01*
G02X214802Y1369600I9J3468D01*
G03X214670I-66J-189D01*
G02X213521Y1369404I-1149J3272D01*
G02Y1376340I0J3468D01*
G02X214670Y1376144I0J-3468D01*
G03X214802I66J189D01*
G02X215951Y1376340I1149J-3272D01*
G02X217100Y1376144I0J-3468D01*
G03X217232I66J189D01*
G02X217643Y1376260I1146J-3273D01*
G02X217642Y1376305I3501J100D01*
G01Y1376309D01*
G37*
G36*
G01X184742D02*
G02X185022Y1377679I3503J-2D01*
G03Y1377835I-184J78D01*
G02X184742Y1379207I3223J1372D01*
G02X188245Y1382710I3503J0D01*
G02X190416Y1381955I-1J-3503D01*
G03X190647Y1381943I124J157D01*
G02X192511Y1382480I1864J-2967D01*
G02X196014Y1378977I0J-3503D01*
G02X195734Y1377605I-3503J0D01*
G03Y1377449I184J-78D01*
G02X196014Y1376077I-3223J-1372D01*
G02X195734Y1374705I-3503J0D01*
G03Y1374549I184J-78D01*
G02X196014Y1373177I-3223J-1372D01*
G02X192511Y1369674I-3503J0D01*
G02X190595Y1370245I1J3503D01*
G01X190550Y1370275D01*
X190445Y1370281D01*
X190087Y1370101D01*
G03X189977Y1369934I90J-179D01*
G02X189704Y1368775I-3496J212D01*
G03Y1368619I184J-78D01*
G02X189984Y1367247I-3223J-1372D01*
G02X182978I-3503J0D01*
G02X183258Y1368619I3503J0D01*
G03Y1368775I-184J78D01*
G02X183058Y1369405I3224J1370D01*
G02X183051Y1369404I-489J3398D01*
G02X181902Y1369600I0J3468D01*
G03X181770I-66J-189D01*
G02X180621Y1369404I-1149J3272D01*
G02Y1376340I0J3468D01*
G02X181770Y1376144I0J-3468D01*
G03X181902I66J189D01*
G02X183051Y1376340I1149J-3272D01*
G02X184200Y1376144I0J-3468D01*
G03X184332I66J189D01*
G02X184743Y1376260I1146J-3273D01*
G02X184742Y1376305I3501J100D01*
G01Y1376309D01*
G37*
G36*
G01X152042D02*
G02X152322Y1377679I3503J-2D01*
G03Y1377835I-184J78D01*
G02X152042Y1379207I3223J1372D01*
G02X155545Y1382710I3503J0D01*
G02X157716Y1381955I-1J-3503D01*
G03X157947Y1381943I124J157D01*
G02X159811Y1382480I1864J-2967D01*
G02X163314Y1378977I0J-3503D01*
G02X163034Y1377605I-3503J0D01*
G03Y1377449I184J-78D01*
G02X163314Y1376077I-3223J-1372D01*
G02X163034Y1374705I-3503J0D01*
G03Y1374549I184J-78D01*
G02X163314Y1373177I-3223J-1372D01*
G02X159811Y1369674I-3503J0D01*
G02X157865Y1370265I1J3503D01*
G01X157819Y1370295D01*
X157709Y1370301D01*
X157350Y1370111D01*
G03X157243Y1369938I93J-177D01*
G01Y1369937D01*
G02X156963Y1368605I-3502J41D01*
G03X156964Y1368449I185J-77D01*
G02X157244Y1367077I-3223J-1372D01*
G02X150238I-3503J0D01*
G02X150518Y1368449I3503J0D01*
G03X150519Y1368605I-184J79D01*
G02X150315Y1369253I3223J1371D01*
G03X150132Y1369411I-196J-42D01*
G02X149202Y1369600I219J3461D01*
G03X149070I-66J-189D01*
G02X147921Y1369404I-1149J3272D01*
G02Y1376340I0J3468D01*
G02X149070Y1376144I0J-3468D01*
G03X149202I66J189D01*
G02X150351Y1376340I1149J-3272D01*
G02X151500Y1376144I0J-3468D01*
G03X151632I66J189D01*
G02X152043Y1376260I1146J-3273D01*
G02X152042Y1376305I3501J100D01*
G01Y1376309D01*
G37*
G36*
G01X119442D02*
G02X119722Y1377679I3503J-2D01*
G03Y1377835I-184J78D01*
G02X119442Y1379207I3223J1372D01*
G02X122945Y1382710I3503J0D01*
G02X125116Y1381955I-1J-3503D01*
G03X125347Y1381943I124J157D01*
G02X127211Y1382480I1864J-2967D01*
G02X130714Y1378977I0J-3503D01*
G02X130434Y1377605I-3503J0D01*
G03Y1377449I184J-78D01*
G02X130714Y1376077I-3223J-1372D01*
G02X130434Y1374705I-3503J0D01*
G03Y1374549I184J-78D01*
G02X130714Y1373177I-3223J-1372D01*
G02X127211Y1369674I-3503J0D01*
G02X125355Y1370207I1J3503D01*
G03X125153Y1370213I-106J-169D01*
G01X124800Y1370022D01*
X124744Y1369930D01*
X124743Y1369876D01*
G02X124464Y1368575I-3502J71D01*
G03Y1368419I184J-78D01*
G02X124744Y1367047I-3223J-1372D01*
G02X122784Y1363903I-3502J0D01*
G03X122672Y1363714I88J-180D01*
G02X122674Y1363643I-1465J-77D01*
G02X119740I-1467J0D01*
G02X119743Y1363743I1467J6D01*
G03X119635Y1363934I-199J13D01*
G02X117738Y1367047I1606J3113D01*
G02X118018Y1368419I3503J0D01*
G03X118019Y1368575I-184J79D01*
G02X117781Y1369405I3222J1373D01*
G02X117754Y1369404I-142J3463D01*
G01X117748D01*
G02X116602Y1369600I3J3468D01*
G03X116470I-66J-189D01*
G02X115321Y1369404I-1149J3272D01*
G02Y1376340I0J3468D01*
G02X116470Y1376144I0J-3468D01*
G03X116602I66J189D01*
G02X117751Y1376340I1149J-3272D01*
G02X118900Y1376144I0J-3468D01*
G03X119032I66J189D01*
G02X119443Y1376260I1146J-3273D01*
G02X119442Y1376305I3501J100D01*
G01Y1376309D01*
G37*
G36*
G01X1220489Y1376320D02*
G02X1221638Y1376125I3J-3467D01*
G03X1221770I66J189D01*
G02X1222181Y1376241I1146J-3273D01*
G02X1222180Y1376286I3501J100D01*
G01Y1376290D01*
G02X1222460Y1377660I3503J-2D01*
G03Y1377816I-184J78D01*
G02X1222180Y1379188I3223J1372D01*
G02X1225683Y1382690I3503J-1D01*
G01X1225684D01*
G02X1227854Y1381936I-1J-3502D01*
G03X1228085Y1381924I124J157D01*
G02X1229949Y1382460I1862J-2967D01*
G02X1233452Y1378958I1J-3502D01*
G02X1233172Y1377586I-3503J0D01*
G03Y1377430I184J-78D01*
G02X1233452Y1376058I-3223J-1372D01*
G02X1233172Y1374686I-3503J0D01*
G03Y1374530I184J-78D01*
G02X1233452Y1373158I-3223J-1372D01*
G02X1229949Y1369656I-3503J1D01*
G01X1229948D01*
G02X1228009Y1370242I0J3502D01*
G01X1227964Y1370272D01*
X1227857Y1370279D01*
X1227497Y1370097D01*
G03X1227388Y1369927I91J-178D01*
G02X1227112Y1368716I-3499J161D01*
G03Y1368560I184J-78D01*
G02X1227392Y1367188I-3223J-1372D01*
G02X1220386I-3503J0D01*
G02X1220666Y1368560I3503J0D01*
G03X1220667Y1368716I-184J79D01*
G02X1220491Y1369239I3221J1375D01*
G03X1220308Y1369391I-194J-48D01*
G02X1219340Y1369581I177J3463D01*
G03X1219208I-66J-189D01*
G02X1218063Y1369386I-1146J3272D01*
G01X1218059D01*
G02Y1376320I0J3467D01*
G01X1218063D01*
G02X1219208Y1376125I-1J-3467D01*
G03X1219340I66J189D01*
G02X1220489Y1376320I1146J-3272D01*
G37*
G36*
G01X1187689D02*
G02X1188838Y1376125I3J-3467D01*
G03X1188970I66J189D01*
G02X1189381Y1376241I1146J-3273D01*
G02X1189380Y1376286I3501J100D01*
G01Y1376290D01*
G02X1189660Y1377660I3503J-2D01*
G03Y1377816I-184J78D01*
G02X1189380Y1379188I3223J1372D01*
G02X1192883Y1382690I3503J-1D01*
G01X1192884D01*
G02X1195054Y1381936I-1J-3502D01*
G03X1195285Y1381924I124J157D01*
G02X1197149Y1382460I1862J-2967D01*
G02X1200652Y1378958I1J-3502D01*
G02X1200372Y1377586I-3503J0D01*
G03Y1377430I184J-78D01*
G02X1200652Y1376058I-3223J-1372D01*
G02X1200372Y1374686I-3503J0D01*
G03Y1374530I184J-78D01*
G02X1200652Y1373158I-3223J-1372D01*
G02X1197149Y1369656I-3503J1D01*
G01X1197146D01*
G02X1195174Y1370265I2J3502D01*
G01X1195129Y1370296D01*
X1195021Y1370304D01*
X1194609Y1370097D01*
X1194551Y1370006D01*
X1194549Y1369951D01*
G02X1194272Y1368716I-3500J136D01*
G03Y1368560I184J-78D01*
G02X1194552Y1367188I-3223J-1372D01*
G02X1187546I-3503J0D01*
G02X1187826Y1368560I3503J0D01*
G03X1187827Y1368716I-184J79D01*
G02X1187651Y1369241I3222J1372D01*
G03X1187469Y1369392I-194J-49D01*
G02X1186540Y1369581I220J3461D01*
G03X1186408I-66J-189D01*
G02X1185263Y1369386I-1146J3272D01*
G01X1185259D01*
G02Y1376320I0J3467D01*
G01X1185263D01*
G02X1186408Y1376125I-1J-3467D01*
G03X1186540I66J189D01*
G02X1187689Y1376320I1146J-3272D01*
G37*
G36*
G01X1154789D02*
G02X1155938Y1376125I3J-3467D01*
G03X1156070I66J189D01*
G02X1156481Y1376241I1146J-3273D01*
G02X1156480Y1376286I3501J100D01*
G01Y1376290D01*
G02X1156760Y1377660I3503J-2D01*
G03Y1377816I-184J78D01*
G02X1156480Y1379188I3223J1372D01*
G02X1159983Y1382690I3503J-1D01*
G01X1159984D01*
G02X1162154Y1381936I-1J-3502D01*
G03X1162385Y1381924I124J157D01*
G02X1164249Y1382460I1862J-2967D01*
G02X1167752Y1378958I1J-3502D01*
G02X1167472Y1377586I-3503J0D01*
G03Y1377430I184J-78D01*
G02X1167752Y1376058I-3223J-1372D01*
G02X1167472Y1374686I-3503J0D01*
G03Y1374530I184J-78D01*
G02X1167752Y1373158I-3223J-1372D01*
G02X1164249Y1369656I-3503J1D01*
G01X1164247D01*
G02X1162195Y1370321I1J3502D01*
G01X1162149Y1370354D01*
X1162036Y1370362D01*
X1161617Y1370144D01*
X1161560Y1370046D01*
X1161561Y1369989D01*
G02X1161562Y1369918I-3502J-85D01*
G02X1161282Y1368546I-3503J0D01*
G03Y1368390I184J-78D01*
G02X1161562Y1367018I-3223J-1372D01*
G02X1154556I-3503J0D01*
G02X1154836Y1368390I3503J0D01*
G03Y1368546I-184J78D01*
G02X1154622Y1369242I3223J1372D01*
G03X1154446Y1369403I-196J-38D01*
G02X1153640Y1369581I339J3451D01*
G03X1153508I-66J-189D01*
G02X1152363Y1369386I-1146J3272D01*
G01X1152359D01*
G02Y1376320I0J3467D01*
G01X1152363D01*
G02X1153508Y1376125I-1J-3467D01*
G03X1153640I66J189D01*
G02X1154789Y1376320I1146J-3272D01*
G37*
G36*
G01X1122089D02*
G02X1123238Y1376125I3J-3467D01*
G03X1123370I66J189D01*
G02X1123781Y1376241I1146J-3273D01*
G02X1123780Y1376286I3501J100D01*
G01Y1376290D01*
G02X1124060Y1377660I3503J-2D01*
G03Y1377816I-184J78D01*
G02X1123780Y1379188I3223J1372D01*
G02X1127283Y1382690I3503J-1D01*
G01X1127284D01*
G02X1129454Y1381936I-1J-3502D01*
G03X1129685Y1381924I124J157D01*
G02X1131549Y1382460I1862J-2967D01*
G02X1135052Y1378958I1J-3502D01*
G02X1134772Y1377586I-3503J0D01*
G03Y1377430I184J-78D01*
G02X1135052Y1376058I-3223J-1372D01*
G02X1134772Y1374686I-3503J0D01*
G03Y1374530I184J-78D01*
G02X1135052Y1373158I-3223J-1372D01*
G02X1131549Y1369656I-3503J1D01*
G01X1131548D01*
G02X1129594Y1370252I0J3502D01*
G01X1129593Y1370253D01*
G03X1129390Y1370264I-111J-167D01*
G01X1129030Y1370077D01*
X1128972Y1369984D01*
X1128971Y1369929D01*
G02X1128692Y1368636I-3502J79D01*
G03Y1368480I184J-78D01*
G02X1128972Y1367108I-3223J-1372D01*
G02X1121966I-3503J0D01*
G02X1122246Y1368480I3503J0D01*
G03Y1368636I-184J78D01*
G02X1122052Y1369237I3223J1372D01*
G03X1121870Y1369392I-195J-44D01*
G02X1120940Y1369581I219J3461D01*
G03X1120808I-66J-189D01*
G02X1119663Y1369386I-1146J3272D01*
G01X1119659D01*
G02Y1376320I0J3467D01*
G01X1119663D01*
G02X1120808Y1376125I-1J-3467D01*
G03X1120940I66J189D01*
G02X1122089Y1376320I1146J-3272D01*
G37*
G36*
G01X1089489D02*
G02X1090638Y1376125I3J-3467D01*
G03X1090770I66J189D01*
G02X1091181Y1376241I1146J-3273D01*
G02X1091180Y1376286I3501J100D01*
G01Y1376290D01*
G02X1091460Y1377660I3503J-2D01*
G03Y1377816I-184J78D01*
G02X1091180Y1379188I3223J1372D01*
G02X1094683Y1382690I3503J-1D01*
G01X1094684D01*
G02X1096854Y1381936I-1J-3502D01*
G03X1097085Y1381924I124J157D01*
G02X1098949Y1382460I1862J-2967D01*
G02X1102452Y1378958I1J-3502D01*
G02X1102172Y1377586I-3503J0D01*
G03Y1377430I184J-78D01*
G02X1102452Y1376058I-3223J-1372D01*
G02X1102172Y1374686I-3503J0D01*
G03Y1374530I184J-78D01*
G02X1102452Y1373158I-3223J-1372D01*
G02X1098949Y1369656I-3503J1D01*
G01X1098947D01*
G02X1097004Y1370245I1J3502D01*
G01X1096960Y1370274D01*
X1096853Y1370282D01*
X1096494Y1370105D01*
G03X1096383Y1369939I89J-179D01*
G02X1096111Y1368806I-3494J240D01*
G03X1096112Y1368650I185J-77D01*
G02X1096392Y1367278I-3223J-1372D01*
G02X1089386I-3503J0D01*
G02X1089666Y1368650I3503J0D01*
G03Y1368806I-184J78D01*
G02X1089513Y1369243I3222J1373D01*
G03X1089330Y1369390I-193J-53D01*
G02X1088340Y1369581I155J3464D01*
G03X1088208I-66J-189D01*
G02X1087063Y1369386I-1146J3272D01*
G01X1087059D01*
G02Y1376320I0J3467D01*
G01X1087063D01*
G02X1088208Y1376125I-1J-3467D01*
G03X1088340I66J189D01*
G02X1089489Y1376320I1146J-3272D01*
G37*
G36*
G01X330686Y1376108D02*
G02X330944Y1377427I3503J0D01*
G03Y1377577I-185J75D01*
G02X330686Y1378897I3245J1319D01*
G02X337692I3503J0D01*
G02X337434Y1377577I-3503J-1D01*
G03Y1377427I185J-75D01*
G02X337692Y1376108I-3245J-1319D01*
G02X337384Y1374673I-3503J1D01*
G03X337376Y1374530I183J-82D01*
G02X337540Y1373469I-3338J-1059D01*
G02X337364Y1372372I-3502J-1D01*
G03X337375Y1372222I190J-61D01*
G02X337732Y1370682I-3145J-1541D01*
G01Y1370680D01*
G02X330728I-3502J0D01*
G01Y1370684D01*
G02X330904Y1371777I3502J-3D01*
G03X330893Y1371927I-190J61D01*
G02X330536Y1373469I3145J1541D01*
G02X330843Y1374904I3502J1D01*
G03X330851Y1375047I-183J82D01*
G02X330686Y1376108I3338J1062D01*
G37*
G36*
G01X362223Y1368226D02*
G02X363406Y1368021I2J-3502D01*
G03X363540I67J188D01*
G02X364723Y1368226I1181J-3297D01*
G02X368226Y1364724I1J-3502D01*
G02X367918Y1363289I-3503J1D01*
G03X367910Y1363146I183J-82D01*
G02X368074Y1362085I-3338J-1059D01*
G02X367898Y1360988I-3502J-1D01*
G03X367909Y1360838I190J-61D01*
G02X368266Y1359298I-3145J-1541D01*
G01Y1359296D01*
G02X364764Y1355794I-3502J0D01*
G01X364761D01*
G02X363581Y1355999I1J3502D01*
G03X363447I-67J-188D01*
G02X362264Y1355794I-1181J3297D01*
G02X361081Y1355999I-2J3502D01*
G03X360947I-67J-188D01*
G02X359764Y1355794I-1181J3297D01*
G02X358345Y1356094I-1J3502D01*
G03X358183I-81J-183D01*
G02X356764Y1355794I-1418J3202D01*
G02X355581Y1355999I-2J3502D01*
G03X355447I-67J-188D01*
G02X354264Y1355794I-1181J3297D01*
G02X353135Y1355981I0J3502D01*
G03X352993Y1355976I-64J-190D01*
G02X351632Y1355700I-1363J3227D01*
G02X348130Y1359203I1J3503D01*
G01Y1359206D01*
G02X348476Y1360723I3502J-1D01*
G03X348484Y1360878I-180J87D01*
G02X348270Y1362085I3288J1205D01*
G02X348577Y1363520I3502J1D01*
G03X348585Y1363663I-183J82D01*
G02X348420Y1364724I3338J1062D01*
G02X351923Y1368226I3503J-1D01*
G01X351926D01*
G02X353106Y1368021I-1J-3502D01*
G03X353240I67J188D01*
G02X354423Y1368226I1181J-3297D01*
G02X355606Y1368021I2J-3502D01*
G03X355740I67J188D01*
G02X356923Y1368226I1181J-3297D01*
G02X358106Y1368021I2J-3502D01*
G03X358240I67J188D01*
G02X359423Y1368226I1181J-3297D01*
G02X360747Y1367967I2J-3502D01*
G03X360899I76J185D01*
G02X362223Y1368226I1322J-3243D01*
G37*
G36*
G01X415198Y1349687D02*
G02X415452Y1350638I3477J-419D01*
G03Y1350794I-184J78D01*
G02X415172Y1352166I3223J1372D01*
G02X417978Y1355599I3503J0D01*
G03X418121Y1355713I-39J196D01*
G02X421315Y1357778I3194J-1438D01*
G01X421317D01*
G02X424818Y1354276I-1J-3502D01*
G02X424538Y1352904I-3503J0D01*
G03Y1352748I184J-78D01*
G02X424818Y1351376I-3223J-1372D01*
G02X424505Y1349928I-3502J-1D01*
G03X424499Y1349777I182J-83D01*
G02X424708Y1348586I-3294J-1192D01*
G02X424428Y1347214I-3503J0D01*
G03Y1347058I184J-78D01*
G02X424708Y1345686I-3223J-1372D01*
G02X421205Y1342184I-3503J1D01*
G01X421203D01*
G02X420507Y1342254I1J3502D01*
G03X420282Y1342132I-39J-196D01*
G02X420248Y1342052I-3208J1316D01*
G03Y1341894I184J-79D01*
G02X420530Y1340526I-3185J-1370D01*
G01Y1340523D01*
G02X413596I-3467J0D01*
G01Y1340526D01*
G02X413878Y1341894I3467J-2D01*
G03Y1342052I-184J79D01*
G02X413670Y1342707I3185J1372D01*
G02X413533Y1342704I-144J3465D01*
G02X412384Y1342900I0J3468D01*
G03X412252I-66J-189D01*
G02X411103Y1342704I-1149J3272D01*
G02Y1349640I0J3468D01*
G02X412252Y1349444I0J-3468D01*
G03X412384I66J189D01*
G02X413533Y1349640I1149J-3272D01*
G02X414682Y1349444I0J-3468D01*
G03X414814I66J189D01*
G02X415052Y1349518I1148J-3272D01*
G03X415198Y1349687I-53J193D01*
G37*
G36*
G01X1389662Y1349620D02*
G02X1390811Y1349425I3J-3467D01*
G03X1390943I66J189D01*
G02X1391354Y1349541I1146J-3273D01*
G01Y1349588D01*
G02X1391634Y1350960I3502J0D01*
G03Y1351116I-184J78D01*
G02X1391354Y1352487I3222J1372D01*
G01Y1352488D01*
G02X1394856Y1355990I3502J0D01*
G01X1394857D01*
G02X1397027Y1355236I-1J-3502D01*
G03X1397258Y1355224I124J157D01*
G02X1399119Y1355760I1862J-2967D01*
G01X1399122D01*
G02X1402624Y1352258I0J-3502D01*
G01Y1352257D01*
G02X1402344Y1350886I-3502J1D01*
G03Y1350730I184J-78D01*
G02X1402624Y1349358I-3222J-1372D01*
G02X1402344Y1347986I-3502J0D01*
G03Y1347830I184J-78D01*
G02X1402624Y1346459I-3222J-1372D01*
G01Y1346458D01*
G02X1399122Y1342956I-3502J0D01*
G01X1399120D01*
G02X1397123Y1343582I1J3502D01*
G01X1397122D01*
G03X1397009Y1343618I-114J-164D01*
G01X1397008D01*
G03X1396808Y1343418I0J-200D01*
G01Y1343414D01*
G02X1396528Y1342043I-3502J1D01*
G03Y1341887I184J-78D01*
G02X1396808Y1340516I-3222J-1372D01*
G01Y1340515D01*
G02X1389804I-3502J0D01*
G01Y1340516D01*
G02X1390084Y1341887I3502J-1D01*
G03Y1342043I-184J78D01*
G02X1389916Y1342536I3222J1373D01*
G03X1389719Y1342686I-194J-50D01*
G01X1389662D01*
G02X1388513Y1342881I-3J3467D01*
G03X1388381I-66J-189D01*
G02X1387236Y1342686I-1146J3272D01*
G01X1387232D01*
G02Y1349620I0J3467D01*
G01X1387236D01*
G02X1388381Y1349425I-1J-3467D01*
G03X1388513I66J189D01*
G02X1389662Y1349620I1146J-3272D01*
G37*
G36*
G01X380951Y1330308D02*
G02X382100Y1330113I3J-3467D01*
G03X382232I66J189D01*
G02X382643Y1330229I1146J-3273D01*
G02X382642Y1330274I3501J100D01*
G01Y1330278D01*
G02X382922Y1331648I3503J-2D01*
G03Y1331804I-184J78D01*
G02X382642Y1333176I3223J1372D01*
G02X383188Y1335053I3503J-1D01*
G03X383213Y1335208I-169J107D01*
G02X383108Y1336056I3398J851D01*
G02X385773Y1339457I3503J0D01*
G03X385890Y1339537I-47J194D01*
G02X388771Y1341048I2881J-1991D01*
G01X388773D01*
G02X392274Y1337546I-1J-3502D01*
G02X391973Y1336127I-3503J2D01*
G03Y1335965I183J-81D01*
G02X392274Y1334546I-3202J-1421D01*
G02X391711Y1332643I-3503J1D01*
G03X391686Y1332481I168J-109D01*
G02X391814Y1331546I-3375J-938D01*
G02X391464Y1330021I-3503J1D01*
G03X391459Y1329859I180J-87D01*
G02X391714Y1328546I-3248J-1312D01*
G02X388300Y1325045I-3502J0D01*
G01X388298D01*
G03X388152Y1324974I7J-200D01*
G01X387930Y1324713D01*
X387907Y1324630D01*
X387913Y1324588D01*
G02X387948Y1324092I-3432J-491D01*
G02X387666Y1322721I-3467J-1D01*
G03Y1322563I184J-79D01*
G02X387948Y1321195I-3185J-1370D01*
G01Y1321192D01*
G02X381014I-3467J0D01*
G01Y1321195D01*
G02X381296Y1322563I3467J-2D01*
G03Y1322721I-184J79D01*
G02X381088Y1323376I3185J1372D01*
G02X380952Y1323374I-119J3465D01*
G01X380950D01*
G02X379802Y1323569I-2J3467D01*
G03X379670I-66J-189D01*
G02X378525Y1323374I-1146J3272D01*
G01X378521D01*
G02Y1330308I0J3467D01*
G01X378525D01*
G02X379670Y1330113I-1J-3467D01*
G03X379802I66J189D01*
G02X380951Y1330308I1146J-3272D01*
G37*
G36*
G01X1357080Y1323354D02*
G02X1355931Y1323550I0J3468D01*
G03X1355799I-66J-189D01*
G02X1354650Y1323354I-1149J3272D01*
G02Y1330290I0J3468D01*
G02X1355799Y1330094I0J-3468D01*
G03X1355931I66J189D01*
G02X1357080Y1330290I1149J-3272D01*
G02X1358229Y1330094I0J-3468D01*
G03X1358361I66J189D01*
G02X1358772Y1330210I1146J-3273D01*
G01Y1330257D01*
G02X1359052Y1331629I3502J0D01*
G03Y1331785I-184J78D01*
G02X1358772Y1333157I3222J1372D01*
G02X1359052Y1334529I3502J0D01*
G03Y1334685I-184J78D01*
G02X1358772Y1336056I3222J1372D01*
G01Y1336057D01*
G02X1361459Y1339463I3502J0D01*
G03X1361576Y1339543I-47J194D01*
G02X1364440Y1341030I2865J-2016D01*
G02X1367942Y1337527I-1J-3503D01*
G01Y1337525D01*
G02X1367642Y1336108I-3502J1D01*
G03Y1335946I183J-81D01*
G02X1367942Y1334527I-3202J-1418D01*
G02X1367642Y1333108I-3502J-1D01*
G03Y1332946I183J-81D01*
G02X1367942Y1331527I-3202J-1418D01*
G02X1367593Y1330002I-3502J-1D01*
G03X1367587Y1329840I180J-88D01*
G02X1367842Y1328531I-3247J-1312D01*
G01Y1328527D01*
G02X1364563Y1325032I-3502J0D01*
G01X1364561D01*
G03X1364420Y1324959I14J-200D01*
G01X1364208Y1324699D01*
X1364186Y1324618D01*
X1364192Y1324576D01*
G02X1364226Y1324084I-3468J-487D01*
G02X1363946Y1322712I-3502J0D01*
G03Y1322556I184J-78D01*
G02X1364226Y1321185I-3222J-1372D01*
G01Y1321184D01*
G02X1357222I-3502J0D01*
G01Y1321185D01*
G02X1357502Y1322556I3502J-1D01*
G03Y1322712I-184J78D01*
G02X1357334Y1323205I3222J1373D01*
G03X1357137Y1323355I-194J-50D01*
G02X1357080Y1323354I-89J3466D01*
G37*
G36*
G01X284042Y1330163D02*
G02X284322Y1331533I3503J-2D01*
G03Y1331689I-184J78D01*
G02X284042Y1333061I3223J1372D01*
G02X287545Y1336564I3503J0D01*
G02X289716Y1335809I-1J-3503D01*
G03X289947Y1335797I124J157D01*
G02X291811Y1336334I1864J-2967D01*
G02X295314Y1332831I0J-3503D01*
G02X295034Y1331459I-3503J0D01*
G03Y1331303I184J-78D01*
G02X295314Y1329931I-3223J-1372D01*
G02X295034Y1328559I-3503J0D01*
G03Y1328403I184J-78D01*
G02X295314Y1327031I-3223J-1372D01*
G02X291811Y1323528I-3503J0D01*
G02X289967Y1324053I1J3503D01*
G01X289921Y1324082D01*
X289815Y1324085D01*
X289415Y1323871D01*
X289358Y1323780D01*
X289357Y1323727D01*
G02X289076Y1322471I-3466J116D01*
G03Y1322313I184J-79D01*
G02X289358Y1320945I-3185J-1370D01*
G01Y1320942D01*
G02X282424I-3467J0D01*
G01Y1320945D01*
G02X282706Y1322313I3467J-2D01*
G03Y1322471I-184J79D01*
G02X282473Y1323261I3186J1369D01*
G02X282352Y1323258I-146J3464D01*
G01X282350D01*
G02X281202Y1323454I1J3468D01*
G03X281070I-66J-189D01*
G02X279921Y1323258I-1149J3272D01*
G02Y1330194I0J3468D01*
G02X281070Y1329998I0J-3468D01*
G03X281202I66J189D01*
G02X282351Y1330194I1149J-3272D01*
G02X283500Y1329998I0J-3468D01*
G03X283632I66J189D01*
G02X284043Y1330114I1146J-3273D01*
G02X284042Y1330159I3501J100D01*
G01Y1330163D01*
G37*
G36*
G01X1258480Y1330174D02*
G02X1259629Y1329979I3J-3467D01*
G03X1259761I66J189D01*
G02X1260172Y1330095I1146J-3273D01*
G01Y1330142D01*
G02X1260452Y1331514I3502J0D01*
G03Y1331670I-184J78D01*
G02X1260172Y1333041I3222J1372D01*
G01Y1333042D01*
G02X1263674Y1336544I3502J0D01*
G01X1263675D01*
G02X1265845Y1335790I-1J-3502D01*
G03X1266076Y1335778I124J157D01*
G02X1267937Y1336314I1862J-2967D01*
G01X1267940D01*
G02X1271442Y1332812I0J-3502D01*
G01Y1332811D01*
G02X1271162Y1331440I-3502J1D01*
G03Y1331284I184J-78D01*
G02X1271442Y1329912I-3222J-1372D01*
G02X1271162Y1328540I-3502J0D01*
G03Y1328384I184J-78D01*
G02X1271442Y1327013I-3222J-1372D01*
G01Y1327012D01*
G02X1267940Y1323510I-3502J0D01*
G01X1267938D01*
G02X1266154Y1323999I1J3502D01*
G01X1266108Y1324026D01*
X1266003Y1324028D01*
X1265607Y1323810D01*
X1265552Y1323720D01*
X1265551Y1323667D01*
G02X1265273Y1322406I-3501J111D01*
G03X1265272Y1322250I184J-79D01*
G02X1265552Y1320879I-3222J-1372D01*
G01Y1320878D01*
G02X1258548I-3502J0D01*
G01Y1320879D01*
G02X1258828Y1322250I3502J-1D01*
G03Y1322406I-184J78D01*
G02X1258589Y1323241I3222J1374D01*
G02X1258481Y1323240I-86J3466D01*
G01X1258479D01*
G02X1257331Y1323435I-2J3467D01*
G03X1257199I-66J-189D01*
G02X1256054Y1323240I-1146J3272D01*
G01X1256050D01*
G02Y1330174I0J3467D01*
G01X1256054D01*
G02X1257199Y1329979I-1J-3467D01*
G03X1257331I66J189D01*
G02X1258480Y1330174I1146J-3272D01*
G37*
G36*
G01X316938Y1330135D02*
G02X317218Y1331505I3503J-2D01*
G03Y1331661I-184J78D01*
G02X316938Y1333033I3223J1372D01*
G02X320441Y1336536I3503J0D01*
G02X322612Y1335781I-1J-3503D01*
G03X322843Y1335769I124J157D01*
G02X324707Y1336306I1864J-2967D01*
G02X328210Y1332803I0J-3503D01*
G02X327930Y1331431I-3503J0D01*
G03Y1331275I184J-78D01*
G02X328210Y1329903I-3223J-1372D01*
G02X327930Y1328531I-3503J0D01*
G03Y1328375I184J-78D01*
G02X328210Y1327003I-3223J-1372D01*
G02X324707Y1323500I-3503J0D01*
G02X322884Y1324012I0J3503D01*
G01X322838Y1324040D01*
X322732Y1324043D01*
X322381Y1323853D01*
G03X322276Y1323684I95J-176D01*
G02X321996Y1322431I-3465J117D01*
G03Y1322273I184J-79D01*
G02X322278Y1320905I-3185J-1370D01*
G01Y1320902D01*
G02X315344I-3467J0D01*
G01Y1320905D01*
G02X315626Y1322273I3467J-2D01*
G03Y1322431I-184J79D01*
G02X315390Y1323233I3184J1373D01*
G02X315247Y1323230I-144J3465D01*
G02X314098Y1323426I0J3468D01*
G03X313966I-66J-189D01*
G02X312817Y1323230I-1149J3272D01*
G02Y1330166I0J3468D01*
G02X313966Y1329970I0J-3468D01*
G03X314098I66J189D01*
G02X315247Y1330166I1149J-3272D01*
G02X316396Y1329970I0J-3468D01*
G03X316528I66J189D01*
G02X316939Y1330086I1146J-3273D01*
G02X316938Y1330131I3501J100D01*
G01Y1330135D01*
G37*
G36*
G01X1291376Y1330146D02*
G02X1292525Y1329951I3J-3467D01*
G03X1292657I66J189D01*
G02X1293068Y1330067I1146J-3273D01*
G01Y1330114D01*
G02X1293348Y1331486I3502J0D01*
G03Y1331642I-184J78D01*
G02X1293068Y1333013I3222J1372D01*
G01Y1333014D01*
G02X1296570Y1336516I3502J0D01*
G01X1296571D01*
G02X1298741Y1335762I-1J-3502D01*
G03X1298972Y1335750I124J157D01*
G02X1300833Y1336286I1862J-2967D01*
G01X1300836D01*
G02X1304338Y1332784I0J-3502D01*
G01Y1332783D01*
G02X1304058Y1331412I-3502J1D01*
G03Y1331256I184J-78D01*
G02X1304338Y1329884I-3222J-1372D01*
G02X1304058Y1328512I-3502J0D01*
G03Y1328356I184J-78D01*
G02X1304338Y1326985I-3222J-1372D01*
G01Y1326984D01*
G02X1300836Y1323482I-3502J0D01*
G02X1299056Y1323968I0J3503D01*
G03X1298860Y1323972I-102J-172D01*
G01X1298512Y1323785D01*
X1298456Y1323697D01*
X1298453Y1323645D01*
G02X1298178Y1322462I-3497J189D01*
G03Y1322306I184J-78D01*
G02X1298458Y1320935I-3222J-1372D01*
G01Y1320934D01*
G02X1291454I-3502J0D01*
G01Y1320935D01*
G02X1291734Y1322306I3502J-1D01*
G03Y1322462I-184J78D01*
G02X1291509Y1323214I3222J1374D01*
G02X1291376Y1323212I-119J3465D01*
G02X1290227Y1323407I-3J3467D01*
G03X1290095I-66J-189D01*
G02X1288950Y1323212I-1146J3272D01*
G01X1288946D01*
G02Y1330146I0J3467D01*
G01X1288950D01*
G02X1290095Y1329951I-1J-3467D01*
G03X1290227I66J189D01*
G02X1291376Y1330146I1146J-3272D01*
G37*
G36*
G01X348151Y1330108D02*
G02X349300Y1329913I3J-3467D01*
G03X349432I66J189D01*
G02X349843Y1330029I1146J-3273D01*
G02X349842Y1330074I3501J100D01*
G01Y1330078D01*
G02X350122Y1331448I3503J-2D01*
G03Y1331604I-184J78D01*
G02X349842Y1332976I3223J1372D01*
G02X353345Y1336478I3503J-1D01*
G01X353346D01*
G02X355516Y1335724I-1J-3502D01*
G03X355747Y1335712I124J157D01*
G02X357611Y1336248I1862J-2967D01*
G02X361114Y1332746I1J-3502D01*
G02X360834Y1331374I-3503J0D01*
G03Y1331218I184J-78D01*
G02X361114Y1329846I-3223J-1372D01*
G02X360834Y1328474I-3503J0D01*
G03Y1328318I184J-78D01*
G02X361114Y1326946I-3223J-1372D01*
G02X357611Y1323444I-3503J1D01*
G01X357609D01*
G02X355729Y1323992I1J3502D01*
G01X355683Y1324021D01*
X355578Y1324026D01*
X355222Y1323842D01*
G03X355114Y1323675I92J-178D01*
G01Y1323674D01*
G02X354836Y1322471I-3463J167D01*
G03Y1322313I184J-79D01*
G02X355118Y1320945I-3185J-1370D01*
G01Y1320942D01*
G02X348184I-3467J0D01*
G01Y1320945D01*
G02X348466Y1322313I3467J-2D01*
G03Y1322471I-184J79D01*
G02X348248Y1323175I3185J1372D01*
G02X348151Y1323174I-84J3466D01*
G02X347002Y1323369I-3J3467D01*
G03X346870I-66J-189D01*
G02X345725Y1323174I-1146J3272D01*
G01X345721D01*
G02Y1330108I0J3467D01*
G01X345725D01*
G02X346870Y1329913I-1J-3467D01*
G03X347002I66J189D01*
G02X348151Y1330108I1146J-3272D01*
G37*
G36*
G01X1326252Y1331585D02*
G02X1325972Y1332957I3222J1372D01*
G02X1329474Y1336460I3502J1D01*
G02X1331645Y1335705I-1J-3503D01*
G03X1331876Y1335693I124J157D01*
G02X1333740Y1336230I1864J-2967D01*
G02X1337242Y1332727I-1J-3503D01*
G01Y1332726D01*
G02X1336962Y1331355I-3502J1D01*
G03Y1331199I184J-78D01*
G02X1337242Y1329827I-3222J-1372D01*
G02X1336962Y1328455I-3502J0D01*
G03Y1328299I184J-78D01*
G02X1337242Y1326927I-3222J-1372D01*
G02X1333740Y1323424I-3502J-1D01*
G02X1331971Y1323904I1J3503D01*
G01X1331926Y1323930D01*
X1331823Y1323932D01*
X1331476Y1323750D01*
G03X1331370Y1323587I94J-177D01*
G02X1331099Y1322462I-3494J247D01*
G03X1331098Y1322306I184J-79D01*
G02X1331378Y1320935I-3222J-1372D01*
G01Y1320934D01*
G02X1324374I-3502J0D01*
G01Y1320935D01*
G02X1324654Y1322306I3502J-1D01*
G03X1324653Y1322462I-185J77D01*
G02X1324439Y1323158I3223J1372D01*
G02X1324280Y1323154I-167J3464D01*
G02X1323131Y1323350I0J3468D01*
G03X1322999I-66J-189D01*
G02X1321850Y1323154I-1149J3272D01*
G02Y1330090I0J3468D01*
G02X1322999Y1329894I0J-3468D01*
G03X1323131I66J189D01*
G02X1324280Y1330090I1149J-3272D01*
G02X1325429Y1329894I0J-3468D01*
G03X1325561I66J189D01*
G02X1325972Y1330010I1146J-3273D01*
G01Y1330057D01*
G02X1326252Y1331429I3502J0D01*
G03Y1331585I-184J78D01*
G37*
G36*
G01X1521562Y714544D02*
G02X1521842Y715916I3502J0D01*
G03Y716072I-184J78D01*
G02X1521562Y717443I3222J1372D01*
G01Y717444D01*
G02X1528566I3502J0D01*
G01Y717443D01*
G02X1528286Y716072I-3502J1D01*
G03X1528287Y715916I185J-77D01*
G02X1528506Y715190I-3224J-1369D01*
G03X1528662Y715031I197J37D01*
G02X1529106Y714908I-702J-3396D01*
G03X1529238I66J189D01*
G02X1530387Y715104I1149J-3272D01*
G02Y708168I0J-3468D01*
G02X1529238Y708364I0J3468D01*
G03X1529106I-66J-189D01*
G02X1527957Y708168I-1149J3272D01*
G02X1526808Y708364I0J3468D01*
G03X1526676I-66J-189D01*
G02X1526265Y708248I-1146J3273D01*
G02X1526266Y708203I-3501J-100D01*
G01Y708199D01*
G02X1525986Y706829I-3503J2D01*
G03Y706673I184J-78D01*
G02X1526266Y705301I-3223J-1372D01*
G02X1522763Y701798I-3503J0D01*
G02X1520592Y702553I1J3503D01*
G03X1520361Y702565I-124J-157D01*
G02X1518497Y702028I-1864J2967D01*
G02X1514994Y705531I0J3503D01*
G02X1515274Y706903I3503J0D01*
G03Y707059I-184J78D01*
G02X1514994Y708431I3223J1372D01*
G02X1515274Y709803I3503J0D01*
G03Y709959I-184J78D01*
G02X1514994Y711331I3223J1372D01*
G02X1518497Y714834I3503J0D01*
G02X1521298Y713434I0J-3502D01*
G03X1521415Y713359I160J120D01*
G02X1521455Y713350I-749J-3421D01*
G01X1521615Y713519D01*
G03X1521664Y713704I-146J138D01*
G02X1521562Y714544I3400J839D01*
G37*
G36*
G01X1488762D02*
G02X1489042Y715916I3502J0D01*
G03Y716072I-184J78D01*
G02X1488762Y717443I3222J1372D01*
G01Y717444D01*
G02X1495766I3502J0D01*
G01Y717443D01*
G02X1495486Y716072I-3502J1D01*
G03X1495487Y715916I185J-77D01*
G02X1495706Y715190I-3224J-1369D01*
G03X1495862Y715031I197J37D01*
G02X1496306Y714908I-702J-3396D01*
G03X1496438I66J189D01*
G02X1497587Y715104I1149J-3272D01*
G02Y708168I0J-3468D01*
G02X1496438Y708364I0J3468D01*
G03X1496306I-66J-189D01*
G02X1495157Y708168I-1149J3272D01*
G02X1494008Y708364I0J3468D01*
G03X1493876I-66J-189D01*
G02X1493465Y708248I-1146J3273D01*
G02X1493466Y708203I-3501J-100D01*
G01Y708199D01*
G02X1493186Y706829I-3503J2D01*
G03Y706673I184J-78D01*
G02X1493466Y705301I-3223J-1372D01*
G02X1489963Y701798I-3503J0D01*
G02X1487792Y702553I1J3503D01*
G03X1487561Y702565I-124J-157D01*
G02X1485697Y702028I-1864J2967D01*
G02X1482194Y705531I0J3503D01*
G02X1482474Y706903I3503J0D01*
G03Y707059I-184J78D01*
G02X1482194Y708431I3223J1372D01*
G02X1482474Y709803I3503J0D01*
G03Y709959I-184J78D01*
G02X1482194Y711331I3223J1372D01*
G02X1485697Y714834I3503J0D01*
G02X1488498Y713434I0J-3502D01*
G03X1488615Y713359I160J120D01*
G02X1488655Y713350I-749J-3421D01*
G01X1488815Y713519D01*
G03X1488864Y713704I-146J138D01*
G02X1488762Y714544I3400J839D01*
G37*
G36*
G01X312410Y714500D02*
G02X312690Y715872I3502J0D01*
G03Y716028I-184J78D01*
G02X312410Y717399I3222J1372D01*
G01Y717400D01*
G02X319414I3502J0D01*
G01Y717399D01*
G02X319134Y716028I-3502J1D01*
G03X319135Y715872I185J-77D01*
G02X319346Y715189I-3224J-1370D01*
G03X319502Y715033I196J40D01*
G02X319954Y714908I-696J-3397D01*
G03X320086I66J189D01*
G02X321235Y715104I1149J-3272D01*
G02Y708168I0J-3468D01*
G02X320086Y708364I0J3468D01*
G03X319954I-66J-189D01*
G02X318805Y708168I-1149J3272D01*
G02X317656Y708364I0J3468D01*
G03X317524I-66J-189D01*
G02X317113Y708248I-1146J3273D01*
G02X317114Y708203I-3501J-100D01*
G01Y708199D01*
G02X316834Y706829I-3503J2D01*
G03Y706673I184J-78D01*
G02X317114Y705301I-3223J-1372D01*
G02X316143Y702881I-3503J1D01*
G03X316089Y702719I144J-138D01*
G02X316114Y702301I-3478J-418D01*
G02X313343Y698876I-3502J0D01*
G03X313226Y698802I42J-196D01*
G02X310445Y697428I-2782J2129D01*
G02X306942Y700931I0J3503D01*
G02X307243Y702350I3503J-2D01*
G03Y702512I-183J81D01*
G02X306942Y703931I3202J1421D01*
G02X307913Y706351I3503J-1D01*
G03X307967Y706513I-144J138D01*
G02X307942Y706931I3478J418D01*
G02X308292Y708456I3503J-1D01*
G03X308297Y708618I-180J87D01*
G02X308042Y709931I3248J1312D01*
G02X311545Y713434I3503J0D01*
G02X312019Y713401I-6J-3503D01*
G01X312067Y713394D01*
X312157Y713426D01*
X312415Y713696D01*
G03X312467Y713869I-145J138D01*
G01Y713870D01*
G02X312410Y714500I3445J629D01*
G37*
G36*
G01X1455274Y714194D02*
G02X1455554Y715566I3503J0D01*
G03Y715722I-184J78D01*
G02X1455274Y717094I3223J1372D01*
G02X1462280I3503J0D01*
G02X1462000Y715723I-3503J1D01*
G03Y715566I184J-78D01*
G02X1462059Y715418I-3223J-1371D01*
G03X1462235Y715288I188J70D01*
G02X1463194Y715098I-188J-3462D01*
G03X1463326I66J189D01*
G02X1464475Y715294I1149J-3272D01*
G02Y708358I0J-3468D01*
G02X1463326Y708554I0J3468D01*
G03X1463194I-66J-189D01*
G02X1462045Y708358I-1149J3272D01*
G02X1460896Y708554I0J3468D01*
G03X1460764I-66J-189D01*
G02X1460530Y708481I-1149J3272D01*
G03X1460383Y708283I53J-193D01*
G02X1460384Y708201I-3502J-84D01*
G02X1460104Y706829I-3503J0D01*
G03Y706673I184J-78D01*
G02X1460384Y705301I-3223J-1372D01*
G02X1458218Y702064I-3502J0D01*
G03X1458101Y701828I76J-185D01*
G02X1458218Y700932I-3386J-898D01*
G01Y700931D01*
G02X1451212I-3503J0D01*
G02X1451371Y701972I3503J-2D01*
G03X1451362Y702115I-191J60D01*
G01X1451313Y702222D01*
G03X1451211Y702323I-182J-82D01*
G02X1449112Y705531I1403J3209D01*
G02X1451314Y708783I3502J0D01*
G03X1451433Y709021I-74J186D01*
G02X1451312Y709931I3382J913D01*
G02X1454814Y713434I3503J0D01*
G01X1454816D01*
G02X1454883Y713433I-19J-3503D01*
G01X1454926Y713432D01*
X1455005Y713465D01*
X1455237Y713716D01*
G03X1455290Y713870I-146J136D01*
G02X1455274Y714194I3486J335D01*
G37*
G36*
G01X378310Y714157D02*
Y714161D01*
G02X378590Y715532I3502J-1D01*
G03Y715688I-184J78D01*
G02X378310Y717059I3222J1372D01*
G01Y717060D01*
G02X385314I3502J0D01*
G01Y717059D01*
G02X385034Y715688I-3502J1D01*
G03Y715532I184J-78D01*
G02X385207Y715020I-3221J-1374D01*
G03X385374Y714871I194J49D01*
G02X386054Y714708I-464J-3436D01*
G03X386186I66J189D01*
G02X387335Y714904I1149J-3272D01*
G02Y707968I0J-3468D01*
G02X386186Y708164I0J3468D01*
G03X386054I-66J-189D01*
G02X384905Y707968I-1149J3272D01*
G02X383756Y708164I0J3468D01*
G03X383624I-66J-189D01*
G02X383213Y708048I-1146J3273D01*
G02X383214Y708003I-3501J-100D01*
G01Y707999D01*
G02X382934Y706629I-3503J2D01*
G03Y706473I184J-78D01*
G02X383214Y705101I-3223J-1372D01*
G02X379711Y701598I-3503J0D01*
G02X377540Y702353I1J3503D01*
G03X377309Y702365I-124J-157D01*
G02X375445Y701828I-1864J2967D01*
G02X371942Y705331I0J3503D01*
G02X372222Y706703I3503J0D01*
G03Y706859I-184J78D01*
G02X371942Y708231I3223J1372D01*
G02X372222Y709603I3503J0D01*
G03Y709759I-184J78D01*
G02X371942Y711131I3223J1372D01*
G02X375445Y714634I3503J0D01*
G02X377657Y713847I0J-3502D01*
G01X377702Y713810D01*
X377816Y713796D01*
X378196Y713977D01*
G03X378310Y714157I-86J181D01*
G37*
G36*
G01X345172Y715688D02*
G02X344892Y717060I3223J1372D01*
G02X351898I3503J0D01*
G02X351618Y715688I-3503J0D01*
G03Y715532I184J-78D01*
G02X351832Y714835I-3223J-1371D01*
G02X351862Y714836I130J-3464D01*
G01X351868D01*
G02X353014Y714640I-3J-3468D01*
G03X353146I66J189D01*
G02X354295Y714836I1149J-3272D01*
G02Y707900I0J-3468D01*
G02X353146Y708096I0J3468D01*
G03X353014I-66J-189D01*
G02X351865Y707900I-1149J3272D01*
G02X350716Y708096I0J3468D01*
G03X350584I-66J-189D01*
G02X350173Y707980I-1146J3273D01*
G02X350174Y707935I-3501J-100D01*
G01Y707931D01*
G02X349894Y706561I-3503J2D01*
G03Y706405I184J-78D01*
G02X350174Y705033I-3223J-1372D01*
G02X346671Y701530I-3503J0D01*
G02X344500Y702285I1J3503D01*
G03X344269Y702297I-124J-157D01*
G02X342405Y701760I-1864J2967D01*
G02X338902Y705263I0J3503D01*
G02X339182Y706635I3503J0D01*
G03Y706791I-184J78D01*
G02X338902Y708163I3223J1372D01*
G02X339182Y709535I3503J0D01*
G03Y709691I-184J78D01*
G02X338902Y711063I3223J1372D01*
G02X342405Y714566I3503J0D01*
G02X344283Y714019I-2J-3503D01*
G01X344328Y713990D01*
X344434Y713986D01*
X344789Y714169D01*
G03X344897Y714337I-92J178D01*
G02X345172Y715532I3498J-176D01*
G03Y715688I-184J78D01*
G37*
G36*
G01X411210Y696540D02*
G02X411490Y697912I3502J0D01*
G03Y698068I-184J78D01*
G02X411210Y699439I3222J1372D01*
G01Y699440D01*
G02X418214I3502J0D01*
G01Y699439D01*
G02X417934Y698068I-3502J1D01*
G03X417935Y697912I185J-77D01*
G02X418145Y697237I-3223J-1373D01*
G03X418317Y697079I196J40D01*
G02X419054Y696908I-411J-3443D01*
G03X419186I66J189D01*
G02X420335Y697104I1149J-3272D01*
G02Y690168I0J-3468D01*
G02X419186Y690364I0J3468D01*
G03X419054I-66J-189D01*
G02X417905Y690168I-1149J3272D01*
G02X416756Y690364I0J3468D01*
G03X416624I-66J-189D01*
G02X416213Y690248I-1146J3273D01*
G02X416214Y690203I-3501J-100D01*
G01Y690199D01*
G02X415934Y688829I-3503J2D01*
G03Y688673I184J-78D01*
G02X416214Y687301I-3223J-1372D01*
G02X412711Y683798I-3503J0D01*
G02X410540Y684553I1J3503D01*
G03X410309Y684565I-124J-157D01*
G02X408445Y684028I-1864J2967D01*
G02X404942Y687531I0J3503D01*
G02X405222Y688903I3503J0D01*
G03Y689059I-184J78D01*
G02X404942Y690431I3223J1372D01*
G02X405222Y691803I3503J0D01*
G03Y691959I-184J78D01*
G02X404942Y693331I3223J1372D01*
G02X408445Y696834I3503J0D01*
G02X410567Y696116I-3J-3502D01*
G01X410569D01*
Y696115D01*
G03X410780Y696097I120J160D01*
G01X411102Y696262D01*
G03X411211Y696445I-91J178D01*
G02X411210Y696540I3501J84D01*
G37*
G36*
G01X1429187Y688892D02*
G02X1428038Y689087I-3J3467D01*
G03X1427906I-66J-189D01*
G02X1427612Y688998I-1151J3271D01*
G03X1427461Y688794I49J-194D01*
G02X1427466Y688624I-3497J-188D01*
G02X1427186Y687252I-3503J0D01*
G03Y687096I184J-78D01*
G02X1427466Y685724I-3223J-1372D01*
G02X1423963Y682222I-3503J1D01*
G01X1423962D01*
G02X1421792Y682976I1J3502D01*
G03X1421561Y682988I-124J-157D01*
G02X1419697Y682452I-1862J2967D01*
G02X1416194Y685954I-1J3502D01*
G02X1416474Y687326I3503J0D01*
G03Y687482I-184J78D01*
G02X1416194Y688854I3223J1372D01*
G02X1416474Y690226I3503J0D01*
G03Y690382I-184J78D01*
G02X1416194Y691754I3223J1372D01*
G02X1419697Y695256I3503J-1D01*
G02X1422498Y693857I0J-3504D01*
G03X1422615Y693782I160J120D01*
G02X1422652Y693774I-722J-3427D01*
G01X1422812Y693943D01*
G03X1422861Y694127I-145J137D01*
G02X1422762Y694954I3405J827D01*
G01Y694955D01*
G02X1423042Y696326I3502J-1D01*
G03Y696482I-184J78D01*
G02X1422762Y697853I3222J1372D01*
G01Y697854D01*
G02X1429766I3502J0D01*
G01Y697853D01*
G02X1429486Y696482I-3502J1D01*
G03Y696326I184J-78D01*
G02X1429631Y695916I-3223J-1370D01*
G03X1429789Y695773I193J54D01*
G02X1430336Y695631I-595J-3416D01*
G03X1430468I66J189D01*
G02X1431613Y695826I1146J-3272D01*
G01X1431617D01*
G02Y688892I0J-3467D01*
G01X1431613D01*
G02X1430468Y689087I1J3467D01*
G03X1430336I-66J-189D01*
G02X1429187Y688892I-1146J3272D01*
G37*
G36*
G01X286035Y688026D02*
G02X284886Y688221I-3J3467D01*
G03X284754I-66J-189D01*
G02X284343Y688105I-1146J3273D01*
G02X284344Y688052I-3501J-93D01*
G01Y688050D01*
G02X284064Y686679I-3503J1D01*
G03Y686523I184J-78D01*
G02X284344Y685151I-3223J-1372D01*
G02X280841Y681648I-3503J0D01*
G02X278670Y682403I1J3503D01*
G03X278439Y682415I-124J-157D01*
G02X276575Y681878I-1864J2967D01*
G02X273072Y685381I0J3503D01*
G02X273352Y686753I3503J0D01*
G03Y686909I-184J78D01*
G02X273072Y688281I3223J1372D01*
G02X273352Y689653I3503J0D01*
G03Y689809I-184J78D01*
G02X273072Y691181I3223J1372D01*
G02X276575Y694684I3503J0D01*
G02X278885Y693814I0J-3502D01*
G01X278930Y693774D01*
X279050Y693758D01*
X279437Y693949D01*
G03X279548Y694142I-88J179D01*
G02X279540Y694380I3494J237D01*
G02X279820Y695752I3502J0D01*
G03Y695908I-184J78D01*
G02X279540Y697279I3222J1372D01*
G01Y697280D01*
G02X286544I3502J0D01*
G01Y697279D01*
G02X286264Y695908I-3502J1D01*
G03Y695752I184J-78D01*
G02X286477Y695066I-3221J-1376D01*
G03X286638Y694908I196J39D01*
G02X287184Y694765I-603J-3415D01*
G03X287316I66J189D01*
G02X288461Y694960I1146J-3272D01*
G01X288465D01*
G02Y688026I0J-3467D01*
G01X288461D01*
G02X287316Y688221I1J3467D01*
G03X287184I-66J-189D01*
G02X286035Y688026I-1146J3272D01*
G37*
G36*
G01X1554692Y692501D02*
G02X1554992Y693920I3502J1D01*
G03Y694082I-183J81D01*
G02X1554692Y695499I3202J1418D01*
G01Y695501D01*
G02X1561696I3502J0D01*
G01Y695499D01*
G02X1561396Y694082I-3502J1D01*
G03Y693920I183J-81D01*
G02X1561616Y693249I-3201J-1421D01*
G03X1561772Y693095I196J42D01*
G02X1562236Y692968I-681J-3400D01*
G03X1562368I66J189D01*
G02X1563517Y693164I1149J-3272D01*
G02Y686228I0J-3468D01*
G02X1562368Y686424I0J3468D01*
G03X1562236I-66J-189D01*
G02X1561087Y686228I-1149J3272D01*
G02X1559938Y686424I0J3468D01*
G03X1559806I-66J-189D01*
G02X1559395Y686308I-1146J3273D01*
G02X1559396Y686263I-3501J-100D01*
G01Y686259D01*
G02X1559116Y684889I-3503J2D01*
G03Y684733I184J-78D01*
G02X1559396Y683361I-3223J-1372D01*
G02X1559161Y682101I-3503J1D01*
G03X1559168Y681940I186J-73D01*
G02X1559530Y680391I-3141J-1551D01*
G02X1556581Y676933I-3502J0D01*
G03X1556453Y676856I32J-198D01*
G02X1553657Y675462I-2797J2109D01*
G02X1550154Y678965I0J3503D01*
G02X1550455Y680384I3503J-2D01*
G03Y680546I-183J81D01*
G02X1550154Y681965I3202J1421D01*
G02X1550494Y683470I3503J0D01*
G03X1550498Y683634I-180J86D01*
G02X1550224Y684991I3229J1358D01*
G02X1550574Y686516I3503J-1D01*
G03X1550579Y686678I-180J87D01*
G02X1550324Y687991I3248J1312D01*
G02X1554292Y691463I3503J0D01*
G01X1554340Y691456D01*
X1554429Y691487D01*
X1554686Y691752D01*
G03X1554739Y691925I-144J139D01*
G02X1554692Y692501I3455J572D01*
G37*
G36*
G01X443990Y673168D02*
G02X443710Y674539I3222J1372D01*
G01Y674540D01*
G02X450714I3502J0D01*
G01Y674539D01*
G02X450434Y673168I-3502J1D01*
G03X450435Y673012I185J-77D01*
G02X450575Y672618I-3225J-1368D01*
G03X450742Y672476I192J56D01*
G02X451454Y672308I-436J-3440D01*
G03X451586I66J189D01*
G02X452735Y672504I1149J-3272D01*
G02Y665568I0J-3468D01*
G02X451586Y665764I0J3468D01*
G03X451454I-66J-189D01*
G02X450305Y665568I-1149J3272D01*
G02X449156Y665764I0J3468D01*
G03X449024I-66J-189D01*
G02X448613Y665648I-1146J3273D01*
G02X448614Y665603I-3501J-100D01*
G01Y665599D01*
G02X448334Y664229I-3503J2D01*
G03Y664073I184J-78D01*
G02X448614Y662701I-3223J-1372D01*
G02X445111Y659198I-3503J0D01*
G02X442940Y659953I1J3503D01*
G03X442709Y659965I-124J-157D01*
G02X440845Y659428I-1864J2967D01*
G02X437342Y662931I0J3503D01*
G02X437622Y664303I3503J0D01*
G03Y664459I-184J78D01*
G02X437342Y665831I3223J1372D01*
G02X437622Y667203I3503J0D01*
G03Y667359I-184J78D01*
G02X437342Y668731I3223J1372D01*
G02X440845Y672234I3503J0D01*
G02X443057Y671445I-2J-3502D01*
G01X443059D01*
Y671444D01*
G03X443267Y671418I125J156D01*
G01X443594Y671567D01*
G03X443711Y671743I-83J182D01*
G01Y671744D01*
G02X443990Y673012I3501J-106D01*
G03Y673168I-184J78D01*
G37*
G36*
G01X1396557Y656012D02*
G02X1395408Y656207I-3J3467D01*
G03X1395276I-66J-189D01*
G02X1394865Y656091I-1146J3273D01*
G02X1394866Y656046I-3501J-100D01*
G01Y656042D01*
G02X1394586Y654672I-3503J2D01*
G03Y654516I184J-78D01*
G02X1394866Y653144I-3223J-1372D01*
G02X1391363Y649642I-3503J1D01*
G01X1391362D01*
G02X1389192Y650396I1J3502D01*
G03X1388961Y650408I-124J-157D01*
G02X1387097Y649872I-1862J2967D01*
G02X1383594Y653374I-1J3502D01*
G02X1383874Y654746I3503J0D01*
G03Y654902I-184J78D01*
G02X1383594Y656274I3223J1372D01*
G02X1383874Y657646I3503J0D01*
G03Y657802I-184J78D01*
G02X1383594Y659174I3223J1372D01*
G02X1387097Y662676I3503J-1D01*
G02X1389897Y661278I0J-3503D01*
G03X1390016Y661202I160J120D01*
G02X1390055Y661194I-684J-3435D01*
G01X1390214Y661362D01*
G03X1390263Y661547I-145J138D01*
G02X1390162Y662384I3401J835D01*
G02X1390442Y663756I3502J0D01*
G03Y663912I-184J78D01*
G02X1390162Y665283I3222J1372D01*
G01Y665284D01*
G02X1397166I3502J0D01*
G01Y665283D01*
G02X1396886Y663912I-3502J1D01*
G03Y663756I184J-78D01*
G02X1397105Y663033I-3223J-1371D01*
G03X1397261Y662874I197J37D01*
G02X1397706Y662751I-699J-3396D01*
G03X1397838I66J189D01*
G02X1398983Y662946I1146J-3272D01*
G01X1398987D01*
G02Y656012I0J-3467D01*
G01X1398983D01*
G02X1397838Y656207I1J3467D01*
G03X1397706I-66J-189D01*
G02X1396557Y656012I-1146J3272D01*
G37*
G36*
G01X253305Y653778D02*
G02X252156Y653973I-3J3467D01*
G03X252024I-66J-189D01*
G02X251613Y653857I-1146J3273D01*
G02X251614Y653812I-3501J-100D01*
G01Y653808D01*
G02X251334Y652438I-3503J2D01*
G03Y652282I184J-78D01*
G02X251614Y650910I-3223J-1372D01*
G02X248111Y647408I-3503J1D01*
G01X248110D01*
G02X245940Y648162I1J3502D01*
G03X245709Y648174I-124J-157D01*
G02X243845Y647638I-1862J2967D01*
G02X240342Y651140I-1J3502D01*
G02X240622Y652512I3503J0D01*
G03Y652668I-184J78D01*
G02X240342Y654040I3223J1372D01*
G02X240622Y655412I3503J0D01*
G03Y655568I-184J78D01*
G02X240342Y656940I3223J1372D01*
G02X243845Y660442I3503J-1D01*
G01X243846D01*
G02X246158Y659570I0J-3502D01*
G01X246204Y659529D01*
X246324Y659514D01*
X246711Y659708D01*
G03X246821Y659902I-89J179D01*
G02X246810Y660180I3491J277D01*
G02X247090Y661552I3502J0D01*
G03Y661708I-184J78D01*
G02X246810Y663079I3222J1372D01*
G01Y663080D01*
G02X253814I3502J0D01*
G01Y663079D01*
G02X253534Y661708I-3502J1D01*
G03X253535Y661552I185J-77D01*
G02X253756Y660818I-3223J-1371D01*
G03X253917Y660658I197J37D01*
G02X254454Y660517I-609J-3414D01*
G03X254586I66J189D01*
G02X255731Y660712I1146J-3272D01*
G01X255735D01*
G02Y653778I0J-3467D01*
G01X255731D01*
G02X254586Y653973I1J3467D01*
G03X254454I-66J-189D01*
G02X253305Y653778I-1146J3272D01*
G37*
G36*
G01X1593857Y652460D02*
G02X1592708Y652655I-3J3467D01*
G03X1592576I-66J-189D01*
G02X1592165Y652539I-1146J3273D01*
G02X1592166Y652494I-3501J-100D01*
G01Y652490D01*
G02X1591886Y651120I-3503J2D01*
G03Y650964I184J-78D01*
G02X1592166Y649592I-3223J-1372D01*
G02X1588663Y646090I-3503J1D01*
G01X1588662D01*
G02X1586492Y646844I1J3502D01*
G03X1586261Y646856I-124J-157D01*
G02X1584397Y646320I-1862J2967D01*
G02X1580894Y649822I-1J3502D01*
G02X1581174Y651194I3503J0D01*
G03Y651350I-184J78D01*
G02X1580894Y652722I3223J1372D01*
G02X1581174Y654094I3503J0D01*
G03Y654250I-184J78D01*
G02X1580894Y655622I3223J1372D01*
G02X1584397Y659124I3503J-1D01*
G02X1587198Y657726I1J-3504D01*
G03X1587316Y657650I160J119D01*
G02X1587330Y657647I-727J-3426D01*
G01X1587490Y657813D01*
G03X1587542Y657994I-143J139D01*
G02X1587462Y658741I3422J744D01*
G02X1587762Y660160I3502J1D01*
G03Y660322I-183J81D01*
G02X1587462Y661739I3202J1418D01*
G01Y661741D01*
G02X1594466I3502J0D01*
G01Y661739D01*
G02X1594166Y660322I-3502J1D01*
G03Y660160I183J-81D01*
G02X1594387Y659480I-3203J-1417D01*
G03X1594543Y659326I196J42D01*
G02X1595006Y659199I-684J-3400D01*
G03X1595138I66J189D01*
G02X1596283Y659394I1146J-3272D01*
G01X1596287D01*
G02Y652460I0J-3467D01*
G01X1596283D01*
G02X1595138Y652655I1J3467D01*
G03X1595006I-66J-189D01*
G02X1593857Y652460I-1146J3272D01*
G37*
G36*
G01X1454046Y653872D02*
G02X1455229Y653667I2J-3502D01*
G03X1455363I67J188D01*
G02X1456546Y653872I1181J-3297D01*
G02X1457918Y653592I0J-3502D01*
G03X1458074I78J184D01*
G02X1459445Y653872I1372J-3222D01*
G01X1459446D01*
G02X1462948Y650370I0J-3502D01*
G01Y650365D01*
G02X1462701Y649077I-3502J4D01*
G03X1462699Y648936I186J-73D01*
G02X1462898Y647770I-3303J-1164D01*
G02X1462693Y646587I-3502J-2D01*
G03Y646453I188J-67D01*
G02X1462898Y645273I-3297J-1181D01*
G01Y645270D01*
G02X1459396Y641768I-3502J0D01*
G01X1459395D01*
G02X1458024Y642048I1J3502D01*
G03X1457868I-78J-184D01*
G02X1456496Y641768I-1372J3222D01*
G02X1455313Y641973I-2J3502D01*
G03X1455179I-67J-188D01*
G02X1453996Y641768I-1181J3297D01*
G02X1452813Y641973I-2J3502D01*
G03X1452679I-67J-188D01*
G02X1451496Y641768I-1181J3297D01*
G02X1450313Y641973I-2J3502D01*
G03X1450179I-67J-188D01*
G02X1448996Y641768I-1181J3297D01*
G02X1447757Y641994I-1J3502D01*
G03X1447615I-71J-187D01*
G02X1446376Y641768I-1238J3276D01*
G02X1445193Y641973I-2J3502D01*
G03X1445059I-67J-188D01*
G02X1443879Y641768I-1181J3297D01*
G01X1443876D01*
G02X1440374Y645270I0J3502D01*
G01Y645273D01*
G02X1440579Y646453I3502J-1D01*
G03Y646587I-188J67D01*
G02X1440374Y647770I3297J1181D01*
G02X1440621Y649063I3502J1D01*
G03X1440623Y649204I-186J73D01*
G02X1440424Y650366I3303J1164D01*
G01Y650370D01*
G02X1443926Y653872I3502J0D01*
G01X1443929D01*
G02X1445109Y653667I-1J-3502D01*
G03X1445243I67J188D01*
G02X1446426Y653872I1181J-3297D01*
G02X1447665Y653646I1J-3502D01*
G03X1447807I71J187D01*
G02X1449046Y653872I1238J-3276D01*
G02X1450229Y653667I2J-3502D01*
G03X1450363I67J188D01*
G02X1451546Y653872I1181J-3297D01*
G02X1452729Y653667I2J-3502D01*
G03X1452863I67J188D01*
G02X1454046Y653872I1181J-3297D01*
G37*
G36*
G01X476590Y646768D02*
G02X476310Y648139I3222J1372D01*
G01Y648140D01*
G02X483314I3502J0D01*
G01Y648139D01*
G02X483034Y646768I-3502J1D01*
G03X483035Y646612I185J-77D01*
G02X483202Y646120I-3224J-1369D01*
G03X483369Y645972I194J50D01*
G02X484054Y645808I-461J-3437D01*
G03X484186I66J189D01*
G02X485335Y646004I1149J-3272D01*
G02Y639068I0J-3468D01*
G02X484186Y639264I0J3468D01*
G03X484054I-66J-189D01*
G02X482905Y639068I-1149J3272D01*
G02X481756Y639264I0J3468D01*
G03X481624I-66J-189D01*
G02X481213Y639148I-1146J3273D01*
G02X481214Y639103I-3501J-100D01*
G01Y639099D01*
G02X480934Y637729I-3503J2D01*
G03Y637573I184J-78D01*
G02X481214Y636201I-3223J-1372D01*
G02X477711Y632698I-3503J0D01*
G02X475540Y633453I1J3503D01*
G03X475309Y633465I-124J-157D01*
G02X473445Y632928I-1864J2967D01*
G02X469942Y636431I0J3503D01*
G02X470222Y637803I3503J0D01*
G03Y637959I-184J78D01*
G02X469942Y639331I3223J1372D01*
G02X470222Y640703I3503J0D01*
G03Y640859I-184J78D01*
G02X469942Y642231I3223J1372D01*
G02X473445Y645734I3503J0D01*
G02X475657Y644947I0J-3502D01*
G03X475869Y644921I127J155D01*
G01X476196Y645075D01*
G03X476310Y645255I-86J181D01*
G02X476590Y646612I3502J-15D01*
G03Y646768I-184J78D01*
G37*
G36*
G01X350095Y649556D02*
G02X351278Y649351I2J-3502D01*
G03X351412I67J188D01*
G02X352595Y649556I1181J-3297D01*
G02X353774Y649352I1J-3502D01*
G03X353915Y649354I68J188D01*
G02X355195Y649596I1279J-3260D01*
G02X358698Y646094I1J-3502D01*
G02X358517Y644986I-3502J3D01*
G03X358522Y644848I190J-62D01*
G02X358778Y643534I-3247J-1315D01*
G02X358572Y642352I-3503J2D01*
G03Y642216I188J-68D01*
G02X358778Y641034I-3297J-1184D01*
G02X355275Y637532I-3503J1D01*
G01X355272D01*
G02X354096Y637736I2J3502D01*
G03X353955Y637734I-68J-188D01*
G02X352675Y637492I-1279J3260D01*
G02X351492Y637697I-2J3502D01*
G03X351358I-67J-188D01*
G02X350175Y637492I-1181J3297D01*
G02X348992Y637697I-2J3502D01*
G03X348858I-67J-188D01*
G02X347675Y637492I-1181J3297D01*
G02X346492Y637697I-2J3502D01*
G03X346358I-67J-188D01*
G02X345175Y637492I-1181J3297D01*
G02X343992Y637697I-2J3502D01*
G03X343858I-67J-188D01*
G02X342675Y637492I-1181J3297D01*
G02X339172Y640994I-1J3502D01*
G02X339378Y642176I3503J-2D01*
G03Y642312I-188J68D01*
G02X339172Y643494I3297J1184D01*
G02X339353Y644602I3502J-3D01*
G03X339348Y644740I-190J62D01*
G02X339092Y646054I3247J1315D01*
G02X342595Y649556I3503J-1D01*
G01X342598D01*
G02X343778Y649351I-1J-3502D01*
G03X343912I67J188D01*
G02X345095Y649556I1181J-3297D01*
G02X346278Y649351I2J-3502D01*
G03X346412I67J188D01*
G02X347595Y649556I1181J-3297D01*
G02X348778Y649351I2J-3502D01*
G03X348912I67J188D01*
G02X350095Y649556I1181J-3297D01*
G37*
G36*
G01X1626857Y633460D02*
G02X1625708Y633655I-3J3467D01*
G03X1625576I-66J-189D01*
G02X1625165Y633539I-1146J3273D01*
G02X1625166Y633494I-3501J-100D01*
G01Y633490D01*
G02X1624886Y632120I-3503J2D01*
G03Y631964I184J-78D01*
G02X1625166Y630592I-3223J-1372D01*
G02X1621663Y627090I-3503J1D01*
G01X1621662D01*
G02X1619492Y627844I1J3502D01*
G03X1619261Y627856I-124J-157D01*
G02X1617397Y627320I-1862J2967D01*
G02X1613894Y630822I-1J3502D01*
G02X1614174Y632194I3503J0D01*
G03Y632350I-184J78D01*
G02X1613894Y633722I3223J1372D01*
G02X1614174Y635094I3503J0D01*
G03Y635250I-184J78D01*
G02X1613894Y636622I3223J1372D01*
G02X1617397Y640124I3503J-1D01*
G02X1620198Y638726I1J-3504D01*
G03X1620316Y638650I160J119D01*
G02X1620330Y638647I-727J-3426D01*
G01X1620490Y638813D01*
G03X1620542Y638994I-143J139D01*
G02X1620462Y639741I3422J744D01*
G02X1620762Y641160I3502J1D01*
G03Y641322I-183J81D01*
G02X1620462Y642739I3202J1418D01*
G01Y642741D01*
G02X1627466I3502J0D01*
G01Y642739D01*
G02X1627166Y641322I-3502J1D01*
G03Y641160I183J-81D01*
G02X1627387Y640480I-3203J-1417D01*
G03X1627543Y640326I196J42D01*
G02X1628006Y640199I-684J-3400D01*
G03X1628138I66J189D01*
G02X1629283Y640394I1146J-3272D01*
G01X1629287D01*
G02Y633460I0J-3467D01*
G01X1629283D01*
G02X1628138Y633655I1J3467D01*
G03X1628006I-66J-189D01*
G02X1626857Y633460I-1146J3272D01*
G37*
G36*
G01X1363857Y623112D02*
G02X1362708Y623307I-3J3467D01*
G03X1362576I-66J-189D01*
G02X1362165Y623191I-1146J3273D01*
G02X1362166Y623146I-3501J-100D01*
G01Y623142D01*
G02X1361886Y621772I-3503J2D01*
G03Y621616I184J-78D01*
G02X1362166Y620244I-3223J-1372D01*
G02X1358663Y616742I-3503J1D01*
G01X1358662D01*
G02X1356492Y617496I1J3502D01*
G03X1356261Y617508I-124J-157D01*
G02X1354397Y616972I-1862J2967D01*
G02X1350894Y620474I-1J3502D01*
G02X1351174Y621846I3503J0D01*
G03Y622002I-184J78D01*
G02X1350894Y623374I3223J1372D01*
G02X1351174Y624746I3503J0D01*
G03Y624902I-184J78D01*
G02X1350894Y626274I3223J1372D01*
G02X1354397Y629776I3503J-1D01*
G02X1357197Y628378I0J-3503D01*
G03X1357316Y628302I160J120D01*
G02X1357363Y628292I-705J-3431D01*
G01X1357522Y628461D01*
G03X1357570Y628647I-146J137D01*
G02X1357462Y629514I3394J863D01*
G02X1357742Y630886I3502J0D01*
G03Y631042I-184J78D01*
G02X1357462Y632413I3222J1372D01*
G01Y632414D01*
G02X1364466I3502J0D01*
G01Y632413D01*
G02X1364186Y631042I-3502J1D01*
G03X1364187Y630886I185J-77D01*
G02X1364411Y630133I-3224J-1369D01*
G03X1364567Y629973I197J36D01*
G02X1365006Y629851I-707J-3395D01*
G03X1365138I66J189D01*
G02X1366283Y630046I1146J-3272D01*
G01X1366287D01*
G02Y623112I0J-3467D01*
G01X1366283D01*
G02X1365138Y623307I1J3467D01*
G03X1365006I-66J-189D01*
G02X1363857Y623112I-1146J3272D01*
G37*
G36*
G01X1521274Y615618D02*
G02X1521480Y616800I3503J-2D01*
G03Y616936I-188J68D01*
G02X1521274Y618118I3297J1184D01*
G02X1524777Y621620I3503J-1D01*
G01X1524780D01*
G02X1525960Y621415I-1J-3502D01*
G03X1526094I67J188D01*
G02X1527277Y621620I1181J-3297D01*
G02X1530780Y618118I1J-3502D01*
G02X1530574Y616936I-3503J2D01*
G03Y616800I188J-68D01*
G02X1530780Y615618I-3297J-1184D01*
G02X1530569Y614421I-3503J0D01*
G03Y614285I188J-68D01*
G02X1530780Y613088I-3292J-1197D01*
G02X1530574Y611906I-3503J2D01*
G03Y611770I188J-68D01*
G02X1530780Y610588I-3297J-1184D01*
G02X1530556Y609358I-3503J2D01*
G03Y609218I188J-70D01*
G02X1530780Y607988I-3279J-1232D01*
G02X1530574Y606806I-3503J2D01*
G03Y606670I188J-68D01*
G02X1530780Y605488I-3297J-1184D01*
G02X1527277Y601986I-3503J1D01*
G01X1527274D01*
G02X1526094Y602191I1J3502D01*
G03X1525960I-67J-188D01*
G02X1524777Y601986I-1181J3297D01*
G02X1521274Y605488I-1J3502D01*
G02X1521480Y606670I3503J-2D01*
G03Y606806I-188J68D01*
G02X1521274Y607988I3297J1184D01*
G02X1521498Y609218I3503J-2D01*
G03Y609358I-188J70D01*
G02X1521274Y610588I3279J1232D01*
G02X1521480Y611770I3503J-2D01*
G03Y611906I-188J68D01*
G02X1521274Y613088I3297J1184D01*
G02X1521485Y614285I3503J0D01*
G03Y614421I-188J68D01*
G02X1521274Y615618I3292J1197D01*
G37*
G36*
G01X509790Y612568D02*
G02X509510Y613939I3222J1372D01*
G01Y613940D01*
G02X516514I3502J0D01*
G01Y613939D01*
G02X516234Y612568I-3502J1D01*
G03X516235Y612412I185J-77D01*
G02X516372Y612030I-3223J-1372D01*
G03X516544Y611887I192J56D01*
G02X517354Y611708I-338J-3451D01*
G03X517486I66J189D01*
G02X518635Y611904I1149J-3272D01*
G02Y604968I0J-3468D01*
G02X517486Y605164I0J3468D01*
G03X517354I-66J-189D01*
G02X516205Y604968I-1149J3272D01*
G02X515056Y605164I0J3468D01*
G03X514924I-66J-189D01*
G02X514513Y605048I-1146J3273D01*
G02X514514Y605003I-3501J-100D01*
G01Y604999D01*
G02X514234Y603629I-3503J2D01*
G03Y603473I184J-78D01*
G02X514514Y602101I-3223J-1372D01*
G02X511011Y598598I-3503J0D01*
G02X508840Y599353I1J3503D01*
G03X508609Y599365I-124J-157D01*
G02X506745Y598828I-1864J2967D01*
G02X503242Y602331I0J3503D01*
G02X503522Y603703I3503J0D01*
G03Y603859I-184J78D01*
G02X503242Y605231I3223J1372D01*
G02X503522Y606603I3503J0D01*
G03Y606759I-184J78D01*
G02X503242Y608131I3223J1372D01*
G02X506745Y611634I3503J0D01*
G02X508871Y610914I-1J-3503D01*
G01X508916Y610880D01*
X509025Y610868D01*
X509449Y611065D01*
X509511Y611157D01*
X509514Y611212D01*
G02X509790Y612412I3498J-173D01*
G03Y612568I-184J78D01*
G37*
G36*
G01X465331Y604516D02*
G02X466514Y604311I2J-3502D01*
G03X466648I67J188D01*
G02X467831Y604516I1181J-3297D01*
G02X469014Y604311I2J-3502D01*
G03X469148I67J188D01*
G02X470331Y604516I1181J-3297D01*
G02X473834Y601014I1J-3502D01*
G02X473628Y599832I-3503J2D01*
G03Y599696I188J-68D01*
G02X473834Y598514I-3297J-1184D01*
G02X470331Y595012I-3503J1D01*
G01X470328D01*
G02X469148Y595217I1J3502D01*
G03X469014I-67J-188D01*
G02X467831Y595012I-1181J3297D01*
G02X466648Y595217I-2J3502D01*
G03X466514I-67J-188D01*
G02X465331Y595012I-1181J3297D01*
G02X464148Y595217I-2J3502D01*
G03X464014I-67J-188D01*
G02X462831Y595012I-1181J3297D01*
G02X461592Y595238I-1J3502D01*
G03X461450I-71J-187D01*
G02X460211Y595012I-1238J3276D01*
G02X459028Y595217I-2J3502D01*
G03X458894I-67J-188D01*
G02X457711Y595012I-1181J3297D01*
G02X454208Y598514I-1J3502D01*
G02X454414Y599696I3503J-2D01*
G03Y599832I-188J68D01*
G02X454208Y601014I3297J1184D01*
G02X457711Y604516I3503J-1D01*
G01X457714D01*
G02X458894Y604311I-1J-3502D01*
G03X459028I67J188D01*
G02X460211Y604516I1181J-3297D01*
G02X461450Y604290I1J-3502D01*
G03X461592I71J187D01*
G02X462831Y604516I1238J-3276D01*
G02X464014Y604311I2J-3502D01*
G03X464148I67J188D01*
G02X465331Y604516I1181J-3297D01*
G37*
G36*
G01X981891Y205046D02*
G02X983641Y205656I1987J-2884D01*
G03X983827Y205842I-14J200D01*
G02X987321Y209102I3494J-242D01*
G02X987564Y209093I-8J-3503D01*
G03X987721Y209152I15J199D01*
G02X990221Y210202I2501J-2453D01*
G02X993724Y206699I0J-3503D01*
G02X993308Y205044I-3503J1D01*
G03Y204854I176J-95D01*
G02X993724Y203199I-3087J-1656D01*
G02X993308Y201544I-3503J1D01*
G03Y201354I176J-95D01*
G02X993724Y199699I-3087J-1656D01*
G02X990221Y196196I-3503J0D01*
G02X989978Y196205I8J3503D01*
G03X989821Y196146I-15J-199D01*
G02X989542Y195890I-2504J2449D01*
G03X989471Y195701I126J-155D01*
G02X989524Y195099I-3450J-607D01*
G02X982518I-3503J0D01*
G02X983800Y197808I3503J0D01*
G03X983871Y197997I-126J155D01*
G02X983818Y198598I3450J607D01*
G01Y198600D01*
G02X983819Y198660I3503J-28D01*
G02X982055Y199171I59J3502D01*
G03X981837Y199165I-104J-170D01*
G02X979849Y198546I-1988J2884D01*
G02X977910Y199132I1J3503D01*
G03X977688I-111J-166D01*
G02X975749Y198546I-1940J2917D01*
G02X972359Y201167I0J3503D01*
G03X972153Y201317I-194J-50D01*
G02X971943Y201310I-222J3496D01*
G02X970051Y201866I2J3503D01*
G03X969835I-108J-169D01*
G02X967943Y201310I-1894J2947D01*
G02X964686Y203525I0J3502D01*
G03X964536Y203648I-186J-74D01*
G02X963305Y205125I271J1477D01*
G02X964807Y206627I1502J0D01*
G01X964833D01*
G03X965004Y206718I3J200D01*
G02X967943Y208316I2939J-1904D01*
G02X969835Y207760I-2J-3503D01*
G03X970051I108J169D01*
G02X971943Y208316I1894J-2947D01*
G02X974028Y207627I-1J-3503D01*
G01X974059Y207604D01*
X974131Y207584D01*
X974478Y207624D01*
X974544Y207658D01*
X974569Y207687D01*
G02X977221Y208902I2652J-2287D01*
G02X980718Y205584I0J-3502D01*
G03X980860Y205403I200J11D01*
G02X981673Y205040I-1010J-3354D01*
G03X981891Y205046I104J170D01*
G37*
G36*
G01X943221Y179892D02*
G02X944403Y179686I-2J-3503D01*
G03X944539I68J188D01*
G02X945721Y179892I1184J-3297D01*
G02X946854Y179703I-2J-3503D01*
G03X946999Y179709I65J189D01*
G02X948401Y180002I1402J-3210D01*
G02X951904Y176499I0J-3503D01*
G02X949342Y173125I-3503J0D01*
G03X949197Y172957I54J-193D01*
G02X945721Y169886I-3476J432D01*
G02X944539Y170092I2J3503D01*
G03X944403I-68J-188D01*
G02X943221Y169886I-1184J3297D01*
G02X942039Y170092I2J3503D01*
G03X941903I-68J-188D01*
G02X940721Y169886I-1184J3297D01*
G02X939510Y170103I3J3503D01*
G03X939372I-69J-188D01*
G02X938161Y169886I-1214J3286D01*
G02X937002Y170084I2J3503D01*
G03X936861Y170081I-67J-189D01*
G02X935551Y169826I-1312J3248D01*
G02X932048Y173329I0J3503D01*
G02X932313Y174663I3503J-2D01*
G03X932315Y174810I-185J76D01*
G02X932088Y176049I3276J1240D01*
G02X935591Y179552I3503J0D01*
G02X936376Y179463I0J-3503D01*
G03X936515Y179481I45J195D01*
G02X938161Y179892I1646J-3091D01*
G02X939372Y179675I-3J-3503D01*
G03X939510I69J188D01*
G02X940721Y179892I1214J-3286D01*
G02X941903Y179686I-2J-3503D01*
G03X942039I68J188D01*
G02X943221Y179892I1184J-3297D01*
G37*
G36*
G01X959170Y167763D02*
G02X959376Y168945I3503J-2D01*
G03Y169081I-188J68D01*
G02X959170Y170263I3297J1184D01*
G02X966176I3503J0D01*
G02X965970Y169081I-3503J2D01*
G03Y168945I188J-68D01*
G02X966176Y167763I-3297J-1184D01*
G02X959170I-3503J0D01*
G37*
G36*
G01X975691Y157718D02*
G02Y164722I0J3502D01*
G01X975693D01*
G02X978131Y163733I-1J-3502D01*
G01X978159Y163705D01*
X978231Y163676D01*
X978548Y163675D01*
G03X978686Y163730I0J200D01*
G01X978687Y163731D01*
G02X981112Y164706I2425J-2528D01*
G02Y157702I0J-3502D01*
G01X981110D01*
G02X978672Y158691I1J3502D01*
G01X978644Y158719D01*
X978572Y158748D01*
X978255Y158749D01*
G03X978117Y158694I0J-200D01*
G01X978116Y158693D01*
G02X975691Y157718I-2425J2528D01*
G37*
G36*
G01X786322Y149471D02*
G02X783651Y146068I-3503J0D01*
G03X783507Y145933I47J-194D01*
G02X780159Y143458I-3348J1027D01*
G02X776656Y146961I0J3503D01*
G02X779327Y150364I3503J0D01*
G03X779471Y150499I-47J194D01*
G02X782819Y152974I3348J-1027D01*
G02X786322Y149471I0J-3503D01*
G37*
G36*
G01X787681Y124450D02*
G02X788863Y124244I-2J-3503D01*
G03X788999I68J188D01*
G02X790181Y124450I1184J-3297D01*
G02X791363Y124244I-2J-3503D01*
G03X791499I68J188D01*
G02X792681Y124450I1184J-3297D01*
G02Y117444I0J-3503D01*
G02X792393Y117456I2J3503D01*
G03X792191Y117331I-16J-199D01*
G02X788941Y115134I-3250J1305D01*
G02X787759Y115340I2J3503D01*
G03X787623I-68J-188D01*
G02X786441Y115134I-1184J3297D01*
G02X785259Y115340I2J3503D01*
G03X785123I-68J-188D01*
G02X783941Y115134I-1184J3297D01*
G02X782759Y115340I2J3503D01*
G03X782623I-68J-188D01*
G02X781441Y115134I-1184J3297D01*
G02Y122140I0J3503D01*
G02X781729Y122128I-2J-3503D01*
G03X781931Y122253I16J199D01*
G02X785181Y124450I3250J-1305D01*
G02X786363Y124244I-2J-3503D01*
G03X786499I68J188D01*
G02X787681Y124450I1184J-3297D01*
G37*
G36*
G01X694221Y108364D02*
X694223D01*
G02X695877Y107949I0J-3502D01*
G03X696065I94J176D01*
G02X697721Y108364I1654J-3087D01*
G02X699377Y107949I2J-3502D01*
G03X699565I94J176D01*
G02X701219Y108364I1654J-3087D01*
G01X701221D01*
G02X704713Y105131I0J-3502D01*
G03X704794Y104985I200J15D01*
G02X705722Y103968I-2073J-2823D01*
G03X705938Y103876I171J103D01*
G02X706716Y103964I780J-3414D01*
G01X706721D01*
G02Y96960I0J-3502D01*
G02X703720Y98656I0J3503D01*
G03X703504Y98748I-171J-103D01*
G02X702721Y98660I-780J3414D01*
G02X701065Y99075I-2J3502D01*
G03X700877I-94J-176D01*
G02X699221Y98660I-1654J3087D01*
G02X697565Y99075I-2J3502D01*
G03X697377I-94J-176D01*
G02X695723Y98660I-1654J3087D01*
G01X695721D01*
G02X692229Y101893I0J3502D01*
G03X692148Y102039I-200J-15D01*
G02X690718Y104862I2071J2823D01*
G02X694221Y108364I3503J-1D01*
G37*
G36*
G01X1736731Y105796D02*
G02X1738386Y105380I-1J-3503D01*
G03X1738576I95J176D01*
G02X1740231Y105796I1656J-3087D01*
G02X1741886Y105380I-1J-3503D01*
G03X1742076I95J176D01*
G02X1743731Y105796I1656J-3087D01*
G02X1747049Y103414I0J-3502D01*
G03X1747141Y103303I190J64D01*
G02X1748844Y101047I-1706J-3059D01*
G03X1749019Y100894I195J46D01*
G02X1752188Y97408I-333J-3486D01*
G02X1748686Y93906I-3502J0D01*
G02X1745277Y96605I0J3502D01*
G03X1745102Y96758I-195J-46D01*
G02X1743779Y97157I330J3487D01*
G03X1743591I-94J-176D01*
G02X1741935Y96742I-1654J3087D01*
G02X1740279Y97157I-2J3502D01*
G03X1740091I-94J-176D01*
G02X1738437Y96742I-1654J3087D01*
G01X1738435D01*
G02X1735117Y99123I0J3502D01*
G03X1735025Y99234I-190J-64D01*
G02X1733228Y102293I1705J3059D01*
G02X1736731Y105796I3503J0D01*
G37*
G36*
G01X261416Y104168D02*
G02X263071Y103752I-1J-3503D01*
G03X263261I95J176D01*
G02X264916Y104168I1656J-3087D01*
G02X266571Y103752I-1J-3503D01*
G03X266761I95J176D01*
G02X268416Y104168I1656J-3087D01*
G02X271908Y100934I0J-3502D01*
G03X271989Y100788I200J15D01*
G02X272651Y100153I-2073J-2823D01*
G03X272851Y100083I156J125D01*
G02X273616Y100168I767J-3418D01*
G02Y93162I0J-3503D01*
G02X270881Y94477I0J3502D01*
G03X270681Y94547I-156J-125D01*
G02X269916Y94462I-767J3418D01*
G02X268261Y94878I1J3503D01*
G03X268071I-95J-176D01*
G02X266416Y94462I-1656J3087D01*
G02X264761Y94878I1J3503D01*
G03X264571I-95J-176D01*
G02X262916Y94462I-1656J3087D01*
G02X259424Y97696I0J3502D01*
G03X259343Y97842I-200J-15D01*
G02X257914Y100665I2073J2823D01*
G02X261416Y104168I3502J1D01*
G37*
G36*
G01X746532Y89988D02*
Y89989D01*
G02X746812Y91360I3502J-1D01*
G03Y91516I-184J78D01*
G02X746532Y92887I3222J1372D01*
G01Y92888D01*
G02X753536I3502J0D01*
G01Y92887D01*
G02X753256Y91516I-3502J1D01*
G03Y91360I184J-78D01*
G02X753536Y89989I-3222J-1372D01*
G01Y89988D01*
G02X746532I-3502J0D01*
G37*
G36*
G01X693226Y81552D02*
G02X693431Y82735I3502J2D01*
G03Y82869I-188J67D01*
G02X693226Y84049I3297J1181D01*
G01Y84052D01*
G02X695374Y87282I3503J0D01*
G03X695481Y87389I-77J184D01*
G02X698711Y89538I3230J-1353D01*
G02X702214Y86035I0J-3503D01*
G02X700174Y82852I-3503J0D01*
G03X700067Y82610I84J-182D01*
G02X700230Y81556I-3339J-1056D01*
G01Y81552D01*
G02X699726Y79743I-3501J1D01*
G03X699707Y79578I171J-103D01*
G02X699874Y78512I-3336J-1069D01*
G02X692868I-3503J0D01*
G02X693373Y80321I3502J-3D01*
G03X693392Y80486I-171J103D01*
G02X693226Y81552I3336J1065D01*
G37*
G36*
G01X1734114Y79140D02*
G02X1734320Y80322I3503J-2D01*
G03Y80458I-188J68D01*
G02X1734114Y81640I3297J1184D01*
G02X1737617Y85142I3503J-1D01*
G01X1737620D01*
G02X1738824Y84928I-1J-3502D01*
G03X1739040Y84981I68J188D01*
G02X1741621Y86116I2581J-2367D01*
G02X1745124Y82613I0J-3503D01*
G02X1744918Y81431I-3503J2D01*
G03Y81295I188J-68D01*
G02X1745124Y80113I-3297J-1184D01*
G02X1744708Y78458I-3503J1D01*
G03Y78268I176J-95D01*
G02X1745124Y76613I-3087J-1656D01*
G02X1744918Y75431I-3503J2D01*
G03Y75295I188J-68D01*
G02X1745124Y74113I-3297J-1184D01*
G02X1741621Y70610I-3503J0D01*
G02X1740414Y70825I1J3503D01*
G03X1740198Y70772I-68J-188D01*
G02X1737617Y69638I-2580J2368D01*
G02X1734114Y73140I-1J3502D01*
G02X1734320Y74322I3503J-2D01*
G03Y74458I-188J68D01*
G02X1734114Y75640I3297J1184D01*
G02X1734530Y77295I3503J-1D01*
G03Y77485I-176J95D01*
G02X1734114Y79140I3087J1656D01*
G37*
G36*
G01X1454786Y76366D02*
G02Y84312I0J3973D01*
G01X1454886D01*
G02X1458808Y80389I-1J-3923D01*
G02X1454786Y76366I-4022J-1D01*
G37*
G36*
G01X259390Y77529D02*
G02X259596Y78711I3503J-2D01*
G03Y78847I-188J68D01*
G02X259390Y80029I3297J1184D01*
G02X266396I3503J0D01*
G02X266190Y78847I-3503J2D01*
G03Y78711I188J-68D01*
G02X266396Y77529I-3297J-1184D01*
G02X265926Y75777I-3503J1D01*
G03X265941Y75554I173J-100D01*
G02X266353Y74883I-2760J-2157D01*
G01Y74881D01*
G03X266515Y74768I181J86D01*
G01X266858Y74735D01*
G03X267037Y74814I19J199D01*
G01X267038Y74815D01*
G02X269860Y76244I2823J-2074D01*
G02Y69238I0J-3503D01*
G02X266689Y71254I0J3503D01*
G01Y71256D01*
G03X266527Y71369I-181J-86D01*
G01X266184Y71402D01*
G03X266005Y71323I-19J-199D01*
G01X266004Y71322D01*
G02X263182Y69894I-2822J2074D01*
G02X259680Y73396I0J3502D01*
G01Y73397D01*
G02X260149Y75148I3502J0D01*
G03X260134Y75371I-173J100D01*
G02X259390Y77529I2758J2158D01*
G37*
G36*
G01X1776242Y70073D02*
Y70074D01*
G02X1776522Y71445I3502J-1D01*
G03Y71601I-184J78D01*
G02X1776242Y72972I3222J1372D01*
G01Y72973D01*
G02X1783246I3502J0D01*
G01Y72972D01*
G02X1782966Y71601I-3502J1D01*
G03Y71445I184J-78D01*
G02X1783246Y70074I-3222J-1372D01*
G01Y70073D01*
G02X1776242I-3502J0D01*
G37*
G36*
G01X311150Y68906D02*
G02X311430Y70278I3503J0D01*
G03Y70434I-184J78D01*
G02X311150Y71806I3223J1372D01*
G02X318156I3503J0D01*
G02X317876Y70434I-3503J0D01*
G03Y70278I184J-78D01*
G02X318156Y68906I-3223J-1372D01*
G02X311150I-3503J0D01*
G37*
G36*
G01X1225541Y63504D02*
X1225441D01*
G02X1221518Y67427I0J3923D01*
G02X1225540Y71450I4023J0D01*
G01X1225541D01*
G02Y63504I0J-3973D01*
G37*
G36*
G01X306470Y61658D02*
X306466D01*
G02X305379Y61832I3J3502D01*
G03X305238Y61825I-61J-190D01*
G02X303854Y61540I-1384J3217D01*
G01X303852D01*
G02Y68544I0J3502D01*
G01X303856D01*
G02X304943Y68370I-3J-3502D01*
G03X305084Y68377I61J190D01*
G02X306468Y68662I1384J-3217D01*
G01X306470D01*
G02Y61658I0J-3502D01*
G37*
G36*
G01X757721Y68134D02*
X757724D01*
G02X758904Y67929I-1J-3502D01*
G03X759038I67J188D01*
G02X760221Y68134I1181J-3297D01*
G02X761115Y68018I0J-3502D01*
G03X761277Y68045I51J194D01*
G02X763221Y68634I1944J-2913D01*
G02X766724Y65132I1J-3502D01*
G02X766134Y63188I-3503J2D01*
G03X766107Y63026I167J-111D01*
G02X766224Y62132I-3386J-898D01*
G02X762721Y58630I-3503J1D01*
G01X762718D01*
G02X761538Y58835I1J3502D01*
G03X761404I-67J-188D01*
G02X760221Y58630I-1181J3297D01*
G02X759038Y58835I-2J3502D01*
G03X758904I-67J-188D01*
G02X757721Y58630I-1181J3297D01*
G02X754218Y62132I-1J3502D01*
G02X754424Y63314I3503J-2D01*
G03Y63450I-188J68D01*
G02X754218Y64632I3297J1184D01*
G02X757721Y68134I3503J-1D01*
G37*
G36*
G01X1770792Y60133D02*
G02X1771072Y61505I3502J0D01*
G03Y61661I-184J78D01*
G02X1770792Y63032I3222J1372D01*
G01Y63033D01*
G02X1777796I3502J0D01*
G01Y63032D01*
G02X1777516Y61661I-3502J1D01*
G03Y61505I184J-78D01*
G02X1777796Y60133I-3222J-1372D01*
G02X1777507Y58738I-3502J-2D01*
G03Y58579I183J-79D01*
G02X1777794Y57191I-3216J-1389D01*
G02X1770788I-3503J0D01*
G02X1771078Y58586I3503J-1D01*
G03X1771079Y58745I-183J81D01*
G02X1770792Y60133I3215J1388D01*
G37*
G36*
G01X1734590Y53103D02*
G02X1734796Y54285I3503J-2D01*
G03Y54421I-188J68D01*
G02X1734590Y55603I3297J1184D01*
G02X1741596I3503J0D01*
G02X1741390Y54421I-3503J2D01*
G03Y54285I188J-68D01*
G02X1741596Y53103I-3297J-1184D01*
G02X1734590I-3503J0D01*
G37*
G36*
G01X752118Y51602D02*
G02X755621Y55104I3503J-1D01*
G01X755623D01*
G02X757040Y54804I-1J-3502D01*
G03X757202I81J183D01*
G02X758621Y55104I1418J-3202D01*
G02X762124Y51602I1J-3502D01*
G02X760383Y48575I-3502J0D01*
G01X760382Y48574D01*
G03X760284Y48421I101J-173D01*
G01X760252Y48099D01*
G03X760319Y47929I199J-20D01*
G02X754928Y47567I-2516J-2851D01*
G01X754962Y47606D01*
X754984Y47707D01*
X754852Y48131D01*
X754778Y48202D01*
X754728Y48215D01*
G02X752118Y51602I893J3387D01*
G37*
G36*
G01X257516Y55068D02*
G02X259171Y54652I-1J-3503D01*
G03X259361I95J176D01*
G02X261016Y55068I1656J-3087D01*
G02X262198Y54862I-2J-3503D01*
G03X262334I68J188D01*
G02X263516Y55068I1184J-3297D01*
G02X266921Y52387I0J-3503D01*
G03X267021Y52257I195J46D01*
G02X268868Y49171I-1655J-3086D01*
G02X265365Y45668I-3503J0D01*
G02X263864Y46006I0J3503D01*
G03X263672Y45995I-86J-181D01*
G02X261816Y45462I-1857J2970D01*
G02X260634Y45668I2J3503D01*
G03X260498I-68J-188D01*
G02X259316Y45462I-1184J3297D01*
G02X257661Y45878I1J3503D01*
G03X257471I-95J-176D01*
G02X255816Y45462I-1656J3087D01*
G02X254161Y45878I1J3503D01*
G03X253971I-95J-176D01*
G02X252316Y45462I-1656J3087D01*
G02X250661Y45878I1J3503D01*
G03X250471I-95J-176D01*
G02X248816Y45462I-1656J3087D01*
G02X245314Y48965I1J3503D01*
G02X246959Y51935I3504J0D01*
G03X247051Y52075I-106J170D01*
G02X250516Y55068I3465J-509D01*
G02X252171Y54652I-1J-3503D01*
G03X252361I95J176D01*
G02X254016Y55068I1656J-3087D01*
G02X255671Y54652I-1J-3503D01*
G03X255861I95J176D01*
G02X257516Y55068I1656J-3087D01*
G37*
G36*
G01X365287Y197050D02*
X371587D01*
G02Y173422I0J-11814D01*
G01X365287D01*
G02Y197050I0J11814D01*
G37*
G36*
G01X280826Y52152D02*
X284226D01*
G02Y49146I0J-1503D01*
G01X280826D01*
G02Y52152I0J1503D01*
G37*
G36*
G01X280828Y27438D02*
X284228D01*
G02Y24432I0J-1503D01*
G01X280828D01*
G02Y27438I0J1503D01*
G37*
G36*
G01X247177Y197836D02*
X253476D01*
G02Y172636I0J-12600D01*
G01X247177D01*
G02Y197836I0J12600D01*
G37*
G36*
G01X225727Y52152D02*
X229127D01*
G02Y49146I0J-1503D01*
G01X225727D01*
G02Y52152I0J1503D01*
G37*
G36*
G01X69964Y110535D02*
X65662Y105934D01*
G02X47255Y123148I-9203J8607D01*
G01X51557Y127748D01*
G02X69964Y110535I9203J-8607D01*
G37*
G36*
G01X634794Y592006D02*
X638694D01*
G02Y589002I0J-1502D01*
G01X634794D01*
G02Y592006I0J1502D01*
G37*
G36*
G01X646358Y591818D02*
X650258D01*
G02Y588814I0J-1502D01*
G01X646358D01*
G02Y591818I0J1502D01*
G37*
G36*
G01X635567Y673276D02*
X638967D01*
G02Y670272I0J-1502D01*
G01X635567D01*
G02Y673276I0J1502D01*
G37*
G36*
G01X670613Y43966D02*
X674013D01*
G02Y40962I0J-1502D01*
G01X670613D01*
G02Y43966I0J1502D01*
G37*
G36*
G01X857187Y343712D02*
X860587D01*
G02Y340708I0J-1502D01*
G01X857187D01*
G02Y343712I0J1502D01*
G37*
G36*
G01X860942Y332360D02*
X864342D01*
G02Y329356I0J-1502D01*
G01X860942D01*
G02Y332360I0J1502D01*
G37*
G36*
G01X1700136Y52152D02*
X1703536D01*
G02Y49146I0J-1503D01*
G01X1700136D01*
G02Y52152I0J1503D01*
G37*
G36*
G01X1755238Y27980D02*
X1758638D01*
G02Y24974I0J-1503D01*
G01X1755238D01*
G02Y27980I0J1503D01*
G37*
G36*
G01X1755235Y52152D02*
X1758635D01*
G02Y49146I0J-1503D01*
G01X1755235D01*
G02Y52152I0J1503D01*
G37*
G36*
G01X873175Y748970D02*
X869275D01*
G02Y751974I0J1502D01*
G01X873175D01*
G02Y748970I0J-1502D01*
G37*
G36*
G01X1705561Y643052D02*
X1701661D01*
G02Y646056I0J1502D01*
G01X1705561D01*
G02Y643052I0J-1502D01*
G37*
G36*
G01X937341Y309612D02*
X920139D01*
G02X937341I8601J12042D01*
G37*
G36*
G01X425469Y1593930D02*
X422069D01*
G02Y1596936I0J1503D01*
G01X425469D01*
G02Y1593930I0J-1503D01*
G37*
G36*
G01X413396Y1593094D02*
G02X412333Y1593534I0J1504D01*
G01X409929Y1595939D01*
G02X412054Y1598064I1063J1062D01*
G01X414459Y1595660D01*
G02X414899Y1594597I-1064J-1063D01*
G02X413396Y1593094I-1503J0D01*
G37*
G36*
G01X1113847Y1606056D02*
X1117247D01*
G02Y1603052I0J-1502D01*
G01X1113847D01*
G02Y1606056I0J1502D01*
G37*
G36*
G01X1125784Y1664208D02*
X1129184D01*
G02Y1661202I0J-1503D01*
G01X1125784D01*
G02Y1664208I0J1503D01*
G37*
G36*
G01X417365Y1629198D02*
X420765D01*
G02Y1626192I0J-1503D01*
G01X417365D01*
G02Y1629198I0J1503D01*
G37*
G36*
G01X648314Y569666D02*
X644414D01*
G02Y572672I0J1503D01*
G01X648314D01*
G02Y569666I0J-1503D01*
G37*
G36*
G01X816152Y1720920D02*
X901868D01*
G02X902752Y1720554I0J-1251D01*
G01X906384Y1716922D01*
G02X906750Y1716038I-885J-884D01*
G01Y1662730D01*
G03X906809Y1662588I200J0D01*
G01X925253Y1644144D01*
G03X925395Y1644085I142J141D01*
G01X1071615D01*
G02X1072499Y1643719I0J-1251D01*
G01X1104694Y1611524D01*
G02X1105060Y1610640I-885J-884D01*
G01Y1568572D01*
G02X1104694Y1567688I-1251J0D01*
G01X1100947Y1563941D01*
G02X1100063Y1563575I-884J885D01*
G01X942478D01*
G02X941594Y1563941I0J1251D01*
G01X939599Y1565936D01*
G02X939233Y1566820I885J884D01*
G01Y1598397D01*
G03X939174Y1598539I-200J0D01*
G01X923618Y1614095D01*
G03X923476Y1614154I-142J-141D01*
G01X903723D01*
G02X902839Y1614520I0J1251D01*
G01X892956Y1624403D01*
G03X892814Y1624462I-142J-141D01*
G01X770835D01*
G02X769951Y1624828I0J1251D01*
G01X766466Y1628313D01*
G02X766100Y1629197I885J884D01*
G01Y1656302D01*
G02X766893Y1658211I2700J-2D01*
G01X799393Y1690712D01*
G03X799410Y1690974I-142J141D01*
G01X799171Y1691289D01*
G03X798913Y1691342I-159J-121D01*
G02X791281Y1689340I-7632J13548D01*
G01X791280D01*
G02X806830Y1704890I0J15550D01*
G01Y1704889D01*
G02X804828Y1697257I-15550J0D01*
G01X804791Y1697191D01*
X804821Y1697045D01*
X805197Y1696760D01*
G03X805459Y1696778I121J160D01*
G01X808681Y1700000D01*
G03X808740Y1700142I-141J142D01*
G01Y1713508D01*
G02X809106Y1714392I1251J0D01*
G01X815268Y1720554D01*
G02X816152Y1720920I884J-885D01*
G37*
G36*
G01X1438232Y1664144D02*
G02X1438436Y1664348I204J0D01*
G01X1457722D01*
G02X1457926Y1664144I0J-204D01*
G01Y1658386D01*
Y1658186D01*
X1457740D01*
X1457330D01*
G03X1457154Y1658008I23J-199D01*
G01Y1656632D01*
G03X1457330Y1656454I199J21D01*
G01X1457726D01*
X1457926D01*
Y1656268D01*
Y1637396D01*
G02X1457722Y1637192I-204J0D01*
G01X1438436D01*
G02X1438232Y1637396I0J204D01*
G01Y1664144D01*
G37*
G36*
G01X791296Y1359655D02*
G02X790770Y1361500I2977J1846D01*
G02X791071Y1362919I3503J-2D01*
G03Y1363081I-183J81D01*
G02X790770Y1364500I3202J1421D01*
G02X797776I3503J0D01*
G02X797475Y1363081I-3503J2D01*
G03Y1362919I183J-81D01*
G02X797776Y1361500I-3202J-1421D01*
G02X797250Y1359655I-3503J1D01*
G03Y1359445I170J-105D01*
G02X797776Y1357600I-2977J-1846D01*
G02X797475Y1356181I-3503J2D01*
G03Y1356019I183J-81D01*
G02X797776Y1354600I-3202J-1421D01*
G02X790770I-3503J0D01*
G02X791071Y1356019I3503J-2D01*
G03Y1356181I-183J81D01*
G02X790770Y1357600I3202J1421D01*
G02X791296Y1359445I3503J-1D01*
G03Y1359655I-170J105D01*
G37*
G36*
G01X382478Y1657961D02*
G02X382681Y1658164I203J0D01*
G01X401967D01*
G02X402170Y1657961I0J-203D01*
G01Y1631213D01*
G02X401967Y1631010I-203J0D01*
G01X382681D01*
G02X382478Y1631213I0J203D01*
G01Y1657961D01*
G37*
G36*
G01X60921Y429304D02*
G02Y432308I0J1502D01*
G01X64821D01*
G02Y429304I0J-1502D01*
G01X60921D01*
G37*
G36*
G01X45960Y427304D02*
G02Y430308I0J1502D01*
G01X49360D01*
G02Y427304I0J-1502D01*
G01X45960D01*
G37*
G36*
G01X225731Y24974D02*
G02Y27980I0J1503D01*
G01X229131D01*
G02Y24974I0J-1503D01*
G01X225731D01*
G37*
G36*
G01X1700183Y25002D02*
G02Y28008I0J1503D01*
G01X1703583D01*
G02Y25002I0J-1503D01*
G01X1700183D01*
G37*
G36*
G01X551721Y80874D02*
G02Y77870I0J-1502D01*
G01X547821D01*
G02Y80874I0J1502D01*
G01X551721D01*
G37*
G36*
G01X512658Y45110D02*
G02Y48116I0J1503D01*
G01X516058D01*
G02Y45110I0J-1503D01*
G01X512658D01*
G37*
G36*
G01X541003Y69934D02*
G02Y72938I0J1502D01*
G01X544403D01*
G02Y69934I0J-1502D01*
G01X541003D01*
G37*
G36*
G01X509572Y863824D02*
G02Y866830I0J1503D01*
G01X513572D01*
G02Y863824I0J-1503D01*
G01X509572D01*
G37*
G36*
G01X1332812Y854880D02*
G02Y857886I0J1503D01*
G01X1336812D01*
G02Y854880I0J-1503D01*
G01X1332812D01*
G37*
G36*
G01X1659645Y1553264D02*
G02X1660705Y1553900I1060J-565D01*
G02X1661908Y1552698I1J-1202D01*
G02X1661747Y1552098I-1204J1D01*
G01X1660202Y1549425D01*
X1660200Y1549421D01*
G02X1659130Y1548768I-1070J550D01*
G02X1657928Y1549970I0J1202D01*
G01Y1549972D01*
G02X1658077Y1550551I1202J-1D01*
G01X1659643Y1553261D01*
X1659645Y1553264D01*
G37*
G36*
G01X1654920D02*
G02X1655980Y1553900I1060J-565D01*
G02X1657182Y1552698I0J-1202D01*
G02X1657022Y1552098I-1203J0D01*
G01X1655477Y1549425D01*
X1655475Y1549421D01*
G02X1654405Y1548768I-1070J550D01*
G02X1653202Y1549970I-1J1202D01*
G01Y1549972D01*
G02X1653352Y1550551I1203J-3D01*
G01X1654918Y1553261D01*
X1654920Y1553264D01*
G37*
G36*
G01X1645471D02*
G02X1646531Y1553900I1060J-565D01*
G02X1647734Y1552698I1J-1202D01*
G02X1647573Y1552098I-1204J1D01*
G01X1646028Y1549425D01*
X1646026Y1549421D01*
G02X1644956Y1548768I-1070J550D01*
G02X1643754Y1549970I0J1202D01*
G01Y1549972D01*
G02X1643903Y1550551I1202J-1D01*
G01X1645469Y1553261D01*
X1645471Y1553264D01*
G37*
G36*
G01X1650196D02*
G02X1651256Y1553900I1060J-565D01*
G02X1652458Y1552698I0J-1202D01*
G02X1652298Y1552098I-1203J0D01*
G01X1650753Y1549425D01*
X1650751Y1549421D01*
G02X1649681Y1548768I-1070J550D01*
G02X1648478Y1549970I-1J1202D01*
G01Y1549972D01*
G02X1648628Y1550551I1203J-3D01*
G01X1650194Y1553261D01*
X1650196Y1553264D01*
G37*
G36*
G01X1640747D02*
G02X1641807Y1553900I1060J-565D01*
G02X1643010Y1552698I1J-1202D01*
G02X1642849Y1552098I-1204J1D01*
G01X1641304Y1549425D01*
X1641302Y1549421D01*
G02X1640232Y1548768I-1070J550D01*
G02X1639030Y1549970I0J1202D01*
G01Y1549972D01*
G02X1639179Y1550551I1202J-1D01*
G01X1640745Y1553261D01*
X1640747Y1553264D01*
G37*
G36*
G01X1636023D02*
G02X1637083Y1553900I1060J-565D01*
G02X1638286Y1552698I1J-1202D01*
G02X1638125Y1552098I-1204J1D01*
G01X1636580Y1549425D01*
X1636578Y1549421D01*
G02X1635508Y1548768I-1070J550D01*
G02X1634306Y1549970I0J1202D01*
G01Y1549972D01*
G02X1634455Y1550551I1202J-1D01*
G01X1636021Y1553261D01*
X1636023Y1553264D01*
G37*
G36*
G01X1631298D02*
G02X1632358Y1553900I1060J-565D01*
G02X1633560Y1552698I0J-1202D01*
G02X1633400Y1552098I-1203J0D01*
G01X1631855Y1549425D01*
X1631853Y1549421D01*
G02X1630783Y1548768I-1070J550D01*
G02X1629580Y1549970I-1J1202D01*
G01Y1549972D01*
G02X1629730Y1550551I1203J-3D01*
G01X1631296Y1553261D01*
X1631298Y1553264D01*
G37*
G36*
G01X1626574D02*
G02X1627634Y1553900I1060J-565D01*
G02X1628836Y1552698I0J-1202D01*
G02X1628676Y1552098I-1203J0D01*
G01X1627131Y1549425D01*
X1627129Y1549421D01*
G02X1626059Y1548768I-1070J550D01*
G02X1624856Y1549970I-1J1202D01*
G01Y1549972D01*
G02X1625006Y1550551I1203J-3D01*
G01X1626572Y1553261D01*
X1626574Y1553264D01*
G37*
G36*
G01X1621849D02*
G02X1622909Y1553900I1060J-565D01*
G02X1624112Y1552698I1J-1202D01*
G02X1623951Y1552098I-1204J1D01*
G01X1622406Y1549425D01*
X1622404Y1549421D01*
G02X1621334Y1548768I-1070J550D01*
G02X1620132Y1549970I0J1202D01*
G01Y1549972D01*
G02X1620281Y1550551I1202J-1D01*
G01X1621847Y1553261D01*
X1621849Y1553264D01*
G37*
G36*
G01X1617125D02*
G02X1618185Y1553900I1060J-565D01*
G02X1619388Y1552698I1J-1202D01*
G02X1619227Y1552098I-1204J1D01*
G01X1617682Y1549425D01*
X1617680Y1549421D01*
G02X1616610Y1548768I-1070J550D01*
G02X1615408Y1549970I0J1202D01*
G01Y1549972D01*
G02X1615557Y1550551I1202J-1D01*
G01X1617123Y1553261D01*
X1617125Y1553264D01*
G37*
G36*
G01X1607676D02*
G02X1608736Y1553900I1060J-565D01*
G02X1609938Y1552698I0J-1202D01*
G02X1609778Y1552098I-1203J0D01*
G01X1608233Y1549425D01*
X1608231Y1549421D01*
G02X1607161Y1548768I-1070J550D01*
G02X1605958Y1549970I-1J1202D01*
G01Y1549972D01*
G02X1606108Y1550551I1203J-3D01*
G01X1607674Y1553261D01*
X1607676Y1553264D01*
G37*
G36*
G01X1612401D02*
G02X1613461Y1553900I1060J-565D01*
G02X1614664Y1552698I1J-1202D01*
G02X1614503Y1552098I-1204J1D01*
G01X1612958Y1549425D01*
X1612956Y1549421D01*
G02X1611886Y1548768I-1070J550D01*
G02X1610684Y1549970I0J1202D01*
G01Y1549972D01*
G02X1610833Y1550551I1202J-1D01*
G01X1612399Y1553261D01*
X1612401Y1553264D01*
G37*
G36*
G01X1598227D02*
G02X1599287Y1553900I1060J-565D01*
G02X1600490Y1552698I1J-1202D01*
G02X1600329Y1552098I-1204J1D01*
G01X1598784Y1549425D01*
X1598782Y1549421D01*
G02X1597712Y1548768I-1070J550D01*
G02X1596510Y1549970I0J1202D01*
G01Y1549972D01*
G02X1596659Y1550551I1202J-1D01*
G01X1598225Y1553261D01*
X1598227Y1553264D01*
G37*
G36*
G01X1602952D02*
G02X1604012Y1553900I1060J-565D01*
G02X1605214Y1552698I0J-1202D01*
G02X1605054Y1552098I-1203J0D01*
G01X1603509Y1549425D01*
X1603507Y1549421D01*
G02X1602437Y1548768I-1070J550D01*
G02X1601234Y1549970I-1J1202D01*
G01Y1549972D01*
G02X1601384Y1550551I1203J-3D01*
G01X1602950Y1553261D01*
X1602952Y1553264D01*
G37*
G36*
G01X1593503D02*
G02X1594563Y1553900I1060J-565D01*
G02X1595766Y1552698I1J-1202D01*
G02X1595605Y1552098I-1204J1D01*
G01X1594060Y1549425D01*
X1594058Y1549421D01*
G02X1592988Y1548768I-1070J550D01*
G02X1591786Y1549970I0J1202D01*
G01Y1549972D01*
G02X1591935Y1550551I1202J-1D01*
G01X1593501Y1553261D01*
X1593503Y1553264D01*
G37*
G36*
G01X1588779D02*
G02X1589839Y1553900I1060J-565D01*
G02X1591042Y1552698I1J-1202D01*
G02X1590881Y1552098I-1204J1D01*
G01X1589336Y1549425D01*
X1589334Y1549421D01*
G02X1588264Y1548768I-1070J550D01*
G02X1587062Y1549970I0J1202D01*
G01Y1549972D01*
G02X1587211Y1550551I1202J-1D01*
G01X1588777Y1553261D01*
X1588779Y1553264D01*
G37*
G36*
G01X1526858D02*
G02X1527918Y1553900I1060J-565D01*
G02X1529120Y1552698I0J-1202D01*
G02X1528960Y1552098I-1203J0D01*
G01X1527415Y1549425D01*
X1527413Y1549421D01*
G02X1526343Y1548768I-1070J550D01*
G02X1525140Y1549970I-1J1202D01*
G01Y1549972D01*
G02X1525290Y1550551I1203J-3D01*
G01X1526856Y1553261D01*
X1526858Y1553264D01*
G37*
G36*
G01X1531583D02*
G02X1532643Y1553900I1060J-565D01*
G02X1533846Y1552698I1J-1202D01*
G02X1533685Y1552098I-1204J1D01*
G01X1532140Y1549425D01*
X1532138Y1549421D01*
G02X1531068Y1548768I-1070J550D01*
G02X1529866Y1549970I0J1202D01*
G01Y1549972D01*
G02X1530015Y1550551I1202J-1D01*
G01X1531581Y1553261D01*
X1531583Y1553264D01*
G37*
G36*
G01X1517409D02*
G02X1518469Y1553900I1060J-565D01*
G02X1519672Y1552698I1J-1202D01*
G02X1519511Y1552098I-1204J1D01*
G01X1517966Y1549425D01*
X1517964Y1549421D01*
G02X1516894Y1548768I-1070J550D01*
G02X1515692Y1549970I0J1202D01*
G01Y1549972D01*
G02X1515841Y1550551I1202J-1D01*
G01X1517407Y1553261D01*
X1517409Y1553264D01*
G37*
G36*
G01X1512685D02*
G02X1513745Y1553900I1060J-565D01*
G02X1514948Y1552698I1J-1202D01*
G02X1514787Y1552098I-1204J1D01*
G01X1513242Y1549425D01*
X1513240Y1549421D01*
G02X1512170Y1548768I-1070J550D01*
G02X1510968Y1549970I0J1202D01*
G01Y1549972D01*
G02X1511117Y1550551I1202J-1D01*
G01X1512683Y1553261D01*
X1512685Y1553264D01*
G37*
G36*
G01X1522134D02*
G02X1523194Y1553900I1060J-565D01*
G02X1524396Y1552698I0J-1202D01*
G02X1524236Y1552098I-1203J0D01*
G01X1522691Y1549425D01*
X1522689Y1549421D01*
G02X1521619Y1548768I-1070J550D01*
G02X1520416Y1549970I-1J1202D01*
G01Y1549972D01*
G02X1520566Y1550551I1203J-3D01*
G01X1522132Y1553261D01*
X1522134Y1553264D01*
G37*
G36*
G01X1498512D02*
G02X1499572Y1553900I1060J-565D01*
G02X1500774Y1552698I0J-1202D01*
G02X1500614Y1552098I-1203J0D01*
G01X1499069Y1549425D01*
X1499067Y1549421D01*
G02X1497997Y1548768I-1070J550D01*
G02X1496794Y1549970I-1J1202D01*
G01Y1549972D01*
G02X1496944Y1550551I1203J-3D01*
G01X1498510Y1553261D01*
X1498512Y1553264D01*
G37*
G36*
G01X1507961D02*
G02X1509021Y1553900I1060J-565D01*
G02X1510224Y1552698I1J-1202D01*
G02X1510063Y1552098I-1204J1D01*
G01X1508518Y1549425D01*
X1508516Y1549421D01*
G02X1507446Y1548768I-1070J550D01*
G02X1506244Y1549970I0J1202D01*
G01Y1549972D01*
G02X1506393Y1550551I1202J-1D01*
G01X1507959Y1553261D01*
X1507961Y1553264D01*
G37*
G36*
G01X1503236D02*
G02X1504296Y1553900I1060J-565D01*
G02X1505498Y1552698I0J-1202D01*
G02X1505338Y1552098I-1203J0D01*
G01X1503793Y1549425D01*
X1503791Y1549421D01*
G02X1502721Y1548768I-1070J550D01*
G02X1501518Y1549970I-1J1202D01*
G01Y1549972D01*
G02X1501668Y1550551I1203J-3D01*
G01X1503234Y1553261D01*
X1503236Y1553264D01*
G37*
G36*
G01X1493787D02*
G02X1494847Y1553900I1060J-565D01*
G02X1496050Y1552698I1J-1202D01*
G02X1495889Y1552098I-1204J1D01*
G01X1494344Y1549425D01*
X1494342Y1549421D01*
G02X1493272Y1548768I-1070J550D01*
G02X1492070Y1549970I0J1202D01*
G01Y1549972D01*
G02X1492219Y1550551I1202J-1D01*
G01X1493785Y1553261D01*
X1493787Y1553264D01*
G37*
G36*
G01X1484339D02*
G02X1485399Y1553900I1060J-565D01*
G02X1486602Y1552698I1J-1202D01*
G02X1486441Y1552098I-1204J1D01*
G01X1484896Y1549425D01*
X1484894Y1549421D01*
G02X1483824Y1548768I-1070J550D01*
G02X1482622Y1549970I0J1202D01*
G01Y1549972D01*
G02X1482771Y1550551I1202J-1D01*
G01X1484337Y1553261D01*
X1484339Y1553264D01*
G37*
G36*
G01X1489063D02*
G02X1490123Y1553900I1060J-565D01*
G02X1491326Y1552698I1J-1202D01*
G02X1491165Y1552098I-1204J1D01*
G01X1489620Y1549425D01*
X1489618Y1549421D01*
G02X1488548Y1548768I-1070J550D01*
G02X1487346Y1549970I0J1202D01*
G01Y1549972D01*
G02X1487495Y1550551I1202J-1D01*
G01X1489061Y1553261D01*
X1489063Y1553264D01*
G37*
G36*
G01X1479614D02*
G02X1480674Y1553900I1060J-565D01*
G02X1481876Y1552698I0J-1202D01*
G02X1481716Y1552098I-1203J0D01*
G01X1480171Y1549425D01*
X1480169Y1549421D01*
G02X1479099Y1548768I-1070J550D01*
G02X1477896Y1549970I-1J1202D01*
G01Y1549972D01*
G02X1478046Y1550551I1203J-3D01*
G01X1479612Y1553261D01*
X1479614Y1553264D01*
G37*
G36*
G01X1470165D02*
G02X1471225Y1553900I1060J-565D01*
G02X1472428Y1552698I1J-1202D01*
G02X1472267Y1552098I-1204J1D01*
G01X1470722Y1549425D01*
X1470720Y1549421D01*
G02X1469650Y1548768I-1070J550D01*
G02X1468448Y1549970I0J1202D01*
G01Y1549972D01*
G02X1468597Y1550551I1202J-1D01*
G01X1470163Y1553261D01*
X1470165Y1553264D01*
G37*
G36*
G01X1474890D02*
G02X1475950Y1553900I1060J-565D01*
G02X1477152Y1552698I0J-1202D01*
G02X1476992Y1552098I-1203J0D01*
G01X1475447Y1549425D01*
X1475445Y1549421D01*
G02X1474375Y1548768I-1070J550D01*
G02X1473172Y1549970I-1J1202D01*
G01Y1549972D01*
G02X1473322Y1550551I1203J-3D01*
G01X1474888Y1553261D01*
X1474890Y1553264D01*
G37*
G36*
G01X1465441D02*
G02X1466501Y1553900I1060J-565D01*
G02X1467704Y1552698I1J-1202D01*
G02X1467543Y1552098I-1204J1D01*
G01X1465998Y1549425D01*
X1465996Y1549421D01*
G02X1464926Y1548768I-1070J550D01*
G02X1463724Y1549970I0J1202D01*
G01Y1549972D01*
G02X1463873Y1550551I1202J-1D01*
G01X1465439Y1553261D01*
X1465441Y1553264D01*
G37*
G36*
G01X1460717D02*
G02X1461777Y1553900I1060J-565D01*
G02X1462980Y1552698I1J-1202D01*
G02X1462819Y1552098I-1204J1D01*
G01X1461274Y1549425D01*
X1461272Y1549421D01*
G02X1460202Y1548768I-1070J550D01*
G02X1459000Y1549970I0J1202D01*
G01Y1549972D01*
G02X1459149Y1550551I1202J-1D01*
G01X1460715Y1553261D01*
X1460717Y1553264D01*
G37*
G36*
G01X372126Y1215958D02*
G02Y1212952I0J-1503D01*
G01X368726D01*
G02Y1215958I0J1503D01*
G01X372126D01*
G37*
G36*
G01X613975Y1520264D02*
G02X615035Y1520900I1060J-565D01*
G02X616238Y1519698I1J-1202D01*
G02X616077Y1519098I-1204J1D01*
G01X614532Y1516425D01*
X614530Y1516421D01*
G02X613460Y1515768I-1070J550D01*
G02X612258Y1516970I0J1202D01*
G01Y1516972D01*
G02X612407Y1517551I1202J-1D01*
G01X613973Y1520261D01*
X613975Y1520264D01*
G37*
G36*
G01X642322D02*
G02X643382Y1520900I1060J-565D01*
G02X644584Y1519698I0J-1202D01*
G02X644424Y1519098I-1203J0D01*
G01X642879Y1516425D01*
X642877Y1516421D01*
G02X641807Y1515768I-1070J550D01*
G02X640604Y1516970I-1J1202D01*
G01Y1516972D01*
G02X640754Y1517551I1203J-3D01*
G01X642320Y1520261D01*
X642322Y1520264D01*
G37*
G36*
G01X609251D02*
G02X610311Y1520900I1060J-565D01*
G02X611514Y1519698I1J-1202D01*
G02X611353Y1519098I-1204J1D01*
G01X609808Y1516425D01*
X609806Y1516421D01*
G02X608736Y1515768I-1070J550D01*
G02X607534Y1516970I0J1202D01*
G01Y1516972D01*
G02X607683Y1517551I1202J-1D01*
G01X609249Y1520261D01*
X609251Y1520264D01*
G37*
G36*
G01X637597D02*
G02X638657Y1520900I1060J-565D01*
G02X639860Y1519698I1J-1202D01*
G02X639699Y1519098I-1204J1D01*
G01X638154Y1516425D01*
X638152Y1516421D01*
G02X637082Y1515768I-1070J550D01*
G02X635880Y1516970I0J1202D01*
G01Y1516972D01*
G02X636029Y1517551I1202J-1D01*
G01X637595Y1520261D01*
X637597Y1520264D01*
G37*
G36*
G01X595078D02*
G02X596138Y1520900I1060J-565D01*
G02X597340Y1519698I0J-1202D01*
G02X597180Y1519098I-1203J0D01*
G01X595635Y1516425D01*
X595633Y1516421D01*
G02X594563Y1515768I-1070J550D01*
G02X593360Y1516970I-1J1202D01*
G01Y1516972D01*
G02X593510Y1517551I1203J-3D01*
G01X595076Y1520261D01*
X595078Y1520264D01*
G37*
G36*
G01X647046D02*
G02X648106Y1520900I1060J-565D01*
G02X649308Y1519698I0J-1202D01*
G02X649148Y1519098I-1203J0D01*
G01X647603Y1516425D01*
X647601Y1516421D01*
G02X646531Y1515768I-1070J550D01*
G02X645328Y1516970I-1J1202D01*
G01Y1516972D01*
G02X645478Y1517551I1203J-3D01*
G01X647044Y1520261D01*
X647046Y1520264D01*
G37*
G36*
G01X590353D02*
G02X591413Y1520900I1060J-565D01*
G02X592616Y1519698I1J-1202D01*
G02X592455Y1519098I-1204J1D01*
G01X590910Y1516425D01*
X590908Y1516421D01*
G02X589838Y1515768I-1070J550D01*
G02X588636Y1516970I0J1202D01*
G01Y1516972D01*
G02X588785Y1517551I1202J-1D01*
G01X590351Y1520261D01*
X590353Y1520264D01*
G37*
G36*
G01X604527D02*
G02X605587Y1520900I1060J-565D01*
G02X606790Y1519698I1J-1202D01*
G02X606629Y1519098I-1204J1D01*
G01X605084Y1516425D01*
X605082Y1516421D01*
G02X604012Y1515768I-1070J550D01*
G02X602810Y1516970I0J1202D01*
G01Y1516972D01*
G02X602959Y1517551I1202J-1D01*
G01X604525Y1520261D01*
X604527Y1520264D01*
G37*
G36*
G01X628149D02*
G02X629209Y1520900I1060J-565D01*
G02X630412Y1519698I1J-1202D01*
G02X630251Y1519098I-1204J1D01*
G01X628706Y1516425D01*
X628704Y1516421D01*
G02X627634Y1515768I-1070J550D01*
G02X626432Y1516970I0J1202D01*
G01Y1516972D01*
G02X626581Y1517551I1202J-1D01*
G01X628147Y1520261D01*
X628149Y1520264D01*
G37*
G36*
G01X618700D02*
G02X619760Y1520900I1060J-565D01*
G02X620962Y1519698I0J-1202D01*
G02X620802Y1519098I-1203J0D01*
G01X619257Y1516425D01*
X619255Y1516421D01*
G02X618185Y1515768I-1070J550D01*
G02X616982Y1516970I-1J1202D01*
G01Y1516972D01*
G02X617132Y1517551I1203J-3D01*
G01X618698Y1520261D01*
X618700Y1520264D01*
G37*
G36*
G01X599802D02*
G02X600862Y1520900I1060J-565D01*
G02X602064Y1519698I0J-1202D01*
G02X601904Y1519098I-1203J0D01*
G01X600359Y1516425D01*
X600357Y1516421D01*
G02X599287Y1515768I-1070J550D01*
G02X598084Y1516970I-1J1202D01*
G01Y1516972D01*
G02X598234Y1517551I1203J-3D01*
G01X599800Y1520261D01*
X599802Y1520264D01*
G37*
G36*
G01X623424D02*
G02X624484Y1520900I1060J-565D01*
G02X625686Y1519698I0J-1202D01*
G02X625526Y1519098I-1203J0D01*
G01X623981Y1516425D01*
X623979Y1516421D01*
G02X622909Y1515768I-1070J550D01*
G02X621706Y1516970I-1J1202D01*
G01Y1516972D01*
G02X621856Y1517551I1203J-3D01*
G01X623422Y1520261D01*
X623424Y1520264D01*
G37*
G36*
G01X580905D02*
G02X581965Y1520900I1060J-565D01*
G02X583168Y1519698I1J-1202D01*
G02X583007Y1519098I-1204J1D01*
G01X581462Y1516425D01*
X581460Y1516421D01*
G02X580390Y1515768I-1070J550D01*
G02X579188Y1516970I0J1202D01*
G01Y1516972D01*
G02X579337Y1517551I1202J-1D01*
G01X580903Y1520261D01*
X580905Y1520264D01*
G37*
G36*
G01X632873D02*
G02X633933Y1520900I1060J-565D01*
G02X635136Y1519698I1J-1202D01*
G02X634975Y1519098I-1204J1D01*
G01X633430Y1516425D01*
X633428Y1516421D01*
G02X632358Y1515768I-1070J550D01*
G02X631156Y1516970I0J1202D01*
G01Y1516972D01*
G02X631305Y1517551I1202J-1D01*
G01X632871Y1520261D01*
X632873Y1520264D01*
G37*
G36*
G01X585629D02*
G02X586689Y1520900I1060J-565D01*
G02X587892Y1519698I1J-1202D01*
G02X587731Y1519098I-1204J1D01*
G01X586186Y1516425D01*
X586184Y1516421D01*
G02X585114Y1515768I-1070J550D01*
G02X583912Y1516970I0J1202D01*
G01Y1516972D01*
G02X584061Y1517551I1202J-1D01*
G01X585627Y1520261D01*
X585629Y1520264D01*
G37*
G36*
G01X481189D02*
G02X482249Y1520900I1060J-565D01*
G02X483452Y1519698I1J-1202D01*
G02X483291Y1519098I-1204J1D01*
G01X481746Y1516425D01*
X481744Y1516421D01*
G02X480674Y1515768I-1070J550D01*
G02X479472Y1516970I0J1202D01*
G01Y1516972D01*
G02X479621Y1517551I1202J-1D01*
G01X481187Y1520261D01*
X481189Y1520264D01*
G37*
G36*
G01X518984D02*
G02X520044Y1520900I1060J-565D01*
G02X521246Y1519698I0J-1202D01*
G02X521086Y1519098I-1203J0D01*
G01X519541Y1516425D01*
X519539Y1516421D01*
G02X518469Y1515768I-1070J550D01*
G02X517266Y1516970I-1J1202D01*
G01Y1516972D01*
G02X517416Y1517551I1203J-3D01*
G01X518982Y1520261D01*
X518984Y1520264D01*
G37*
G36*
G01X471740D02*
G02X472800Y1520900I1060J-565D01*
G02X474002Y1519698I0J-1202D01*
G02X473842Y1519098I-1203J0D01*
G01X472297Y1516425D01*
X472295Y1516421D01*
G02X471225Y1515768I-1070J550D01*
G02X470022Y1516970I-1J1202D01*
G01Y1516972D01*
G02X470172Y1517551I1203J-3D01*
G01X471738Y1520261D01*
X471740Y1520264D01*
G37*
G36*
G01X514260D02*
G02X515320Y1520900I1060J-565D01*
G02X516522Y1519698I0J-1202D01*
G02X516362Y1519098I-1203J0D01*
G01X514817Y1516425D01*
X514815Y1516421D01*
G02X513745Y1515768I-1070J550D01*
G02X512542Y1516970I-1J1202D01*
G01Y1516972D01*
G02X512692Y1517551I1203J-3D01*
G01X514258Y1520261D01*
X514260Y1520264D01*
G37*
G36*
G01X476465D02*
G02X477525Y1520900I1060J-565D01*
G02X478728Y1519698I1J-1202D01*
G02X478567Y1519098I-1204J1D01*
G01X477022Y1516425D01*
X477020Y1516421D01*
G02X475950Y1515768I-1070J550D01*
G02X474748Y1516970I0J1202D01*
G01Y1516972D01*
G02X474897Y1517551I1202J-1D01*
G01X476463Y1520261D01*
X476465Y1520264D01*
G37*
G36*
G01X1395471Y1553264D02*
G02X1396531Y1553900I1060J-565D01*
G02X1397734Y1552698I1J-1202D01*
G02X1397573Y1552098I-1204J1D01*
G01X1396028Y1549425D01*
X1396026Y1549421D01*
G02X1394956Y1548768I-1070J550D01*
G02X1393754Y1549970I0J1202D01*
G01Y1549972D01*
G02X1393903Y1550551I1202J-1D01*
G01X1395469Y1553261D01*
X1395471Y1553264D01*
G37*
G36*
G01X1386022D02*
G02X1387082Y1553900I1060J-565D01*
G02X1388284Y1552698I0J-1202D01*
G02X1388124Y1552098I-1203J0D01*
G01X1386579Y1549425D01*
X1386577Y1549421D01*
G02X1385507Y1548768I-1070J550D01*
G02X1384304Y1549970I-1J1202D01*
G01Y1549972D01*
G02X1384454Y1550551I1203J-3D01*
G01X1386020Y1553261D01*
X1386022Y1553264D01*
G37*
G36*
G01X1376573D02*
G02X1377633Y1553900I1060J-565D01*
G02X1378836Y1552698I1J-1202D01*
G02X1378675Y1552098I-1204J1D01*
G01X1377130Y1549425D01*
X1377128Y1549421D01*
G02X1376058Y1548768I-1070J550D01*
G02X1374856Y1549970I0J1202D01*
G01Y1549972D01*
G02X1375005Y1550551I1202J-1D01*
G01X1376571Y1553261D01*
X1376573Y1553264D01*
G37*
G36*
G01X504811Y1520264D02*
G02X505871Y1520900I1060J-565D01*
G02X507074Y1519698I1J-1202D01*
G02X506913Y1519098I-1204J1D01*
G01X505368Y1516425D01*
X505366Y1516421D01*
G02X504296Y1515768I-1070J550D01*
G02X503094Y1516970I0J1202D01*
G01Y1516972D01*
G02X503243Y1517551I1202J-1D01*
G01X504809Y1520261D01*
X504811Y1520264D01*
G37*
G36*
G01X495362D02*
G02X496422Y1520900I1060J-565D01*
G02X497624Y1519698I0J-1202D01*
G02X497464Y1519098I-1203J0D01*
G01X495919Y1516425D01*
X495917Y1516421D01*
G02X494847Y1515768I-1070J550D01*
G02X493644Y1516970I-1J1202D01*
G01Y1516972D01*
G02X493794Y1517551I1203J-3D01*
G01X495360Y1520261D01*
X495362Y1520264D01*
G37*
G36*
G01X523709D02*
G02X524769Y1520900I1060J-565D01*
G02X525972Y1519698I1J-1202D01*
G02X525811Y1519098I-1204J1D01*
G01X524266Y1516425D01*
X524264Y1516421D01*
G02X523194Y1515768I-1070J550D01*
G02X521992Y1516970I0J1202D01*
G01Y1516972D01*
G02X522141Y1517551I1202J-1D01*
G01X523707Y1520261D01*
X523709Y1520264D01*
G37*
G36*
G01X452843D02*
G02X453903Y1520900I1060J-565D01*
G02X455106Y1519698I1J-1202D01*
G02X454945Y1519098I-1204J1D01*
G01X453400Y1516425D01*
X453398Y1516421D01*
G02X452328Y1515768I-1070J550D01*
G02X451126Y1516970I0J1202D01*
G01Y1516972D01*
G02X451275Y1517551I1202J-1D01*
G01X452841Y1520261D01*
X452843Y1520264D01*
G37*
G36*
G01X457567D02*
G02X458627Y1520900I1060J-565D01*
G02X459830Y1519698I1J-1202D01*
G02X459669Y1519098I-1204J1D01*
G01X458124Y1516425D01*
X458122Y1516421D01*
G02X457052Y1515768I-1070J550D01*
G02X455850Y1516970I0J1202D01*
G01Y1516972D01*
G02X455999Y1517551I1202J-1D01*
G01X457565Y1520261D01*
X457567Y1520264D01*
G37*
G36*
G01X691276Y1453610D02*
G02Y1456614I0J1502D01*
G01X694676D01*
G02Y1453610I0J-1502D01*
G01X691276D01*
G37*
G36*
G01X1338778Y1553264D02*
G02X1339838Y1553900I1060J-565D01*
G02X1341040Y1552698I0J-1202D01*
G02X1340880Y1552098I-1203J0D01*
G01X1339335Y1549425D01*
X1339333Y1549421D01*
G02X1338263Y1548768I-1070J550D01*
G02X1337060Y1549970I-1J1202D01*
G01Y1549972D01*
G02X1337210Y1550551I1203J-3D01*
G01X1338776Y1553261D01*
X1338778Y1553264D01*
G37*
G36*
G01X467016Y1520264D02*
G02X468076Y1520900I1060J-565D01*
G02X469278Y1519698I0J-1202D01*
G02X469118Y1519098I-1203J0D01*
G01X467573Y1516425D01*
X467571Y1516421D01*
G02X466501Y1515768I-1070J550D01*
G02X465298Y1516970I-1J1202D01*
G01Y1516972D01*
G02X465448Y1517551I1203J-3D01*
G01X467014Y1520261D01*
X467016Y1520264D01*
G37*
G36*
G01X485913D02*
G02X486973Y1520900I1060J-565D01*
G02X488176Y1519698I1J-1202D01*
G02X488015Y1519098I-1204J1D01*
G01X486470Y1516425D01*
X486468Y1516421D01*
G02X485398Y1515768I-1070J550D01*
G02X484196Y1516970I0J1202D01*
G01Y1516972D01*
G02X484345Y1517551I1202J-1D01*
G01X485911Y1520261D01*
X485913Y1520264D01*
G37*
G36*
G01X382873D02*
G02X383933Y1520900I1060J-565D01*
G02X385136Y1519698I1J-1202D01*
G02X384975Y1519098I-1204J1D01*
G01X383430Y1516425D01*
X383428Y1516421D01*
G02X382358Y1515768I-1070J550D01*
G02X381156Y1516970I0J1202D01*
G01Y1516972D01*
G02X381305Y1517551I1202J-1D01*
G01X382871Y1520261D01*
X382873Y1520264D01*
G37*
G36*
G01X340354D02*
G02X341414Y1520900I1060J-565D01*
G02X342616Y1519698I0J-1202D01*
G02X342456Y1519098I-1203J0D01*
G01X340911Y1516425D01*
X340909Y1516421D01*
G02X339839Y1515768I-1070J550D01*
G02X338636Y1516970I-1J1202D01*
G01Y1516972D01*
G02X338786Y1517551I1203J-3D01*
G01X340352Y1520261D01*
X340354Y1520264D01*
G37*
G36*
G01X387598D02*
G02X388658Y1520900I1060J-565D01*
G02X389860Y1519698I0J-1202D01*
G02X389700Y1519098I-1203J0D01*
G01X388155Y1516425D01*
X388153Y1516421D01*
G02X387083Y1515768I-1070J550D01*
G02X385880Y1516970I-1J1202D01*
G01Y1516972D01*
G02X386030Y1517551I1203J-3D01*
G01X387596Y1520261D01*
X387598Y1520264D01*
G37*
G36*
G01X462291D02*
G02X463351Y1520900I1060J-565D01*
G02X464554Y1519698I1J-1202D01*
G02X464393Y1519098I-1204J1D01*
G01X462848Y1516425D01*
X462846Y1516421D01*
G02X461776Y1515768I-1070J550D01*
G02X460574Y1516970I0J1202D01*
G01Y1516972D01*
G02X460723Y1517551I1202J-1D01*
G01X462289Y1520261D01*
X462291Y1520264D01*
G37*
G36*
G01X490638D02*
G02X491698Y1520900I1060J-565D01*
G02X492900Y1519698I0J-1202D01*
G02X492740Y1519098I-1203J0D01*
G01X491195Y1516425D01*
X491193Y1516421D01*
G02X490123Y1515768I-1070J550D01*
G02X488920Y1516970I-1J1202D01*
G01Y1516972D01*
G02X489070Y1517551I1203J-3D01*
G01X490636Y1520261D01*
X490638Y1520264D01*
G37*
G36*
G01X1371849Y1553264D02*
G02X1372909Y1553900I1060J-565D01*
G02X1374112Y1552698I1J-1202D01*
G02X1373951Y1552098I-1204J1D01*
G01X1372406Y1549425D01*
X1372404Y1549421D01*
G02X1371334Y1548768I-1070J550D01*
G02X1370132Y1549970I0J1202D01*
G01Y1549972D01*
G02X1370281Y1550551I1202J-1D01*
G01X1371847Y1553261D01*
X1371849Y1553264D01*
G37*
G36*
G01X1362400D02*
G02X1363460Y1553900I1060J-565D01*
G02X1364662Y1552698I0J-1202D01*
G02X1364502Y1552098I-1203J0D01*
G01X1362957Y1549425D01*
X1362955Y1549421D01*
G02X1361885Y1548768I-1070J550D01*
G02X1360682Y1549970I-1J1202D01*
G01Y1549972D01*
G02X1360832Y1550551I1203J-3D01*
G01X1362398Y1553261D01*
X1362400Y1553264D01*
G37*
G36*
G01X1367124D02*
G02X1368184Y1553900I1060J-565D01*
G02X1369386Y1552698I0J-1202D01*
G02X1369226Y1552098I-1203J0D01*
G01X1367681Y1549425D01*
X1367679Y1549421D01*
G02X1366609Y1548768I-1070J550D01*
G02X1365406Y1549970I-1J1202D01*
G01Y1549972D01*
G02X1365556Y1550551I1203J-3D01*
G01X1367122Y1553261D01*
X1367124Y1553264D01*
G37*
G36*
G01X1343502D02*
G02X1344562Y1553900I1060J-565D01*
G02X1345764Y1552698I0J-1202D01*
G02X1345604Y1552098I-1203J0D01*
G01X1344059Y1549425D01*
X1344057Y1549421D01*
G02X1342987Y1548768I-1070J550D01*
G02X1341784Y1549970I-1J1202D01*
G01Y1549972D01*
G02X1341934Y1550551I1203J-3D01*
G01X1343500Y1553261D01*
X1343502Y1553264D01*
G37*
G36*
G01X1348227D02*
G02X1349287Y1553900I1060J-565D01*
G02X1350490Y1552698I1J-1202D01*
G02X1350329Y1552098I-1204J1D01*
G01X1348784Y1549425D01*
X1348782Y1549421D01*
G02X1347712Y1548768I-1070J550D01*
G02X1346510Y1549970I0J1202D01*
G01Y1549972D01*
G02X1346659Y1550551I1202J-1D01*
G01X1348225Y1553261D01*
X1348227Y1553264D01*
G37*
G36*
G01X1352951D02*
G02X1354011Y1553900I1060J-565D01*
G02X1355214Y1552698I1J-1202D01*
G02X1355053Y1552098I-1204J1D01*
G01X1353508Y1549425D01*
X1353506Y1549421D01*
G02X1352436Y1548768I-1070J550D01*
G02X1351234Y1549970I0J1202D01*
G01Y1549972D01*
G02X1351383Y1550551I1202J-1D01*
G01X1352949Y1553261D01*
X1352951Y1553264D01*
G37*
G36*
G01X188670Y1520264D02*
G02X189730Y1520900I1060J-565D01*
G02X190932Y1519698I0J-1202D01*
G02X190772Y1519098I-1203J0D01*
G01X189227Y1516425D01*
X189225Y1516421D01*
G02X188155Y1515768I-1070J550D01*
G02X186952Y1516970I-1J1202D01*
G01Y1516972D01*
G02X187102Y1517551I1203J-3D01*
G01X188668Y1520261D01*
X188670Y1520264D01*
G37*
G36*
G01X217016D02*
G02X218076Y1520900I1060J-565D01*
G02X219278Y1519698I0J-1202D01*
G02X219118Y1519098I-1203J0D01*
G01X217573Y1516425D01*
X217571Y1516421D01*
G02X216501Y1515768I-1070J550D01*
G02X215298Y1516970I-1J1202D01*
G01Y1516972D01*
G02X215448Y1517551I1203J-3D01*
G01X217014Y1520261D01*
X217016Y1520264D01*
G37*
G36*
G01X1267409Y1566902D02*
G02X1268469Y1567538I1060J-565D01*
G02X1269672Y1566336I1J-1202D01*
G02X1269511Y1565736I-1204J1D01*
G01X1267966Y1563063D01*
X1267964Y1563059D01*
G02X1266894Y1562406I-1070J550D01*
G02X1265692Y1563608I0J1202D01*
G01Y1563610D01*
G02X1265841Y1564189I1202J-1D01*
G01X1267407Y1566899D01*
X1267409Y1566902D01*
G37*
G36*
G01X1262684D02*
G02X1263744Y1567538I1060J-565D01*
G02X1264946Y1566336I0J-1202D01*
G02X1264786Y1565736I-1203J0D01*
G01X1263241Y1563063D01*
X1263239Y1563059D01*
G02X1262169Y1562406I-1070J550D01*
G02X1260966Y1563608I-1J1202D01*
G01Y1563610D01*
G02X1261116Y1564189I1203J-3D01*
G01X1262682Y1566899D01*
X1262684Y1566902D01*
G37*
G36*
G01X1257960D02*
G02X1259020Y1567538I1060J-565D01*
G02X1260222Y1566336I0J-1202D01*
G02X1260062Y1565736I-1203J0D01*
G01X1258517Y1563063D01*
X1258515Y1563059D01*
G02X1257445Y1562406I-1070J550D01*
G02X1256242Y1563608I-1J1202D01*
G01Y1563610D01*
G02X1256392Y1564189I1203J-3D01*
G01X1257958Y1566899D01*
X1257960Y1566902D01*
G37*
G36*
G01X1253235D02*
G02X1254295Y1567538I1060J-565D01*
G02X1255498Y1566336I1J-1202D01*
G02X1255337Y1565736I-1204J1D01*
G01X1253792Y1563063D01*
X1253790Y1563059D01*
G02X1252720Y1562406I-1070J550D01*
G02X1251518Y1563608I0J1202D01*
G01Y1563610D01*
G02X1251667Y1564189I1202J-1D01*
G01X1253233Y1566899D01*
X1253235Y1566902D01*
G37*
G36*
G01X1248511D02*
G02X1249571Y1567538I1060J-565D01*
G02X1250774Y1566336I1J-1202D01*
G02X1250613Y1565736I-1204J1D01*
G01X1249068Y1563063D01*
X1249066Y1563059D01*
G02X1247996Y1562406I-1070J550D01*
G02X1246794Y1563608I0J1202D01*
G01Y1563610D01*
G02X1246943Y1564189I1202J-1D01*
G01X1248509Y1566899D01*
X1248511Y1566902D01*
G37*
G36*
G01X1243787D02*
G02X1244847Y1567538I1060J-565D01*
G02X1246050Y1566336I1J-1202D01*
G02X1245889Y1565736I-1204J1D01*
G01X1244344Y1563063D01*
X1244342Y1563059D01*
G02X1243272Y1562406I-1070J550D01*
G02X1242070Y1563608I0J1202D01*
G01Y1563610D01*
G02X1242219Y1564189I1202J-1D01*
G01X1243785Y1566899D01*
X1243787Y1566902D01*
G37*
G36*
G01X1239062D02*
G02X1240122Y1567538I1060J-565D01*
G02X1241324Y1566336I0J-1202D01*
G02X1241164Y1565736I-1203J0D01*
G01X1239619Y1563063D01*
X1239617Y1563059D01*
G02X1238547Y1562406I-1070J550D01*
G02X1237344Y1563608I-1J1202D01*
G01Y1563610D01*
G02X1237494Y1564189I1203J-3D01*
G01X1239060Y1566899D01*
X1239062Y1566902D01*
G37*
G36*
G01X1234338D02*
G02X1235398Y1567538I1060J-565D01*
G02X1236600Y1566336I0J-1202D01*
G02X1236440Y1565736I-1203J0D01*
G01X1234895Y1563063D01*
X1234893Y1563059D01*
G02X1233823Y1562406I-1070J550D01*
G02X1232620Y1563608I-1J1202D01*
G01Y1563610D01*
G02X1232770Y1564189I1203J-3D01*
G01X1234336Y1566899D01*
X1234338Y1566902D01*
G37*
G36*
G01X1220165D02*
G02X1221225Y1567538I1060J-565D01*
G02X1222428Y1566336I1J-1202D01*
G02X1222267Y1565736I-1204J1D01*
G01X1220722Y1563063D01*
X1220720Y1563059D01*
G02X1219650Y1562406I-1070J550D01*
G02X1218448Y1563608I0J1202D01*
G01Y1563610D01*
G02X1218597Y1564189I1202J-1D01*
G01X1220163Y1566899D01*
X1220165Y1566902D01*
G37*
G36*
G01X1215440D02*
G02X1216500Y1567538I1060J-565D01*
G02X1217702Y1566336I0J-1202D01*
G02X1217542Y1565736I-1203J0D01*
G01X1215997Y1563063D01*
X1215995Y1563059D01*
G02X1214925Y1562406I-1070J550D01*
G02X1213722Y1563608I-1J1202D01*
G01Y1563610D01*
G02X1213872Y1564189I1203J-3D01*
G01X1215438Y1566899D01*
X1215440Y1566902D01*
G37*
G36*
G01X1210716D02*
G02X1211776Y1567538I1060J-565D01*
G02X1212978Y1566336I0J-1202D01*
G02X1212818Y1565736I-1203J0D01*
G01X1211273Y1563063D01*
X1211271Y1563059D01*
G02X1210201Y1562406I-1070J550D01*
G02X1208998Y1563608I-1J1202D01*
G01Y1563610D01*
G02X1209148Y1564189I1203J-3D01*
G01X1210714Y1566899D01*
X1210716Y1566902D01*
G37*
G36*
G01X1205991D02*
G02X1207051Y1567538I1060J-565D01*
G02X1208254Y1566336I1J-1202D01*
G02X1208093Y1565736I-1204J1D01*
G01X1206548Y1563063D01*
X1206546Y1563059D01*
G02X1205476Y1562406I-1070J550D01*
G02X1204274Y1563608I0J1202D01*
G01Y1563610D01*
G02X1204423Y1564189I1202J-1D01*
G01X1205989Y1566899D01*
X1205991Y1566902D01*
G37*
G36*
G01X1201267D02*
G02X1202327Y1567538I1060J-565D01*
G02X1203530Y1566336I1J-1202D01*
G02X1203369Y1565736I-1204J1D01*
G01X1201824Y1563063D01*
X1201822Y1563059D01*
G02X1200752Y1562406I-1070J550D01*
G02X1199550Y1563608I0J1202D01*
G01Y1563610D01*
G02X1199699Y1564189I1202J-1D01*
G01X1201265Y1566899D01*
X1201267Y1566902D01*
G37*
G36*
G01X1196543D02*
G02X1197603Y1567538I1060J-565D01*
G02X1198806Y1566336I1J-1202D01*
G02X1198645Y1565736I-1204J1D01*
G01X1197100Y1563063D01*
X1197098Y1563059D01*
G02X1196028Y1562406I-1070J550D01*
G02X1194826Y1563608I0J1202D01*
G01Y1563610D01*
G02X1194975Y1564189I1202J-1D01*
G01X1196541Y1566899D01*
X1196543Y1566902D01*
G37*
G36*
G01X1229613D02*
G02X1230673Y1567538I1060J-565D01*
G02X1231876Y1566336I1J-1202D01*
G02X1231715Y1565736I-1204J1D01*
G01X1230170Y1563063D01*
X1230168Y1563059D01*
G02X1229098Y1562406I-1070J550D01*
G02X1227896Y1563608I0J1202D01*
G01Y1563610D01*
G02X1228045Y1564189I1202J-1D01*
G01X1229611Y1566899D01*
X1229613Y1566902D01*
G37*
G36*
G01X1224889D02*
G02X1225949Y1567538I1060J-565D01*
G02X1227152Y1566336I1J-1202D01*
G02X1226991Y1565736I-1204J1D01*
G01X1225446Y1563063D01*
X1225444Y1563059D01*
G02X1224374Y1562406I-1070J550D01*
G02X1223172Y1563608I0J1202D01*
G01Y1563610D01*
G02X1223321Y1564189I1202J-1D01*
G01X1224887Y1566899D01*
X1224889Y1566902D01*
G37*
G36*
G01X193394Y1520264D02*
G02X194454Y1520900I1060J-565D01*
G02X195656Y1519698I0J-1202D01*
G02X195496Y1519098I-1203J0D01*
G01X193951Y1516425D01*
X193949Y1516421D01*
G02X192879Y1515768I-1070J550D01*
G02X191676Y1516970I-1J1202D01*
G01Y1516972D01*
G02X191826Y1517551I1203J-3D01*
G01X193392Y1520261D01*
X193394Y1520264D01*
G37*
G36*
G01X1210716Y1553264D02*
G02X1211776Y1553900I1060J-565D01*
G02X1212978Y1552698I0J-1202D01*
G02X1212818Y1552098I-1203J0D01*
G01X1211273Y1549425D01*
X1211271Y1549421D01*
G02X1210201Y1548768I-1070J550D01*
G02X1208998Y1549970I-1J1202D01*
G01Y1549972D01*
G02X1209148Y1550551I1203J-3D01*
G01X1210714Y1553261D01*
X1210716Y1553264D01*
G37*
G36*
G01X632873Y1533902D02*
G02X633933Y1534538I1060J-565D01*
G02X635136Y1533336I1J-1202D01*
G02X634975Y1532736I-1204J1D01*
G01X633430Y1530063D01*
X633428Y1530059D01*
G02X632358Y1529406I-1070J550D01*
G02X631156Y1530608I0J1202D01*
G01Y1530610D01*
G02X631305Y1531189I1202J-1D01*
G01X632871Y1533899D01*
X632873Y1533902D01*
G37*
G36*
G01X628149D02*
G02X629209Y1534538I1060J-565D01*
G02X630412Y1533336I1J-1202D01*
G02X630251Y1532736I-1204J1D01*
G01X628706Y1530063D01*
X628704Y1530059D01*
G02X627634Y1529406I-1070J550D01*
G02X626432Y1530608I0J1202D01*
G01Y1530610D01*
G02X626581Y1531189I1202J-1D01*
G01X628147Y1533899D01*
X628149Y1533902D01*
G37*
G36*
G01X623424D02*
G02X624484Y1534538I1060J-565D01*
G02X625686Y1533336I0J-1202D01*
G02X625526Y1532736I-1203J0D01*
G01X623981Y1530063D01*
X623979Y1530059D01*
G02X622909Y1529406I-1070J550D01*
G02X621706Y1530608I-1J1202D01*
G01Y1530610D01*
G02X621856Y1531189I1203J-3D01*
G01X623422Y1533899D01*
X623424Y1533902D01*
G37*
G36*
G01X618700D02*
G02X619760Y1534538I1060J-565D01*
G02X620962Y1533336I0J-1202D01*
G02X620802Y1532736I-1203J0D01*
G01X619257Y1530063D01*
X619255Y1530059D01*
G02X618185Y1529406I-1070J550D01*
G02X616982Y1530608I-1J1202D01*
G01Y1530610D01*
G02X617132Y1531189I1203J-3D01*
G01X618698Y1533899D01*
X618700Y1533902D01*
G37*
G36*
G01X604527D02*
G02X605587Y1534538I1060J-565D01*
G02X606790Y1533336I1J-1202D01*
G02X606629Y1532736I-1204J1D01*
G01X605084Y1530063D01*
X605082Y1530059D01*
G02X604012Y1529406I-1070J550D01*
G02X602810Y1530608I0J1202D01*
G01Y1530610D01*
G02X602959Y1531189I1202J-1D01*
G01X604525Y1533899D01*
X604527Y1533902D01*
G37*
G36*
G01X585629D02*
G02X586689Y1534538I1060J-565D01*
G02X587892Y1533336I1J-1202D01*
G02X587731Y1532736I-1204J1D01*
G01X586186Y1530063D01*
X586184Y1530059D01*
G02X585114Y1529406I-1070J550D01*
G02X583912Y1530608I0J1202D01*
G01Y1530610D01*
G02X584061Y1531189I1202J-1D01*
G01X585627Y1533899D01*
X585629Y1533902D01*
G37*
G36*
G01X580905D02*
G02X581965Y1534538I1060J-565D01*
G02X583168Y1533336I1J-1202D01*
G02X583007Y1532736I-1204J1D01*
G01X581462Y1530063D01*
X581460Y1530059D01*
G02X580390Y1529406I-1070J550D01*
G02X579188Y1530608I0J1202D01*
G01Y1530610D01*
G02X579337Y1531189I1202J-1D01*
G01X580903Y1533899D01*
X580905Y1533902D01*
G37*
G36*
G01X613975D02*
G02X615035Y1534538I1060J-565D01*
G02X616238Y1533336I1J-1202D01*
G02X616077Y1532736I-1204J1D01*
G01X614532Y1530063D01*
X614530Y1530059D01*
G02X613460Y1529406I-1070J550D01*
G02X612258Y1530608I0J1202D01*
G01Y1530610D01*
G02X612407Y1531189I1202J-1D01*
G01X613973Y1533899D01*
X613975Y1533902D01*
G37*
G36*
G01X609251D02*
G02X610311Y1534538I1060J-565D01*
G02X611514Y1533336I1J-1202D01*
G02X611353Y1532736I-1204J1D01*
G01X609808Y1530063D01*
X609806Y1530059D01*
G02X608736Y1529406I-1070J550D01*
G02X607534Y1530608I0J1202D01*
G01Y1530610D01*
G02X607683Y1531189I1202J-1D01*
G01X609249Y1533899D01*
X609251Y1533902D01*
G37*
G36*
G01X1659645Y1566902D02*
G02X1660705Y1567538I1060J-565D01*
G02X1661908Y1566336I1J-1202D01*
G02X1661747Y1565736I-1204J1D01*
G01X1660202Y1563063D01*
X1660200Y1563059D01*
G02X1659130Y1562406I-1070J550D01*
G02X1657928Y1563608I0J1202D01*
G01Y1563610D01*
G02X1658077Y1564189I1202J-1D01*
G01X1659643Y1566899D01*
X1659645Y1566902D01*
G37*
G36*
G01X1654920D02*
G02X1655980Y1567538I1060J-565D01*
G02X1657182Y1566336I0J-1202D01*
G02X1657022Y1565736I-1203J0D01*
G01X1655477Y1563063D01*
X1655475Y1563059D01*
G02X1654405Y1562406I-1070J550D01*
G02X1653202Y1563608I-1J1202D01*
G01Y1563610D01*
G02X1653352Y1564189I1203J-3D01*
G01X1654918Y1566899D01*
X1654920Y1566902D01*
G37*
G36*
G01X1650196D02*
G02X1651256Y1567538I1060J-565D01*
G02X1652458Y1566336I0J-1202D01*
G02X1652298Y1565736I-1203J0D01*
G01X1650753Y1563063D01*
X1650751Y1563059D01*
G02X1649681Y1562406I-1070J550D01*
G02X1648478Y1563608I-1J1202D01*
G01Y1563610D01*
G02X1648628Y1564189I1203J-3D01*
G01X1650194Y1566899D01*
X1650196Y1566902D01*
G37*
G36*
G01X1645471D02*
G02X1646531Y1567538I1060J-565D01*
G02X1647734Y1566336I1J-1202D01*
G02X1647573Y1565736I-1204J1D01*
G01X1646028Y1563063D01*
X1646026Y1563059D01*
G02X1644956Y1562406I-1070J550D01*
G02X1643754Y1563608I0J1202D01*
G01Y1563610D01*
G02X1643903Y1564189I1202J-1D01*
G01X1645469Y1566899D01*
X1645471Y1566902D01*
G37*
G36*
G01X1640747D02*
G02X1641807Y1567538I1060J-565D01*
G02X1643010Y1566336I1J-1202D01*
G02X1642849Y1565736I-1204J1D01*
G01X1641304Y1563063D01*
X1641302Y1563059D01*
G02X1640232Y1562406I-1070J550D01*
G02X1639030Y1563608I0J1202D01*
G01Y1563610D01*
G02X1639179Y1564189I1202J-1D01*
G01X1640745Y1566899D01*
X1640747Y1566902D01*
G37*
G36*
G01X1636023D02*
G02X1637083Y1567538I1060J-565D01*
G02X1638286Y1566336I1J-1202D01*
G02X1638125Y1565736I-1204J1D01*
G01X1636580Y1563063D01*
X1636578Y1563059D01*
G02X1635508Y1562406I-1070J550D01*
G02X1634306Y1563608I0J1202D01*
G01Y1563610D01*
G02X1634455Y1564189I1202J-1D01*
G01X1636021Y1566899D01*
X1636023Y1566902D01*
G37*
G36*
G01X1631298D02*
G02X1632358Y1567538I1060J-565D01*
G02X1633560Y1566336I0J-1202D01*
G02X1633400Y1565736I-1203J0D01*
G01X1631855Y1563063D01*
X1631853Y1563059D01*
G02X1630783Y1562406I-1070J550D01*
G02X1629580Y1563608I-1J1202D01*
G01Y1563610D01*
G02X1629730Y1564189I1203J-3D01*
G01X1631296Y1566899D01*
X1631298Y1566902D01*
G37*
G36*
G01X1626574D02*
G02X1627634Y1567538I1060J-565D01*
G02X1628836Y1566336I0J-1202D01*
G02X1628676Y1565736I-1203J0D01*
G01X1627131Y1563063D01*
X1627129Y1563059D01*
G02X1626059Y1562406I-1070J550D01*
G02X1624856Y1563608I-1J1202D01*
G01Y1563610D01*
G02X1625006Y1564189I1203J-3D01*
G01X1626572Y1566899D01*
X1626574Y1566902D01*
G37*
G36*
G01X1612401D02*
G02X1613461Y1567538I1060J-565D01*
G02X1614664Y1566336I1J-1202D01*
G02X1614503Y1565736I-1204J1D01*
G01X1612958Y1563063D01*
X1612956Y1563059D01*
G02X1611886Y1562406I-1070J550D01*
G02X1610684Y1563608I0J1202D01*
G01Y1563610D01*
G02X1610833Y1564189I1202J-1D01*
G01X1612399Y1566899D01*
X1612401Y1566902D01*
G37*
G36*
G01X1607676D02*
G02X1608736Y1567538I1060J-565D01*
G02X1609938Y1566336I0J-1202D01*
G02X1609778Y1565736I-1203J0D01*
G01X1608233Y1563063D01*
X1608231Y1563059D01*
G02X1607161Y1562406I-1070J550D01*
G02X1605958Y1563608I-1J1202D01*
G01Y1563610D01*
G02X1606108Y1564189I1203J-3D01*
G01X1607674Y1566899D01*
X1607676Y1566902D01*
G37*
G36*
G01X1602952D02*
G02X1604012Y1567538I1060J-565D01*
G02X1605214Y1566336I0J-1202D01*
G02X1605054Y1565736I-1203J0D01*
G01X1603509Y1563063D01*
X1603507Y1563059D01*
G02X1602437Y1562406I-1070J550D01*
G02X1601234Y1563608I-1J1202D01*
G01Y1563610D01*
G02X1601384Y1564189I1203J-3D01*
G01X1602950Y1566899D01*
X1602952Y1566902D01*
G37*
G36*
G01X1598227D02*
G02X1599287Y1567538I1060J-565D01*
G02X1600490Y1566336I1J-1202D01*
G02X1600329Y1565736I-1204J1D01*
G01X1598784Y1563063D01*
X1598782Y1563059D01*
G02X1597712Y1562406I-1070J550D01*
G02X1596510Y1563608I0J1202D01*
G01Y1563610D01*
G02X1596659Y1564189I1202J-1D01*
G01X1598225Y1566899D01*
X1598227Y1566902D01*
G37*
G36*
G01X1593503D02*
G02X1594563Y1567538I1060J-565D01*
G02X1595766Y1566336I1J-1202D01*
G02X1595605Y1565736I-1204J1D01*
G01X1594060Y1563063D01*
X1594058Y1563059D01*
G02X1592988Y1562406I-1070J550D01*
G02X1591786Y1563608I0J1202D01*
G01Y1563610D01*
G02X1591935Y1564189I1202J-1D01*
G01X1593501Y1566899D01*
X1593503Y1566902D01*
G37*
G36*
G01X1588779D02*
G02X1589839Y1567538I1060J-565D01*
G02X1591042Y1566336I1J-1202D01*
G02X1590881Y1565736I-1204J1D01*
G01X1589336Y1563063D01*
X1589334Y1563059D01*
G02X1588264Y1562406I-1070J550D01*
G02X1587062Y1563608I0J1202D01*
G01Y1563610D01*
G02X1587211Y1564189I1202J-1D01*
G01X1588777Y1566899D01*
X1588779Y1566902D01*
G37*
G36*
G01X1621849D02*
G02X1622909Y1567538I1060J-565D01*
G02X1624112Y1566336I1J-1202D01*
G02X1623951Y1565736I-1204J1D01*
G01X1622406Y1563063D01*
X1622404Y1563059D01*
G02X1621334Y1562406I-1070J550D01*
G02X1620132Y1563608I0J1202D01*
G01Y1563610D01*
G02X1620281Y1564189I1202J-1D01*
G01X1621847Y1566899D01*
X1621849Y1566902D01*
G37*
G36*
G01X1617125D02*
G02X1618185Y1567538I1060J-565D01*
G02X1619388Y1566336I1J-1202D01*
G02X1619227Y1565736I-1204J1D01*
G01X1617682Y1563063D01*
X1617680Y1563059D01*
G02X1616610Y1562406I-1070J550D01*
G02X1615408Y1563608I0J1202D01*
G01Y1563610D01*
G02X1615557Y1564189I1202J-1D01*
G01X1617123Y1566899D01*
X1617125Y1566902D01*
G37*
G36*
G01X651771Y1533902D02*
G02X652831Y1534538I1060J-565D01*
G02X654034Y1533336I1J-1202D01*
G02X653873Y1532736I-1204J1D01*
G01X652328Y1530063D01*
X652326Y1530059D01*
G02X651256Y1529406I-1070J550D01*
G02X650054Y1530608I0J1202D01*
G01Y1530610D01*
G02X650203Y1531189I1202J-1D01*
G01X651769Y1533899D01*
X651771Y1533902D01*
G37*
G36*
G01X647046D02*
G02X648106Y1534538I1060J-565D01*
G02X649308Y1533336I0J-1202D01*
G02X649148Y1532736I-1203J0D01*
G01X647603Y1530063D01*
X647601Y1530059D01*
G02X646531Y1529406I-1070J550D01*
G02X645328Y1530608I-1J1202D01*
G01Y1530610D01*
G02X645478Y1531189I1203J-3D01*
G01X647044Y1533899D01*
X647046Y1533902D01*
G37*
G36*
G01X642322D02*
G02X643382Y1534538I1060J-565D01*
G02X644584Y1533336I0J-1202D01*
G02X644424Y1532736I-1203J0D01*
G01X642879Y1530063D01*
X642877Y1530059D01*
G02X641807Y1529406I-1070J550D01*
G02X640604Y1530608I-1J1202D01*
G01Y1530610D01*
G02X640754Y1531189I1203J-3D01*
G01X642320Y1533899D01*
X642322Y1533902D01*
G37*
G36*
G01X637597D02*
G02X638657Y1534538I1060J-565D01*
G02X639860Y1533336I1J-1202D01*
G02X639699Y1532736I-1204J1D01*
G01X638154Y1530063D01*
X638152Y1530059D01*
G02X637082Y1529406I-1070J550D01*
G02X635880Y1530608I0J1202D01*
G01Y1530610D01*
G02X636029Y1531189I1202J-1D01*
G01X637595Y1533899D01*
X637597Y1533902D01*
G37*
G36*
G01X599802D02*
G02X600862Y1534538I1060J-565D01*
G02X602064Y1533336I0J-1202D01*
G02X601904Y1532736I-1203J0D01*
G01X600359Y1530063D01*
X600357Y1530059D01*
G02X599287Y1529406I-1070J550D01*
G02X598084Y1530608I-1J1202D01*
G01Y1530610D01*
G02X598234Y1531189I1203J-3D01*
G01X599800Y1533899D01*
X599802Y1533902D01*
G37*
G36*
G01X595078D02*
G02X596138Y1534538I1060J-565D01*
G02X597340Y1533336I0J-1202D01*
G02X597180Y1532736I-1203J0D01*
G01X595635Y1530063D01*
X595633Y1530059D01*
G02X594563Y1529406I-1070J550D01*
G02X593360Y1530608I-1J1202D01*
G01Y1530610D01*
G02X593510Y1531189I1203J-3D01*
G01X595076Y1533899D01*
X595078Y1533902D01*
G37*
G36*
G01X590353D02*
G02X591413Y1534538I1060J-565D01*
G02X592616Y1533336I1J-1202D01*
G02X592455Y1532736I-1204J1D01*
G01X590910Y1530063D01*
X590908Y1530059D01*
G02X589838Y1529406I-1070J550D01*
G02X588636Y1530608I0J1202D01*
G01Y1530610D01*
G02X588785Y1531189I1202J-1D01*
G01X590351Y1533899D01*
X590353Y1533902D01*
G37*
G36*
G01X1196543Y1553264D02*
G02X1197603Y1553900I1060J-565D01*
G02X1198806Y1552698I1J-1202D01*
G02X1198645Y1552098I-1204J1D01*
G01X1197100Y1549425D01*
X1197098Y1549421D01*
G02X1196028Y1548768I-1070J550D01*
G02X1194826Y1549970I0J1202D01*
G01Y1549972D01*
G02X1194975Y1550551I1202J-1D01*
G01X1196541Y1553261D01*
X1196543Y1553264D01*
G37*
G36*
G01X198118Y1520264D02*
G02X199178Y1520900I1060J-565D01*
G02X200380Y1519698I0J-1202D01*
G02X200220Y1519098I-1203J0D01*
G01X198675Y1516425D01*
X198673Y1516421D01*
G02X197603Y1515768I-1070J550D01*
G02X196400Y1516970I-1J1202D01*
G01Y1516972D01*
G02X196550Y1517551I1203J-3D01*
G01X198116Y1520261D01*
X198118Y1520264D01*
G37*
G36*
G01X1201267Y1553264D02*
G02X1202327Y1553900I1060J-565D01*
G02X1203530Y1552698I1J-1202D01*
G02X1203369Y1552098I-1204J1D01*
G01X1201824Y1549425D01*
X1201822Y1549421D01*
G02X1200752Y1548768I-1070J550D01*
G02X1199550Y1549970I0J1202D01*
G01Y1549972D01*
G02X1199699Y1550551I1202J-1D01*
G01X1201265Y1553261D01*
X1201267Y1553264D01*
G37*
G36*
G01X651771Y1520264D02*
G02X652831Y1520900I1060J-565D01*
G02X654034Y1519698I1J-1202D01*
G02X653873Y1519098I-1204J1D01*
G01X652328Y1516425D01*
X652326Y1516421D01*
G02X651256Y1515768I-1070J550D01*
G02X650054Y1516970I0J1202D01*
G01Y1516972D01*
G02X650203Y1517551I1202J-1D01*
G01X651769Y1520261D01*
X651771Y1520264D01*
G37*
G36*
G01X509535D02*
G02X510595Y1520900I1060J-565D01*
G02X511798Y1519698I1J-1202D01*
G02X511637Y1519098I-1204J1D01*
G01X510092Y1516425D01*
X510090Y1516421D01*
G02X509020Y1515768I-1070J550D01*
G02X507818Y1516970I0J1202D01*
G01Y1516972D01*
G02X507967Y1517551I1202J-1D01*
G01X509533Y1520261D01*
X509535Y1520264D01*
G37*
G36*
G01X1385686Y1494092D02*
G02Y1497098I0J1503D01*
G01X1389086D01*
G02Y1494092I0J-1503D01*
G01X1385686D01*
G37*
G36*
G01X269851Y1451392D02*
G02Y1454398I0J1503D01*
G01X273251D01*
G02Y1451392I0J-1503D01*
G01X269851D01*
G37*
G36*
G01X256451D02*
G02Y1454398I0J1503D01*
G01X259851D01*
G02Y1451392I0J-1503D01*
G01X256451D01*
G37*
G36*
G01X249751Y1461092D02*
G02Y1464098I0J1503D01*
G01X253151D01*
G02Y1461092I0J-1503D01*
G01X249751D01*
G37*
G36*
G01X243051Y1470792D02*
G02Y1473798I0J1503D01*
G01X246451D01*
G02Y1470792I0J-1503D01*
G01X243051D01*
G37*
G36*
G01X229651Y1451392D02*
G02Y1454398I0J1503D01*
G01X233051D01*
G02Y1451392I0J-1503D01*
G01X229651D01*
G37*
G36*
G01X222951Y1461092D02*
G02Y1464098I0J1503D01*
G01X226351D01*
G02Y1461092I0J-1503D01*
G01X222951D01*
G37*
G36*
G01X216251Y1470792D02*
G02Y1473798I0J1503D01*
G01X219651D01*
G02Y1470792I0J-1503D01*
G01X216251D01*
G37*
G36*
G01X202851Y1451392D02*
G02Y1454398I0J1503D01*
G01X206251D01*
G02Y1451392I0J-1503D01*
G01X202851D01*
G37*
G36*
G01X196151Y1461092D02*
G02Y1464098I0J1503D01*
G01X199551D01*
G02Y1461092I0J-1503D01*
G01X196151D01*
G37*
G36*
G01X189451Y1470792D02*
G02Y1473798I0J1503D01*
G01X192851D01*
G02Y1470792I0J-1503D01*
G01X189451D01*
G37*
G36*
G01X176051Y1451392D02*
G02Y1454398I0J1503D01*
G01X179451D01*
G02Y1451392I0J-1503D01*
G01X176051D01*
G37*
G36*
G01X212286Y1590878D02*
G02Y1593882I0J1502D01*
G01X215686D01*
G02Y1590878I0J-1502D01*
G01X212286D01*
G37*
G36*
G01X200226D02*
G02Y1593882I0J1502D01*
G01X203626D01*
G02Y1590878I0J-1502D01*
G01X200226D01*
G37*
G36*
G01X1310609Y1633878D02*
G02Y1636882I0J1502D01*
G01X1314009D01*
G02Y1633878I0J-1502D01*
G01X1310609D01*
G37*
G36*
G01X1490363D02*
G02Y1636882I0J1502D01*
G01X1493763D01*
G02Y1633878I0J-1502D01*
G01X1490363D01*
G37*
G36*
G01X491919Y1593882D02*
G02Y1590878I0J-1502D01*
G01X488519D01*
G02Y1593882I0J1502D01*
G01X491919D01*
G37*
G36*
G01X500579Y1590878D02*
G02Y1593882I0J1502D01*
G01X503979D01*
G02Y1590878I0J-1502D01*
G01X500579D01*
G37*
G36*
G01X194196Y1600878D02*
G02Y1603882I0J1502D01*
G01X197596D01*
G02Y1600878I0J-1502D01*
G01X194196D01*
G37*
G36*
G01X350976D02*
G02Y1603882I0J1502D01*
G01X354376D01*
G02Y1600878I0J-1502D01*
G01X350976D01*
G37*
G36*
G01X194196Y1612790D02*
G02Y1615794I0J1502D01*
G01X197596D01*
G02Y1612790I0J-1502D01*
G01X194196D01*
G37*
G36*
G01X330913Y1451392D02*
G02Y1454398I0J1503D01*
G01X334313D01*
G02Y1451392I0J-1503D01*
G01X330913D01*
G37*
G36*
G01X1376939Y1655790D02*
G02Y1658794I0J1502D01*
G01X1380339D01*
G02Y1655790I0J-1502D01*
G01X1376939D01*
G37*
G36*
G01Y1623878D02*
G02Y1626882I0J1502D01*
G01X1380339D01*
G02Y1623878I0J-1502D01*
G01X1376939D01*
G37*
G36*
G01X1220159D02*
G02Y1626882I0J1502D01*
G01X1223559D01*
G02Y1623878I0J-1502D01*
G01X1220159D01*
G37*
G36*
G01X572939Y1590878D02*
G02Y1593882I0J1502D01*
G01X576339D01*
G02Y1590878I0J-1502D01*
G01X572939D01*
G37*
G36*
G01X536759D02*
G02Y1593882I0J1502D01*
G01X540159D01*
G02Y1590878I0J-1502D01*
G01X536759D01*
G37*
G36*
G01X344946D02*
G02Y1593882I0J1502D01*
G01X348346D01*
G02Y1590878I0J-1502D01*
G01X344946D01*
G37*
G36*
G01X248466D02*
G02Y1593882I0J1502D01*
G01X251866D01*
G02Y1590878I0J-1502D01*
G01X248466D01*
G37*
G36*
G01X230376Y1600878D02*
G02Y1603882I0J1502D01*
G01X233776D01*
G02Y1600878I0J-1502D01*
G01X230376D01*
G37*
G36*
G01X206256D02*
G02Y1603882I0J1502D01*
G01X209656D01*
G02Y1600878I0J-1502D01*
G01X206256D01*
G37*
G36*
G01X236406Y1590878D02*
G02Y1593882I0J1502D01*
G01X239806D01*
G02Y1590878I0J-1502D01*
G01X236406D01*
G37*
G36*
G01X554849Y1600878D02*
G02Y1603882I0J1502D01*
G01X558249D01*
G02Y1600878I0J-1502D01*
G01X554849D01*
G37*
G36*
G01X470429D02*
G02Y1603882I0J1502D01*
G01X473829D01*
G02Y1600878I0J-1502D01*
G01X470429D01*
G37*
G36*
G01X482489D02*
G02Y1603882I0J1502D01*
G01X485889D01*
G02Y1600878I0J-1502D01*
G01X482489D01*
G37*
G36*
G01X1370909Y1633878D02*
G02Y1636882I0J1502D01*
G01X1374309D01*
G02Y1633878I0J-1502D01*
G01X1370909D01*
G37*
G36*
G01X1358849D02*
G02Y1636882I0J1502D01*
G01X1362249D01*
G02Y1633878I0J-1502D01*
G01X1358849D01*
G37*
G36*
G01X1346789D02*
G02Y1636882I0J1502D01*
G01X1350189D01*
G02Y1633878I0J-1502D01*
G01X1346789D01*
G37*
G36*
G01X1528498Y1484392D02*
G02Y1487398I0J1503D01*
G01X1531898D01*
G02Y1484392I0J-1503D01*
G01X1528498D01*
G37*
G36*
G01X1468198Y1494092D02*
G02Y1497098I0J1503D01*
G01X1471598D01*
G02Y1494092I0J-1503D01*
G01X1468198D01*
G37*
G36*
G01X615186Y1461092D02*
G02Y1464098I0J1503D01*
G01X618586D01*
G02Y1461092I0J-1503D01*
G01X615186D01*
G37*
G36*
G01X453624Y1470792D02*
G02Y1473798I0J1503D01*
G01X457024D01*
G02Y1470792I0J-1503D01*
G01X453624D01*
G37*
G36*
G01X1673360Y1487398D02*
G02Y1484392I0J-1503D01*
G01X1669960D01*
G02Y1487398I0J1503D01*
G01X1673360D01*
G37*
G36*
G01X1629760Y1484392D02*
G02Y1487398I0J1503D01*
G01X1633160D01*
G02Y1484392I0J-1503D01*
G01X1629760D01*
G37*
G36*
G01X1541898D02*
G02Y1487398I0J1503D01*
G01X1545298D01*
G02Y1484392I0J-1503D01*
G01X1541898D01*
G37*
G36*
G01X1501698D02*
G02Y1487398I0J1503D01*
G01X1505098D01*
G02Y1484392I0J-1503D01*
G01X1501698D01*
G37*
G36*
G01X1405786D02*
G02Y1487398I0J1503D01*
G01X1409186D01*
G02Y1484392I0J-1503D01*
G01X1405786D01*
G37*
G36*
G01X1365586D02*
G02Y1487398I0J1503D01*
G01X1368986D01*
G02Y1484392I0J-1503D01*
G01X1365586D01*
G37*
G36*
G01X1305286Y1494092D02*
G02Y1497098I0J1503D01*
G01X1308686D01*
G02Y1494092I0J-1503D01*
G01X1305286D01*
G37*
G36*
G01X1277724Y1484392D02*
G02Y1487398I0J1503D01*
G01X1281124D01*
G02Y1484392I0J-1503D01*
G01X1277724D01*
G37*
G36*
G01X1264324D02*
G02Y1487398I0J1503D01*
G01X1267724D01*
G02Y1484392I0J-1503D01*
G01X1264324D01*
G37*
G36*
G01X662086Y1451392D02*
G02Y1454398I0J1503D01*
G01X665486D01*
G02Y1451392I0J-1503D01*
G01X662086D01*
G37*
G36*
G01X621886D02*
G02Y1454398I0J1503D01*
G01X625286D01*
G02Y1451392I0J-1503D01*
G01X621886D01*
G37*
G36*
G01X534024D02*
G02Y1454398I0J1503D01*
G01X537424D01*
G02Y1451392I0J-1503D01*
G01X534024D01*
G37*
G36*
G01X520624D02*
G02Y1454398I0J1503D01*
G01X524024D01*
G02Y1451392I0J-1503D01*
G01X520624D01*
G37*
G36*
G01X397913D02*
G02Y1454398I0J1503D01*
G01X401313D01*
G02Y1451392I0J-1503D01*
G01X397913D01*
G37*
G36*
G01X371113Y1470792D02*
G02Y1473798I0J1503D01*
G01X374513D01*
G02Y1470792I0J-1503D01*
G01X371113D01*
G37*
G36*
G01X317513D02*
G02Y1473798I0J1503D01*
G01X320913D01*
G02Y1470792I0J-1503D01*
G01X317513D01*
G37*
G36*
G01X357713Y1451392D02*
G02Y1454398I0J1503D01*
G01X361113D01*
G02Y1451392I0J-1503D01*
G01X357713D01*
G37*
G36*
G01X1496393Y1623878D02*
G02Y1626882I0J1502D01*
G01X1499793D01*
G02Y1623878I0J-1502D01*
G01X1496393D01*
G37*
G36*
G01X1508453D02*
G02Y1626882I0J1502D01*
G01X1511853D01*
G02Y1623878I0J-1502D01*
G01X1508453D01*
G37*
G36*
G01X1322669Y1633878D02*
G02Y1636882I0J1502D01*
G01X1326069D01*
G02Y1633878I0J-1502D01*
G01X1322669D01*
G37*
G36*
G01X597059Y1590878D02*
G02Y1593882I0J1502D01*
G01X600459D01*
G02Y1590878I0J-1502D01*
G01X597059D01*
G37*
G36*
G01X476459Y1622790D02*
G02Y1625794I0J1502D01*
G01X479859D01*
G02Y1622790I0J-1502D01*
G01X476459D01*
G37*
G36*
G01X1215440Y1553264D02*
G02X1216500Y1553900I1060J-565D01*
G02X1217702Y1552698I0J-1202D01*
G02X1217542Y1552098I-1203J0D01*
G01X1215997Y1549425D01*
X1215995Y1549421D01*
G02X1214925Y1548768I-1070J550D01*
G02X1213722Y1549970I-1J1202D01*
G01Y1549972D01*
G02X1213872Y1550551I1203J-3D01*
G01X1215438Y1553261D01*
X1215440Y1553264D01*
G37*
G36*
G01X1220165D02*
G02X1221225Y1553900I1060J-565D01*
G02X1222428Y1552698I1J-1202D01*
G02X1222267Y1552098I-1204J1D01*
G01X1220722Y1549425D01*
X1220720Y1549421D01*
G02X1219650Y1548768I-1070J550D01*
G02X1218448Y1549970I0J1202D01*
G01Y1549972D01*
G02X1218597Y1550551I1202J-1D01*
G01X1220163Y1553261D01*
X1220165Y1553264D01*
G37*
G36*
G01X1224889D02*
G02X1225949Y1553900I1060J-565D01*
G02X1227152Y1552698I1J-1202D01*
G02X1226991Y1552098I-1204J1D01*
G01X1225446Y1549425D01*
X1225444Y1549421D01*
G02X1224374Y1548768I-1070J550D01*
G02X1223172Y1549970I0J1202D01*
G01Y1549972D01*
G02X1223321Y1550551I1202J-1D01*
G01X1224887Y1553261D01*
X1224889Y1553264D01*
G37*
G36*
G01X1243787D02*
G02X1244847Y1553900I1060J-565D01*
G02X1246050Y1552698I1J-1202D01*
G02X1245889Y1552098I-1204J1D01*
G01X1244344Y1549425D01*
X1244342Y1549421D01*
G02X1243272Y1548768I-1070J550D01*
G02X1242070Y1549970I0J1202D01*
G01Y1549972D01*
G02X1242219Y1550551I1202J-1D01*
G01X1243785Y1553261D01*
X1243787Y1553264D01*
G37*
G36*
G01X1253236D02*
G02X1254296Y1553900I1060J-565D01*
G02X1255498Y1552698I0J-1202D01*
G02X1255338Y1552098I-1203J0D01*
G01X1253793Y1549425D01*
X1253791Y1549421D01*
G02X1252721Y1548768I-1070J550D01*
G02X1251518Y1549970I-1J1202D01*
G01Y1549972D01*
G02X1251668Y1550551I1203J-3D01*
G01X1253234Y1553261D01*
X1253236Y1553264D01*
G37*
G36*
G01X1267409D02*
G02X1268469Y1553900I1060J-565D01*
G02X1269672Y1552698I1J-1202D01*
G02X1269511Y1552098I-1204J1D01*
G01X1267966Y1549425D01*
X1267964Y1549421D01*
G02X1266894Y1548768I-1070J550D01*
G02X1265692Y1549970I0J1202D01*
G01Y1549972D01*
G02X1265841Y1550551I1202J-1D01*
G01X1267407Y1553261D01*
X1267409Y1553264D01*
G37*
G36*
G01X1262685D02*
G02X1263745Y1553900I1060J-565D01*
G02X1264948Y1552698I1J-1202D01*
G02X1264787Y1552098I-1204J1D01*
G01X1263242Y1549425D01*
X1263240Y1549421D01*
G02X1262170Y1548768I-1070J550D01*
G02X1260968Y1549970I0J1202D01*
G01Y1549972D01*
G02X1261117Y1550551I1202J-1D01*
G01X1262683Y1553261D01*
X1262685Y1553264D01*
G37*
G36*
G01X1329329D02*
G02X1330389Y1553900I1060J-565D01*
G02X1331592Y1552698I1J-1202D01*
G02X1331431Y1552098I-1204J1D01*
G01X1329886Y1549425D01*
X1329884Y1549421D01*
G02X1328814Y1548768I-1070J550D01*
G02X1327612Y1549970I0J1202D01*
G01Y1549972D01*
G02X1327761Y1550551I1202J-1D01*
G01X1329327Y1553261D01*
X1329329Y1553264D01*
G37*
G36*
G01X1324605D02*
G02X1325665Y1553900I1060J-565D01*
G02X1326868Y1552698I1J-1202D01*
G02X1326707Y1552098I-1204J1D01*
G01X1325162Y1549425D01*
X1325160Y1549421D01*
G02X1324090Y1548768I-1070J550D01*
G02X1322888Y1549970I0J1202D01*
G01Y1549972D01*
G02X1323037Y1550551I1202J-1D01*
G01X1324603Y1553261D01*
X1324605Y1553264D01*
G37*
G36*
G01X1610963Y1633878D02*
G02Y1636882I0J1502D01*
G01X1614363D01*
G02Y1633878I0J-1502D01*
G01X1610963D01*
G37*
G36*
G01X1598903D02*
G02Y1636882I0J1502D01*
G01X1602303D01*
G02Y1633878I0J-1502D01*
G01X1598903D01*
G37*
G36*
G01X1586843D02*
G02Y1636882I0J1502D01*
G01X1590243D01*
G02Y1633878I0J-1502D01*
G01X1586843D01*
G37*
G36*
G01X1641113Y1655790D02*
G02Y1658794I0J1502D01*
G01X1644513D01*
G02Y1655790I0J-1502D01*
G01X1641113D01*
G37*
G36*
G01X1574783Y1633878D02*
G02Y1636882I0J1502D01*
G01X1578183D01*
G02Y1633878I0J-1502D01*
G01X1574783D01*
G37*
G36*
G01X1562723D02*
G02Y1636882I0J1502D01*
G01X1566123D01*
G02Y1633878I0J-1502D01*
G01X1562723D01*
G37*
G36*
G01X1592873Y1623878D02*
G02Y1626882I0J1502D01*
G01X1596273D01*
G02Y1623878I0J-1502D01*
G01X1592873D01*
G37*
G36*
G01X1550663Y1633878D02*
G02Y1636882I0J1502D01*
G01X1554063D01*
G02Y1633878I0J-1502D01*
G01X1550663D01*
G37*
G36*
G01X1580813Y1623878D02*
G02Y1626882I0J1502D01*
G01X1584213D01*
G02Y1623878I0J-1502D01*
G01X1580813D01*
G37*
G36*
G01X1538603Y1633878D02*
G02Y1636882I0J1502D01*
G01X1542003D01*
G02Y1633878I0J-1502D01*
G01X1538603D01*
G37*
G36*
G01X1568753Y1623878D02*
G02Y1626882I0J1502D01*
G01X1572153D01*
G02Y1623878I0J-1502D01*
G01X1568753D01*
G37*
G36*
G01X1526543Y1633878D02*
G02Y1636882I0J1502D01*
G01X1529943D01*
G02Y1633878I0J-1502D01*
G01X1526543D01*
G37*
G36*
G01X1514483D02*
G02Y1636882I0J1502D01*
G01X1517883D01*
G02Y1633878I0J-1502D01*
G01X1514483D01*
G37*
G36*
G01X1478303D02*
G02Y1636882I0J1502D01*
G01X1481703D01*
G02Y1633878I0J-1502D01*
G01X1478303D01*
G37*
G36*
G01X1466243D02*
G02Y1636882I0J1502D01*
G01X1469643D01*
G02Y1633878I0J-1502D01*
G01X1466243D01*
G37*
G36*
G01X1370909Y1645790D02*
G02Y1648794I0J1502D01*
G01X1374309D01*
G02Y1645790I0J-1502D01*
G01X1370909D01*
G37*
G36*
G01X1352819Y1655790D02*
G02Y1658794I0J1502D01*
G01X1356219D01*
G02Y1655790I0J-1502D01*
G01X1352819D01*
G37*
G36*
G01X1298549Y1633878D02*
G02Y1636882I0J1502D01*
G01X1301949D01*
G02Y1633878I0J-1502D01*
G01X1298549D01*
G37*
G36*
G01X1286489D02*
G02Y1636882I0J1502D01*
G01X1289889D01*
G02Y1633878I0J-1502D01*
G01X1286489D01*
G37*
G36*
G01X1238249D02*
G02Y1636882I0J1502D01*
G01X1241649D01*
G02Y1633878I0J-1502D01*
G01X1238249D01*
G37*
G36*
G01X1250309D02*
G02Y1636882I0J1502D01*
G01X1253709D01*
G02Y1633878I0J-1502D01*
G01X1250309D01*
G37*
G36*
G01X1280459Y1655790D02*
G02Y1658794I0J1502D01*
G01X1283859D01*
G02Y1655790I0J-1502D01*
G01X1280459D01*
G37*
G36*
G01X1214129Y1633878D02*
G02Y1636882I0J1502D01*
G01X1217529D01*
G02Y1633878I0J-1502D01*
G01X1214129D01*
G37*
G36*
G01X1226189Y1645790D02*
G02Y1648794I0J1502D01*
G01X1229589D01*
G02Y1645790I0J-1502D01*
G01X1226189D01*
G37*
G36*
G01Y1633878D02*
G02Y1636882I0J1502D01*
G01X1229589D01*
G02Y1633878I0J-1502D01*
G01X1226189D01*
G37*
G36*
G01X1202069Y1645790D02*
G02Y1648794I0J1502D01*
G01X1205469D01*
G02Y1645790I0J-1502D01*
G01X1202069D01*
G37*
G36*
G01X1220159Y1655790D02*
G02Y1658794I0J1502D01*
G01X1223559D01*
G02Y1655790I0J-1502D01*
G01X1220159D01*
G37*
G36*
G01X1208099D02*
G02Y1658794I0J1502D01*
G01X1211499D01*
G02Y1655790I0J-1502D01*
G01X1208099D01*
G37*
G36*
G01Y1623878D02*
G02Y1626882I0J1502D01*
G01X1211499D01*
G02Y1623878I0J-1502D01*
G01X1208099D01*
G37*
G36*
G01X1256339D02*
G02Y1626882I0J1502D01*
G01X1259739D01*
G02Y1623878I0J-1502D01*
G01X1256339D01*
G37*
G36*
G01X591029Y1600878D02*
G02Y1603882I0J1502D01*
G01X594429D01*
G02Y1600878I0J-1502D01*
G01X591029D01*
G37*
G36*
G01X1196039Y1623878D02*
G02Y1626882I0J1502D01*
G01X1199439D01*
G02Y1623878I0J-1502D01*
G01X1196039D01*
G37*
G36*
G01X554849Y1612790D02*
G02Y1615794I0J1502D01*
G01X558249D01*
G02Y1612790I0J-1502D01*
G01X554849D01*
G37*
G36*
G01X584999Y1622790D02*
G02Y1625794I0J1502D01*
G01X588399D01*
G02Y1622790I0J-1502D01*
G01X584999D01*
G37*
G36*
G01X542789Y1600878D02*
G02Y1603882I0J1502D01*
G01X546189D01*
G02Y1600878I0J-1502D01*
G01X542789D01*
G37*
G36*
G01X494549D02*
G02Y1603882I0J1502D01*
G01X497949D01*
G02Y1600878I0J-1502D01*
G01X494549D01*
G37*
G36*
G01Y1612790D02*
G02Y1615794I0J1502D01*
G01X497949D01*
G02Y1612790I0J-1502D01*
G01X494549D01*
G37*
G36*
G01X482489D02*
G02Y1615794I0J1502D01*
G01X485889D01*
G02Y1612790I0J-1502D01*
G01X482489D01*
G37*
G36*
G01X461769Y1603882D02*
G02Y1600878I0J-1502D01*
G01X458369D01*
G02Y1603882I0J1502D01*
G01X461769D01*
G37*
G36*
G01X476459Y1590878D02*
G02Y1593882I0J1502D01*
G01X479859D01*
G02Y1590878I0J-1502D01*
G01X476459D01*
G37*
G36*
G01X464399Y1622790D02*
G02Y1625794I0J1502D01*
G01X467799D01*
G02Y1622790I0J-1502D01*
G01X464399D01*
G37*
G36*
G01X452339Y1590878D02*
G02Y1593882I0J1502D01*
G01X455739D01*
G02Y1590878I0J-1502D01*
G01X452339D01*
G37*
G36*
G01X375096Y1600878D02*
G02Y1603882I0J1502D01*
G01X378496D01*
G02Y1600878I0J-1502D01*
G01X375096D01*
G37*
G36*
G01X357006Y1590878D02*
G02Y1593882I0J1502D01*
G01X360406D01*
G02Y1590878I0J-1502D01*
G01X357006D01*
G37*
G36*
G01X314796Y1612790D02*
G02Y1615794I0J1502D01*
G01X318196D01*
G02Y1612790I0J-1502D01*
G01X314796D01*
G37*
G36*
G01X302736Y1600878D02*
G02Y1603882I0J1502D01*
G01X306136D01*
G02Y1600878I0J-1502D01*
G01X302736D01*
G37*
G36*
G01X272586Y1590878D02*
G02Y1593882I0J1502D01*
G01X275986D01*
G02Y1590878I0J-1502D01*
G01X272586D01*
G37*
G36*
G01X266556Y1612790D02*
G02Y1615794I0J1502D01*
G01X269956D01*
G02Y1612790I0J-1502D01*
G01X266556D01*
G37*
G36*
G01X254496D02*
G02Y1615794I0J1502D01*
G01X257896D01*
G02Y1612790I0J-1502D01*
G01X254496D01*
G37*
G36*
G01X218316D02*
G02Y1615794I0J1502D01*
G01X221716D01*
G02Y1612790I0J-1502D01*
G01X218316D01*
G37*
G36*
G01X212286Y1622790D02*
G02Y1625794I0J1502D01*
G01X215686D01*
G02Y1622790I0J-1502D01*
G01X212286D01*
G37*
G36*
G01X578969Y1612790D02*
G02Y1615794I0J1502D01*
G01X582369D01*
G02Y1612790I0J-1502D01*
G01X578969D01*
G37*
G36*
G01X1340759Y1655790D02*
G02Y1658794I0J1502D01*
G01X1344159D01*
G02Y1655790I0J-1502D01*
G01X1340759D01*
G37*
G36*
G01X1328699D02*
G02Y1658794I0J1502D01*
G01X1332099D01*
G02Y1655790I0J-1502D01*
G01X1328699D01*
G37*
G36*
G01X304113Y1451392D02*
G02Y1454398I0J1503D01*
G01X307513D01*
G02Y1451392I0J-1503D01*
G01X304113D01*
G37*
G36*
G01X324213Y1461092D02*
G02Y1464098I0J1503D01*
G01X327613D01*
G02Y1461092I0J-1503D01*
G01X324213D01*
G37*
G36*
G01X338916Y1612790D02*
G02Y1615794I0J1502D01*
G01X342316D01*
G02Y1612790I0J-1502D01*
G01X338916D01*
G37*
G36*
G01X169351Y1461092D02*
G02Y1464098I0J1503D01*
G01X172751D01*
G02Y1461092I0J-1503D01*
G01X169351D01*
G37*
G36*
G01X350976Y1612790D02*
G02Y1615794I0J1502D01*
G01X354376D01*
G02Y1612790I0J-1502D01*
G01X350976D01*
G37*
G36*
G01X641986Y1461092D02*
G02Y1464098I0J1503D01*
G01X645386D01*
G02Y1461092I0J-1503D01*
G01X641986D01*
G37*
G36*
G01X230376Y1612790D02*
G02Y1615794I0J1502D01*
G01X233776D01*
G02Y1612790I0J-1502D01*
G01X230376D01*
G37*
G36*
G01X344313Y1470792D02*
G02Y1473798I0J1503D01*
G01X347713D01*
G02Y1470792I0J-1503D01*
G01X344313D01*
G37*
G36*
G01X1232219Y1623878D02*
G02Y1626882I0J1502D01*
G01X1235619D01*
G02Y1623878I0J-1502D01*
G01X1232219D01*
G37*
G36*
G01X1629053D02*
G02Y1626882I0J1502D01*
G01X1632453D01*
G02Y1623878I0J-1502D01*
G01X1629053D01*
G37*
G36*
G01X1364879D02*
G02Y1626882I0J1502D01*
G01X1368279D01*
G02Y1623878I0J-1502D01*
G01X1364879D01*
G37*
G36*
G01X363036Y1612790D02*
G02Y1615794I0J1502D01*
G01X366436D01*
G02Y1612790I0J-1502D01*
G01X363036D01*
G37*
G36*
G01X648686Y1451392D02*
G02Y1454398I0J1503D01*
G01X652086D01*
G02Y1451392I0J-1503D01*
G01X648686D01*
G37*
G36*
G01X221740Y1520264D02*
G02X222800Y1520900I1060J-565D01*
G02X224002Y1519698I0J-1202D01*
G02X223842Y1519098I-1203J0D01*
G01X222297Y1516425D01*
X222295Y1516421D01*
G02X221225Y1515768I-1070J550D01*
G02X220022Y1516970I-1J1202D01*
G01Y1516972D01*
G02X220172Y1517551I1203J-3D01*
G01X221738Y1520261D01*
X221740Y1520264D01*
G37*
G36*
G01X1392386Y1484392D02*
G02Y1487398I0J1503D01*
G01X1395786D01*
G02Y1484392I0J-1503D01*
G01X1392386D01*
G37*
G36*
G01X480424Y1470792D02*
G02Y1473798I0J1503D01*
G01X483824D01*
G02Y1470792I0J-1503D01*
G01X480424D01*
G37*
G36*
G01X1334729Y1645790D02*
G02Y1648794I0J1502D01*
G01X1338129D01*
G02Y1645790I0J-1502D01*
G01X1334729D01*
G37*
G36*
G01X1322669D02*
G02Y1648794I0J1502D01*
G01X1326069D01*
G02Y1645790I0J-1502D01*
G01X1322669D01*
G37*
G36*
G01X1310609D02*
G02Y1648794I0J1502D01*
G01X1314009D01*
G02Y1645790I0J-1502D01*
G01X1310609D01*
G37*
G36*
G01X1316639Y1655790D02*
G02Y1658794I0J1502D01*
G01X1320039D01*
G02Y1655790I0J-1502D01*
G01X1316639D01*
G37*
G36*
G01X1304579D02*
G02Y1658794I0J1502D01*
G01X1307979D01*
G02Y1655790I0J-1502D01*
G01X1304579D01*
G37*
G36*
G01X1292519Y1623878D02*
G02Y1626882I0J1502D01*
G01X1295919D01*
G02Y1623878I0J-1502D01*
G01X1292519D01*
G37*
G36*
G01X1280459D02*
G02Y1626882I0J1502D01*
G01X1283859D01*
G02Y1623878I0J-1502D01*
G01X1280459D01*
G37*
G36*
G01X1268399Y1655790D02*
G02Y1658794I0J1502D01*
G01X1271799D01*
G02Y1655790I0J-1502D01*
G01X1268399D01*
G37*
G36*
G01X1256339D02*
G02Y1658794I0J1502D01*
G01X1259739D01*
G02Y1655790I0J-1502D01*
G01X1256339D01*
G37*
G36*
G01X1244279D02*
G02Y1658794I0J1502D01*
G01X1247679D01*
G02Y1655790I0J-1502D01*
G01X1244279D01*
G37*
G36*
G01X1232219D02*
G02Y1658794I0J1502D01*
G01X1235619D01*
G02Y1655790I0J-1502D01*
G01X1232219D01*
G37*
G36*
G01X485649Y1128118D02*
G02Y1125712I0J-1203D01*
G01X481948D01*
G02Y1128118I0J1203D01*
G01X485649D01*
G37*
G36*
G01X1460213Y1655790D02*
G02Y1658794I0J1502D01*
G01X1463613D01*
G02Y1655790I0J-1502D01*
G01X1460213D01*
G37*
G36*
G01X357006Y1622790D02*
G02Y1625794I0J1502D01*
G01X360406D01*
G02Y1622790I0J-1502D01*
G01X357006D01*
G37*
G36*
G01X1616993Y1623878D02*
G02Y1626882I0J1502D01*
G01X1620393D01*
G02Y1623878I0J-1502D01*
G01X1616993D01*
G37*
G36*
G01X1515098Y1503792D02*
G02Y1506798I0J1503D01*
G01X1518498D01*
G02Y1503792I0J-1503D01*
G01X1515098D01*
G37*
G36*
G01X588386Y1461092D02*
G02Y1464098I0J1503D01*
G01X591786D01*
G02Y1461092I0J-1503D01*
G01X588386D01*
G37*
G36*
G01X561586D02*
G02Y1464098I0J1503D01*
G01X564986D01*
G02Y1461092I0J-1503D01*
G01X561586D01*
G37*
G36*
G01X1340759Y1623878D02*
G02Y1626882I0J1502D01*
G01X1344159D01*
G02Y1623878I0J-1502D01*
G01X1340759D01*
G37*
G36*
G01X1659960Y1487398D02*
G02Y1484392I0J-1503D01*
G01X1656560D01*
G02Y1487398I0J1503D01*
G01X1659960D01*
G37*
G36*
G01X1488298Y1503792D02*
G02Y1506798I0J1503D01*
G01X1491698D01*
G02Y1503792I0J-1503D01*
G01X1488298D01*
G37*
G36*
G01X635286Y1470792D02*
G02Y1473798I0J1503D01*
G01X638686D01*
G02Y1470792I0J-1503D01*
G01X635286D01*
G37*
G36*
G01X1647143Y1633878D02*
G02Y1636882I0J1502D01*
G01X1650543D01*
G02Y1633878I0J-1502D01*
G01X1647143D01*
G37*
G36*
G01X1352819Y1623878D02*
G02Y1626882I0J1502D01*
G01X1356219D01*
G02Y1623878I0J-1502D01*
G01X1352819D01*
G37*
G36*
G01X536759Y1622790D02*
G02Y1625794I0J1502D01*
G01X540159D01*
G02Y1622790I0J-1502D01*
G01X536759D01*
G37*
G36*
G01X332886Y1590878D02*
G02Y1593882I0J1502D01*
G01X336286D01*
G02Y1590878I0J-1502D01*
G01X332886D01*
G37*
G36*
G01X512639D02*
G02Y1593882I0J1502D01*
G01X516039D01*
G02Y1590878I0J-1502D01*
G01X512639D01*
G37*
G36*
G01X522069Y1603882D02*
G02Y1600878I0J-1502D01*
G01X518669D01*
G02Y1603882I0J1502D01*
G01X522069D01*
G37*
G36*
G01X603089Y1600878D02*
G02Y1603882I0J1502D01*
G01X606489D01*
G02Y1600878I0J-1502D01*
G01X603089D01*
G37*
G36*
G01X1472273Y1623878D02*
G02Y1626882I0J1502D01*
G01X1475673D01*
G02Y1623878I0J-1502D01*
G01X1472273D01*
G37*
G36*
G01X1304579D02*
G02Y1626882I0J1502D01*
G01X1307979D01*
G02Y1623878I0J-1502D01*
G01X1304579D01*
G37*
G36*
G01X297413Y1461092D02*
G02Y1464098I0J1503D01*
G01X300813D01*
G02Y1461092I0J-1503D01*
G01X297413D01*
G37*
G36*
G01X493824Y1451392D02*
G02Y1454398I0J1503D01*
G01X497224D01*
G02Y1451392I0J-1503D01*
G01X493824D01*
G37*
G36*
G01X1544633Y1623878D02*
G02Y1626882I0J1502D01*
G01X1548033D01*
G02Y1623878I0J-1502D01*
G01X1544633D01*
G37*
G36*
G01X530729Y1600878D02*
G02Y1603882I0J1502D01*
G01X534129D01*
G02Y1600878I0J-1502D01*
G01X530729D01*
G37*
G36*
G01X1177224Y1494092D02*
G02Y1497098I0J1503D01*
G01X1180624D01*
G02Y1494092I0J-1503D01*
G01X1177224D01*
G37*
G36*
G01X440224Y1451392D02*
G02Y1454398I0J1503D01*
G01X443624D01*
G02Y1451392I0J-1503D01*
G01X440224D01*
G37*
G36*
G01X1520513Y1623878D02*
G02Y1626882I0J1502D01*
G01X1523913D01*
G02Y1623878I0J-1502D01*
G01X1520513D01*
G37*
G36*
G01X1316639D02*
G02Y1626882I0J1502D01*
G01X1320039D01*
G02Y1623878I0J-1502D01*
G01X1316639D01*
G37*
G36*
G01X595086Y1451392D02*
G02Y1454398I0J1503D01*
G01X598486D01*
G02Y1451392I0J-1503D01*
G01X595086D01*
G37*
G36*
G01X568286D02*
G02Y1454398I0J1503D01*
G01X571686D01*
G02Y1451392I0J-1503D01*
G01X568286D01*
G37*
G36*
G01X581686Y1470792D02*
G02Y1473798I0J1503D01*
G01X585086D01*
G02Y1470792I0J-1503D01*
G01X581686D01*
G37*
G36*
G01X1604933Y1623878D02*
G02Y1626882I0J1502D01*
G01X1608333D01*
G02Y1623878I0J-1502D01*
G01X1604933D01*
G37*
G36*
G01X296706Y1590878D02*
G02Y1593882I0J1502D01*
G01X300106D01*
G02Y1590878I0J-1502D01*
G01X296706D01*
G37*
G36*
G01X218316Y1600878D02*
G02Y1603882I0J1502D01*
G01X221716D01*
G02Y1600878I0J-1502D01*
G01X218316D01*
G37*
G36*
G01X278616D02*
G02Y1603882I0J1502D01*
G01X282016D01*
G02Y1600878I0J-1502D01*
G01X278616D01*
G37*
G36*
G01X326856D02*
G02Y1603882I0J1502D01*
G01X330256D01*
G02Y1600878I0J-1502D01*
G01X326856D01*
G37*
G36*
G01X338916D02*
G02Y1603882I0J1502D01*
G01X342316D01*
G02Y1600878I0J-1502D01*
G01X338916D01*
G37*
G36*
G01X363036D02*
G02Y1603882I0J1502D01*
G01X366436D01*
G02Y1600878I0J-1502D01*
G01X363036D01*
G37*
G36*
G01X578969D02*
G02Y1603882I0J1502D01*
G01X582369D01*
G02Y1600878I0J-1502D01*
G01X578969D01*
G37*
G36*
G01X1382969Y1633878D02*
G02Y1636882I0J1502D01*
G01X1386369D01*
G02Y1633878I0J-1502D01*
G01X1382969D01*
G37*
G36*
G01X1224124Y1503792D02*
G02Y1506798I0J1503D01*
G01X1227524D01*
G02Y1503792I0J-1503D01*
G01X1224124D01*
G37*
G36*
G01X460324Y1461092D02*
G02Y1464098I0J1503D01*
G01X463724D01*
G02Y1461092I0J-1503D01*
G01X460324D01*
G37*
G36*
G01X1484333Y1623878D02*
G02Y1626882I0J1502D01*
G01X1487733D01*
G02Y1623878I0J-1502D01*
G01X1484333D01*
G37*
G36*
G01X560879Y1590878D02*
G02Y1593882I0J1502D01*
G01X564279D01*
G02Y1590878I0J-1502D01*
G01X560879D01*
G37*
G36*
G01X1325386Y1503792D02*
G02Y1506798I0J1503D01*
G01X1328786D01*
G02Y1503792I0J-1503D01*
G01X1325386D01*
G37*
G36*
G01X1257624Y1494092D02*
G02Y1497098I0J1503D01*
G01X1261024D01*
G02Y1494092I0J-1503D01*
G01X1257624D01*
G37*
G36*
G01X1596260D02*
G02Y1497098I0J1503D01*
G01X1599660D01*
G02Y1494092I0J-1503D01*
G01X1596260D01*
G37*
G36*
G01X1328699Y1623878D02*
G02Y1626882I0J1502D01*
G01X1332099D01*
G02Y1623878I0J-1502D01*
G01X1328699D01*
G37*
G36*
G01X1202069Y1633878D02*
G02Y1636882I0J1502D01*
G01X1205469D01*
G02Y1633878I0J-1502D01*
G01X1202069D01*
G37*
G36*
G01X464399Y1590878D02*
G02Y1593882I0J1502D01*
G01X467799D01*
G02Y1590878I0J-1502D01*
G01X464399D01*
G37*
G36*
G01X1441398Y1494092D02*
G02Y1497098I0J1503D01*
G01X1444798D01*
G02Y1494092I0J-1503D01*
G01X1441398D01*
G37*
G36*
G01X1623060D02*
G02Y1497098I0J1503D01*
G01X1626460D01*
G02Y1494092I0J-1503D01*
G01X1623060D01*
G37*
G36*
G01X1646560Y1506798D02*
G02Y1503792I0J-1503D01*
G01X1643160D01*
G02Y1506798I0J1503D01*
G01X1646560D01*
G37*
G36*
G01X1576160Y1484392D02*
G02Y1487398I0J1503D01*
G01X1579560D01*
G02Y1484392I0J-1503D01*
G01X1576160D01*
G37*
G36*
G01X1268399Y1623878D02*
G02Y1626882I0J1502D01*
G01X1271799D01*
G02Y1623878I0J-1502D01*
G01X1268399D01*
G37*
G36*
G01X1292519Y1655790D02*
G02Y1658794I0J1502D01*
G01X1295919D01*
G02Y1655790I0J-1502D01*
G01X1292519D01*
G37*
G36*
G01X513924Y1461092D02*
G02Y1464098I0J1503D01*
G01X517324D01*
G02Y1461092I0J-1503D01*
G01X513924D01*
G37*
G36*
G01X1197324Y1503792D02*
G02Y1506798I0J1503D01*
G01X1200724D01*
G02Y1503792I0J-1503D01*
G01X1197324D01*
G37*
G36*
G01X608486Y1470792D02*
G02Y1473798I0J1503D01*
G01X611886D01*
G02Y1470792I0J-1503D01*
G01X608486D01*
G37*
G36*
G01X1358886Y1494092D02*
G02Y1497098I0J1503D01*
G01X1362286D01*
G02Y1494092I0J-1503D01*
G01X1358886D01*
G37*
G36*
G01X1448098Y1484392D02*
G02Y1487398I0J1503D01*
G01X1451498D01*
G02Y1484392I0J-1503D01*
G01X1448098D01*
G37*
G36*
G01X1244279Y1623878D02*
G02Y1626882I0J1502D01*
G01X1247679D01*
G02Y1623878I0J-1502D01*
G01X1244279D01*
G37*
G36*
G01X1250924Y1503792D02*
G02Y1506798I0J1503D01*
G01X1254324D01*
G02Y1503792I0J-1503D01*
G01X1250924D01*
G37*
G36*
G01X500087Y1520264D02*
G02X501147Y1520900I1060J-565D01*
G02X502350Y1519698I1J-1202D01*
G02X502189Y1519098I-1204J1D01*
G01X500644Y1516425D01*
X500642Y1516421D01*
G02X499572Y1515768I-1070J550D01*
G02X498370Y1516970I0J1202D01*
G01Y1516972D01*
G02X498519Y1517551I1202J-1D01*
G01X500085Y1520261D01*
X500087Y1520264D01*
G37*
G36*
G01X1653260Y1497098D02*
G02Y1494092I0J-1503D01*
G01X1649860D01*
G02Y1497098I0J1503D01*
G01X1653260D01*
G37*
G36*
G01X1230824Y1494092D02*
G02Y1497098I0J1503D01*
G01X1234224D01*
G02Y1494092I0J-1503D01*
G01X1230824D01*
G37*
G36*
G01X202843Y1520264D02*
G02X203903Y1520900I1060J-565D01*
G02X205106Y1519698I1J-1202D01*
G02X204945Y1519098I-1204J1D01*
G01X203400Y1516425D01*
X203398Y1516421D01*
G02X202328Y1515768I-1070J550D01*
G02X201126Y1516970I0J1202D01*
G01Y1516972D01*
G02X201275Y1517551I1202J-1D01*
G01X202841Y1520261D01*
X202843Y1520264D01*
G37*
G36*
G01X467024Y1451392D02*
G02Y1454398I0J1503D01*
G01X470424D01*
G02Y1451392I0J-1503D01*
G01X467024D01*
G37*
G36*
G01X1589560Y1503792D02*
G02Y1506798I0J1503D01*
G01X1592960D01*
G02Y1503792I0J-1503D01*
G01X1589560D01*
G37*
G36*
G01X1616360D02*
G02Y1506798I0J1503D01*
G01X1619760D01*
G02Y1503792I0J-1503D01*
G01X1616360D01*
G37*
G36*
G01X1460213Y1623878D02*
G02Y1626882I0J1502D01*
G01X1463613D01*
G02Y1623878I0J-1502D01*
G01X1460213D01*
G37*
G36*
G01X1521798Y1494092D02*
G02Y1497098I0J1503D01*
G01X1525198D01*
G02Y1494092I0J-1503D01*
G01X1521798D01*
G37*
G36*
G01X487124Y1461092D02*
G02Y1464098I0J1503D01*
G01X490524D01*
G02Y1461092I0J-1503D01*
G01X487124D01*
G37*
G36*
G01X1352186Y1503792D02*
G02Y1506798I0J1503D01*
G01X1355586D01*
G02Y1503792I0J-1503D01*
G01X1352186D01*
G37*
G36*
G01X375096Y1612790D02*
G02Y1615794I0J1502D01*
G01X378496D01*
G02Y1612790I0J-1502D01*
G01X375096D01*
G37*
G36*
G01X1332086Y1494092D02*
G02Y1497098I0J1503D01*
G01X1335486D01*
G02Y1494092I0J-1503D01*
G01X1332086D01*
G37*
G36*
G01X207567Y1520264D02*
G02X208627Y1520900I1060J-565D01*
G02X209830Y1519698I1J-1202D01*
G02X209669Y1519098I-1204J1D01*
G01X208124Y1516425D01*
X208122Y1516421D01*
G02X207052Y1515768I-1070J550D01*
G02X205850Y1516970I0J1202D01*
G01Y1516972D01*
G02X205999Y1517551I1202J-1D01*
G01X207565Y1520261D01*
X207567Y1520264D01*
G37*
G36*
G01X212292D02*
G02X213352Y1520900I1060J-565D01*
G02X214554Y1519698I0J-1202D01*
G02X214394Y1519098I-1203J0D01*
G01X212849Y1516425D01*
X212847Y1516421D01*
G02X211777Y1515768I-1070J550D01*
G02X210574Y1516970I-1J1202D01*
G01Y1516972D01*
G02X210724Y1517551I1203J-3D01*
G01X212290Y1520261D01*
X212292Y1520264D01*
G37*
G36*
G01X1338786Y1484392D02*
G02Y1487398I0J1503D01*
G01X1342186D01*
G02Y1484392I0J-1503D01*
G01X1338786D01*
G37*
G36*
G01X345078Y1520264D02*
G02X346138Y1520900I1060J-565D01*
G02X347340Y1519698I0J-1202D01*
G02X347180Y1519098I-1203J0D01*
G01X345635Y1516425D01*
X345633Y1516421D01*
G02X344563Y1515768I-1070J550D01*
G02X343360Y1516970I-1J1202D01*
G01Y1516972D01*
G02X343510Y1517551I1203J-3D01*
G01X345076Y1520261D01*
X345078Y1520264D01*
G37*
G36*
G01X368700D02*
G02X369760Y1520900I1060J-565D01*
G02X370962Y1519698I0J-1202D01*
G02X370802Y1519098I-1203J0D01*
G01X369257Y1516425D01*
X369255Y1516421D01*
G02X368185Y1515768I-1070J550D01*
G02X366982Y1516970I-1J1202D01*
G01Y1516972D01*
G02X367132Y1517551I1203J-3D01*
G01X368698Y1520261D01*
X368700Y1520264D01*
G37*
G36*
G01X326180D02*
G02X327240Y1520900I1060J-565D01*
G02X328442Y1519698I0J-1202D01*
G02X328282Y1519098I-1203J0D01*
G01X326737Y1516425D01*
X326735Y1516421D01*
G02X325665Y1515768I-1070J550D01*
G02X324462Y1516970I-1J1202D01*
G01Y1516972D01*
G02X324612Y1517551I1203J-3D01*
G01X326178Y1520261D01*
X326180Y1520264D01*
G37*
G36*
G01X378149D02*
G02X379209Y1520900I1060J-565D01*
G02X380412Y1519698I1J-1202D01*
G02X380251Y1519098I-1204J1D01*
G01X378706Y1516425D01*
X378704Y1516421D01*
G02X377634Y1515768I-1070J550D01*
G02X376432Y1516970I0J1202D01*
G01Y1516972D01*
G02X376581Y1517551I1202J-1D01*
G01X378147Y1520261D01*
X378149Y1520264D01*
G37*
G36*
G01X112473Y1661738D02*
G02Y1658732I0J-1503D01*
G01X109073D01*
G02Y1661738I0J1503D01*
G01X112473D01*
G37*
G36*
G01X157410Y1678314D02*
G02Y1675308I0J-1503D01*
G01X154010D01*
G02Y1678314I0J1503D01*
G01X157410D01*
G37*
G36*
G01X157511Y1665436D02*
G02Y1662430I0J-1503D01*
G01X154111D01*
G02Y1665436I0J1503D01*
G01X157511D01*
G37*
G36*
G01X110969Y1687266D02*
G02Y1684260I0J-1503D01*
G01X107569D01*
G02Y1687266I0J1503D01*
G01X110969D01*
G37*
G36*
G01X388272Y970118D02*
G02Y967712I0J-1203D01*
G01X384571D01*
G02Y970118I0J1203D01*
G01X388272D01*
G37*
G36*
G01Y963740D02*
G02Y961334I0J-1203D01*
G01X384571D01*
G02Y963740I0J1203D01*
G01X388272D01*
G37*
G36*
G01Y976496D02*
G02Y974090I0J-1203D01*
G01X384571D01*
G02Y976496I0J1203D01*
G01X388272D01*
G37*
G36*
G01X389453Y1115362D02*
G02Y1112956I0J-1203D01*
G01X385752D01*
G02Y1115362I0J1203D01*
G01X389453D01*
G37*
G36*
G01Y1108984D02*
G02Y1106578I0J-1203D01*
G01X385752D01*
G02Y1108984I0J1203D01*
G01X389453D01*
G37*
G36*
G01Y1121740D02*
G02Y1119334I0J-1203D01*
G01X385752D01*
G02Y1121740I0J1203D01*
G01X389453D01*
G37*
G36*
G01X399374Y970118D02*
G02Y967712I0J-1203D01*
G01X395673D01*
G02Y970118I0J1203D01*
G01X399374D01*
G37*
G36*
G01X406776Y967712D02*
G02Y970118I0J1203D01*
G01X410477D01*
G02Y967712I0J-1203D01*
G01X406776D01*
G37*
G36*
G01X399374Y963740D02*
G02Y961334I0J-1203D01*
G01X395673D01*
G02Y963740I0J1203D01*
G01X399374D01*
G37*
G36*
G01X410477D02*
G02Y961334I0J-1203D01*
G01X406776D01*
G02Y963740I0J1203D01*
G01X410477D01*
G37*
G36*
G01X399374Y976496D02*
G02Y974090I0J-1203D01*
G01X395673D01*
G02Y976496I0J1203D01*
G01X399374D01*
G37*
G36*
G01X406776Y974090D02*
G02Y976496I0J1203D01*
G01X410477D01*
G02Y974090I0J-1203D01*
G01X406776D01*
G37*
G36*
G01X400556Y1115362D02*
G02Y1112956I0J-1203D01*
G01X396855D01*
G02Y1115362I0J1203D01*
G01X400556D01*
G37*
G36*
G01Y1108984D02*
G02Y1106578I0J-1203D01*
G01X396855D01*
G02Y1108984I0J1203D01*
G01X400556D01*
G37*
G36*
G01Y1128118D02*
G02Y1125712I0J-1203D01*
G01X396855D01*
G02Y1128118I0J1203D01*
G01X400556D01*
G37*
G36*
G01Y1121740D02*
G02Y1119334I0J-1203D01*
G01X396855D01*
G02Y1121740I0J1203D01*
G01X400556D01*
G37*
G36*
G01X421579Y976496D02*
G02Y974090I0J-1203D01*
G01X417878D01*
G02Y976496I0J1203D01*
G01X421579D01*
G37*
G36*
G01Y970118D02*
G02Y967712I0J-1203D01*
G01X417878D01*
G02Y970118I0J1203D01*
G01X421579D01*
G37*
G36*
G01Y963740D02*
G02Y961334I0J-1203D01*
G01X417878D01*
G02Y963740I0J1203D01*
G01X421579D01*
G37*
G36*
G01X419059Y1112956D02*
G02Y1115362I0J1203D01*
G01X422760D01*
G02Y1112956I0J-1203D01*
G01X419059D01*
G37*
G36*
G01X411658Y1115362D02*
G02Y1112956I0J-1203D01*
G01X407957D01*
G02Y1115362I0J1203D01*
G01X411658D01*
G37*
G36*
G01X419059Y1125712D02*
G02Y1128118I0J1203D01*
G01X422760D01*
G02Y1125712I0J-1203D01*
G01X419059D01*
G37*
G36*
G01Y1119334D02*
G02Y1121740I0J1203D01*
G01X422760D01*
G02Y1119334I0J-1203D01*
G01X419059D01*
G37*
G36*
G01X411658Y1128118D02*
G02Y1125712I0J-1203D01*
G01X407957D01*
G02Y1128118I0J1203D01*
G01X411658D01*
G37*
G36*
G01Y1121740D02*
G02Y1119334I0J-1203D01*
G01X407957D01*
G02Y1121740I0J1203D01*
G01X411658D01*
G37*
G36*
G01X427130Y958146D02*
G02Y960550I0J1202D01*
G01X430831D01*
G02Y958146I0J-1202D01*
G01X427130D01*
G37*
G36*
G01X430831Y973306D02*
G02Y970902I0J-1202D01*
G01X427130D01*
G02Y973306I0J1202D01*
G01X430831D01*
G37*
G36*
G01X427130Y977280D02*
G02Y979684I0J1202D01*
G01X430831D01*
G02Y977280I0J-1202D01*
G01X427130D01*
G37*
G36*
G01Y964524D02*
G02Y966928I0J1202D01*
G01X430831D01*
G02Y964524I0J-1202D01*
G01X427130D01*
G37*
G36*
G01X432012Y1118550D02*
G02Y1116146I0J-1202D01*
G01X428311D01*
G02Y1118550I0J1202D01*
G01X432012D01*
G37*
G36*
G01Y1112172D02*
G02Y1109768I0J-1202D01*
G01X428311D01*
G02Y1112172I0J1202D01*
G01X432012D01*
G37*
G36*
G01Y1124928D02*
G02Y1122524I0J-1202D01*
G01X428311D01*
G02Y1124928I0J1202D01*
G01X432012D01*
G37*
G36*
G01X493050Y1119334D02*
G02Y1121740I0J1203D01*
G01X496751D01*
G02Y1119334I0J-1203D01*
G01X493050D01*
G37*
G36*
G01X485649Y1121740D02*
G02Y1119334I0J-1203D01*
G01X481948D01*
G02Y1121740I0J1203D01*
G01X485649D01*
G37*
G36*
G01X470845Y1119334D02*
G02Y1121740I0J1203D01*
G01X474546D01*
G02Y1119334I0J-1203D01*
G01X470845D01*
G37*
G36*
G01X459743Y1125712D02*
G02Y1128118I0J1203D01*
G01X463444D01*
G02Y1125712I0J-1203D01*
G01X459743D01*
G37*
G36*
G01Y1119334D02*
G02Y1121740I0J1203D01*
G01X463444D01*
G02Y1119334I0J-1203D01*
G01X459743D01*
G37*
G36*
G01X450491Y1122524D02*
G02Y1124928I0J1202D01*
G01X454192D01*
G02Y1122524I0J-1202D01*
G01X450491D01*
G37*
G36*
G01X493050Y1112956D02*
G02Y1115362I0J1203D01*
G01X496751D01*
G02Y1112956I0J-1203D01*
G01X493050D01*
G37*
G36*
G01X450491Y1116146D02*
G02Y1118550I0J1202D01*
G01X454192D01*
G02Y1116146I0J-1202D01*
G01X450491D01*
G37*
G36*
G01X493050Y1106578D02*
G02Y1108984I0J1203D01*
G01X496751D01*
G02Y1106578I0J-1203D01*
G01X493050D01*
G37*
G36*
G01X485649Y1115362D02*
G02Y1112956I0J-1203D01*
G01X481948D01*
G02Y1115362I0J1203D01*
G01X485649D01*
G37*
G36*
G01X470845Y1112956D02*
G02Y1115362I0J1203D01*
G01X474546D01*
G02Y1112956I0J-1203D01*
G01X470845D01*
G37*
G36*
G01X485649Y1108984D02*
G02Y1106578I0J-1203D01*
G01X481948D01*
G02Y1108984I0J1203D01*
G01X485649D01*
G37*
G36*
G01X1365595Y1121738D02*
G02Y1119334I0J-1202D01*
G01X1361894D01*
G02Y1121738I0J1202D01*
G01X1365595D01*
G37*
G36*
G01X1376698D02*
G02Y1119334I0J-1202D01*
G01X1372997D01*
G02Y1121738I0J1202D01*
G01X1376698D01*
G37*
G36*
G01Y1128116D02*
G02Y1125712I0J-1202D01*
G01X1372997D01*
G02Y1128116I0J1202D01*
G01X1376698D01*
G37*
G36*
G01Y1115360D02*
G02Y1112956I0J-1202D01*
G01X1372997D01*
G02Y1115360I0J1202D01*
G01X1376698D01*
G37*
G36*
G01X1365595D02*
G02Y1112956I0J-1202D01*
G01X1361894D01*
G02Y1115360I0J1202D01*
G01X1365595D01*
G37*
G36*
G01Y1108982D02*
G02Y1106578I0J-1202D01*
G01X1361894D01*
G02Y1108982I0J1202D01*
G01X1365595D01*
G37*
G36*
G01X1376698D02*
G02Y1106578I0J-1202D01*
G01X1372997D01*
G02Y1108982I0J1202D01*
G01X1376698D01*
G37*
G36*
G01X1387800Y1121738D02*
G02Y1119334I0J-1202D01*
G01X1384099D01*
G02Y1121738I0J1202D01*
G01X1387800D01*
G37*
G36*
G01Y1128116D02*
G02Y1125712I0J-1202D01*
G01X1384099D01*
G02Y1128116I0J1202D01*
G01X1387800D01*
G37*
G36*
G01Y1115360D02*
G02Y1112956I0J-1202D01*
G01X1384099D01*
G02Y1115360I0J1202D01*
G01X1387800D01*
G37*
G36*
G01X1408154Y1118550D02*
G02Y1116144I0J-1203D01*
G01X1404453D01*
G02Y1118550I0J1203D01*
G01X1408154D01*
G37*
G36*
G01Y1112172D02*
G02Y1109766I0J-1203D01*
G01X1404453D01*
G02Y1112172I0J1203D01*
G01X1408154D01*
G37*
G36*
G01X1398902Y1128116D02*
G02Y1125712I0J-1202D01*
G01X1395201D01*
G02Y1128116I0J1202D01*
G01X1398902D01*
G37*
G36*
G01X1408154Y1124928D02*
G02Y1122522I0J-1203D01*
G01X1404453D01*
G02Y1124928I0J1203D01*
G01X1408154D01*
G37*
G36*
G01X1398902Y1121738D02*
G02Y1119334I0J-1202D01*
G01X1395201D01*
G02Y1121738I0J1202D01*
G01X1398902D01*
G37*
G36*
G01Y1115360D02*
G02Y1112956I0J-1202D01*
G01X1395201D01*
G02Y1115360I0J1202D01*
G01X1398902D01*
G37*
G36*
G01X1429153Y960550D02*
G02Y958144I0J-1203D01*
G01X1425452D01*
G02Y960550I0J1203D01*
G01X1429153D01*
G37*
G36*
G01X1438405Y970116D02*
G02Y967712I0J-1202D01*
G01X1434704D01*
G02Y970116I0J1202D01*
G01X1438405D01*
G37*
G36*
G01X1429153Y966928D02*
G02Y964522I0J-1203D01*
G01X1425452D01*
G02Y966928I0J1203D01*
G01X1429153D01*
G37*
G36*
G01X1438405Y963738D02*
G02Y961334I0J-1202D01*
G01X1434704D01*
G02Y963738I0J1202D01*
G01X1438405D01*
G37*
G36*
G01X1429153Y979684D02*
G02Y977278I0J-1203D01*
G01X1425452D01*
G02Y979684I0J1203D01*
G01X1429153D01*
G37*
G36*
G01X1438405Y976494D02*
G02Y974090I0J-1202D01*
G01X1434704D01*
G02Y976494I0J1202D01*
G01X1438405D01*
G37*
G36*
G01X1429153Y973306D02*
G02Y970900I0J-1203D01*
G01X1425452D01*
G02Y973306I0J1203D01*
G01X1429153D01*
G37*
G36*
G01X1426633Y1122522D02*
G02Y1124928I0J1203D01*
G01X1430334D01*
G02Y1122522I0J-1203D01*
G01X1426633D01*
G37*
G36*
G01Y1116144D02*
G02Y1118550I0J1203D01*
G01X1430334D01*
G02Y1116144I0J-1203D01*
G01X1426633D01*
G37*
G36*
G01Y1109766D02*
G02Y1112172I0J1203D01*
G01X1430334D01*
G02Y1109766I0J-1203D01*
G01X1426633D01*
G37*
G36*
G01X1449507Y976494D02*
G02Y974090I0J-1202D01*
G01X1445806D01*
G02Y976494I0J1202D01*
G01X1449507D01*
G37*
G36*
G01Y970116D02*
G02Y967712I0J-1202D01*
G01X1445806D01*
G02Y970116I0J1202D01*
G01X1449507D01*
G37*
G36*
G01Y963738D02*
G02Y961334I0J-1202D01*
G01X1445806D01*
G02Y963738I0J1202D01*
G01X1449507D01*
G37*
G36*
G01X1435885Y1125712D02*
G02Y1128116I0J1202D01*
G01X1439586D01*
G02Y1125712I0J-1202D01*
G01X1435885D01*
G37*
G36*
G01Y1119334D02*
G02Y1121738I0J1202D01*
G01X1439586D01*
G02Y1119334I0J-1202D01*
G01X1435885D01*
G37*
G36*
G01X1446987Y1125712D02*
G02Y1128116I0J1202D01*
G01X1450688D01*
G02Y1125712I0J-1202D01*
G01X1446987D01*
G37*
G36*
G01Y1119334D02*
G02Y1121738I0J1202D01*
G01X1450688D01*
G02Y1119334I0J-1202D01*
G01X1446987D01*
G37*
G36*
G01X1435885Y1112956D02*
G02Y1115360I0J1202D01*
G01X1439586D01*
G02Y1112956I0J-1202D01*
G01X1435885D01*
G37*
G36*
G01X1446987D02*
G02Y1115360I0J1202D01*
G01X1450688D01*
G02Y1112956I0J-1202D01*
G01X1446987D01*
G37*
G36*
G01X1460610Y970116D02*
G02Y967712I0J-1202D01*
G01X1456909D01*
G02Y970116I0J1202D01*
G01X1460610D01*
G37*
G36*
G01Y963738D02*
G02Y961334I0J-1202D01*
G01X1456909D01*
G02Y963738I0J1202D01*
G01X1460610D01*
G37*
G36*
G01Y976494D02*
G02Y974090I0J-1202D01*
G01X1456909D01*
G02Y976494I0J1202D01*
G01X1460610D01*
G37*
G36*
G01X1458090Y1125712D02*
G02Y1128116I0J1202D01*
G01X1461791D01*
G02Y1125712I0J-1202D01*
G01X1458090D01*
G37*
G36*
G01Y1119334D02*
G02Y1121738I0J1202D01*
G01X1461791D01*
G02Y1119334I0J-1202D01*
G01X1458090D01*
G37*
G36*
G01Y1112956D02*
G02Y1115360I0J1202D01*
G01X1461791D01*
G02Y1112956I0J-1202D01*
G01X1458090D01*
G37*
G36*
G01Y1106578D02*
G02Y1108982I0J1202D01*
G01X1461791D01*
G02Y1106578I0J-1202D01*
G01X1458090D01*
G37*
G36*
G01X1471712Y970116D02*
G02Y967712I0J-1202D01*
G01X1468011D01*
G02Y970116I0J1202D01*
G01X1471712D01*
G37*
G36*
G01Y963738D02*
G02Y961334I0J-1202D01*
G01X1468011D01*
G02Y963738I0J1202D01*
G01X1471712D01*
G37*
G36*
G01Y976494D02*
G02Y974090I0J-1202D01*
G01X1468011D01*
G02Y976494I0J1202D01*
G01X1471712D01*
G37*
G36*
G01X1469192Y1106578D02*
G02Y1108982I0J1202D01*
G01X1472893D01*
G02Y1106578I0J-1202D01*
G01X1469192D01*
G37*
G36*
G01Y1119334D02*
G02Y1121738I0J1202D01*
G01X1472893D01*
G02Y1119334I0J-1202D01*
G01X1469192D01*
G37*
G36*
G01Y1112956D02*
G02Y1115360I0J1202D01*
G01X1472893D01*
G02Y1112956I0J-1202D01*
G01X1469192D01*
G37*
G36*
G01X359251Y1520264D02*
G02X360311Y1520900I1060J-565D01*
G02X361514Y1519698I1J-1202D01*
G02X361353Y1519098I-1204J1D01*
G01X359808Y1516425D01*
X359806Y1516421D01*
G02X358736Y1515768I-1070J550D01*
G02X357534Y1516970I0J1202D01*
G01Y1516972D01*
G02X357683Y1517551I1202J-1D01*
G01X359249Y1520261D01*
X359251Y1520264D01*
G37*
G36*
G01X1592873Y1655790D02*
G02Y1658794I0J1502D01*
G01X1596273D01*
G02Y1655790I0J-1502D01*
G01X1592873D01*
G37*
G36*
G01X1616993D02*
G02Y1658794I0J1502D01*
G01X1620393D01*
G02Y1655790I0J-1502D01*
G01X1616993D01*
G37*
G36*
G01X1274429Y1645790D02*
G02Y1648794I0J1502D01*
G01X1277829D01*
G02Y1645790I0J-1502D01*
G01X1274429D01*
G37*
G36*
G01X1286489D02*
G02Y1648794I0J1502D01*
G01X1289889D01*
G02Y1645790I0J-1502D01*
G01X1286489D01*
G37*
G36*
G01X459743Y1112956D02*
G02Y1115362I0J1203D01*
G01X463444D01*
G02Y1112956I0J-1203D01*
G01X459743D01*
G37*
G36*
G01X470845Y1125712D02*
G02Y1128118I0J1203D01*
G01X474546D01*
G02Y1125712I0J-1203D01*
G01X470845D01*
G37*
G36*
G01X450491Y1109768D02*
G02Y1112172I0J1202D01*
G01X454192D01*
G02Y1109768I0J-1202D01*
G01X450491D01*
G37*
G36*
G01X1494998Y1494092D02*
G02Y1497098I0J1503D01*
G01X1498398D01*
G02Y1494092I0J-1503D01*
G01X1494998D01*
G37*
G36*
G01X507224Y1470792D02*
G02Y1473798I0J1503D01*
G01X510624D01*
G02Y1470792I0J-1503D01*
G01X507224D01*
G37*
G36*
G01X335629Y1520264D02*
G02X336689Y1520900I1060J-565D01*
G02X337892Y1519698I1J-1202D01*
G02X337731Y1519098I-1204J1D01*
G01X336186Y1516425D01*
X336184Y1516421D01*
G02X335114Y1515768I-1070J550D01*
G02X333912Y1516970I0J1202D01*
G01Y1516972D01*
G02X334061Y1517551I1202J-1D01*
G01X335627Y1520261D01*
X335629Y1520264D01*
G37*
G36*
G01X433524Y1461092D02*
G02Y1464098I0J1503D01*
G01X436924D01*
G02Y1461092I0J-1503D01*
G01X433524D01*
G37*
G36*
G01X384513Y1451392D02*
G02Y1454398I0J1503D01*
G01X387913D01*
G02Y1451392I0J-1503D01*
G01X384513D01*
G37*
G36*
G01X1204024Y1494092D02*
G02Y1497098I0J1503D01*
G01X1207424D01*
G02Y1494092I0J-1503D01*
G01X1204024D01*
G37*
G36*
G01X242436Y1600878D02*
G02Y1603882I0J1502D01*
G01X245836D01*
G02Y1600878I0J-1502D01*
G01X242436D01*
G37*
G36*
G01Y1612790D02*
G02Y1615794I0J1502D01*
G01X245836D01*
G02Y1612790I0J-1502D01*
G01X242436D01*
G37*
G36*
G01X266556Y1600878D02*
G02Y1603882I0J1502D01*
G01X269956D01*
G02Y1600878I0J-1502D01*
G01X266556D01*
G37*
G36*
G01X254496D02*
G02Y1603882I0J1502D01*
G01X257896D01*
G02Y1600878I0J-1502D01*
G01X254496D01*
G37*
G36*
G01X278616Y1612790D02*
G02Y1615794I0J1502D01*
G01X282016D01*
G02Y1612790I0J-1502D01*
G01X278616D01*
G37*
G36*
G01X290676Y1600878D02*
G02Y1603882I0J1502D01*
G01X294076D01*
G02Y1600878I0J-1502D01*
G01X290676D01*
G37*
G36*
G01Y1612790D02*
G02Y1615794I0J1502D01*
G01X294076D01*
G02Y1612790I0J-1502D01*
G01X290676D01*
G37*
G36*
G01X302736D02*
G02Y1615794I0J1502D01*
G01X306136D01*
G02Y1612790I0J-1502D01*
G01X302736D01*
G37*
G36*
G01X314796Y1600878D02*
G02Y1603882I0J1502D01*
G01X318196D01*
G02Y1600878I0J-1502D01*
G01X314796D01*
G37*
G36*
G01X584999Y1590878D02*
G02Y1593882I0J1502D01*
G01X588399D01*
G02Y1590878I0J-1502D01*
G01X584999D01*
G37*
G36*
G01X597059Y1622790D02*
G02Y1625794I0J1502D01*
G01X600459D01*
G02Y1622790I0J-1502D01*
G01X597059D01*
G37*
G36*
G01X1196039Y1655790D02*
G02Y1658794I0J1502D01*
G01X1199439D01*
G02Y1655790I0J-1502D01*
G01X1196039D01*
G37*
G36*
G01X491919Y1625794D02*
G02Y1622790I0J-1502D01*
G01X488519D01*
G02Y1625794I0J1502D01*
G01X491919D01*
G37*
G36*
G01X500579Y1622790D02*
G02Y1625794I0J1502D01*
G01X503979D01*
G02Y1622790I0J-1502D01*
G01X500579D01*
G37*
G36*
G01X512639D02*
G02Y1625794I0J1502D01*
G01X516039D01*
G02Y1622790I0J-1502D01*
G01X512639D01*
G37*
G36*
G01X524699Y1590878D02*
G02Y1593882I0J1502D01*
G01X528099D01*
G02Y1590878I0J-1502D01*
G01X524699D01*
G37*
G36*
G01Y1622790D02*
G02Y1625794I0J1502D01*
G01X528099D01*
G02Y1622790I0J-1502D01*
G01X524699D01*
G37*
G36*
G01X548819Y1590878D02*
G02Y1593882I0J1502D01*
G01X552219D01*
G02Y1590878I0J-1502D01*
G01X548819D01*
G37*
G36*
G01Y1622790D02*
G02Y1625794I0J1502D01*
G01X552219D01*
G02Y1622790I0J-1502D01*
G01X548819D01*
G37*
G36*
G01X560879D02*
G02Y1625794I0J1502D01*
G01X564279D01*
G02Y1622790I0J-1502D01*
G01X560879D01*
G37*
G36*
G01X572939D02*
G02Y1625794I0J1502D01*
G01X576339D01*
G02Y1622790I0J-1502D01*
G01X572939D01*
G37*
G36*
G01X566909Y1600878D02*
G02Y1603882I0J1502D01*
G01X570309D01*
G02Y1600878I0J-1502D01*
G01X566909D01*
G37*
G36*
G01Y1612790D02*
G02Y1615794I0J1502D01*
G01X570309D01*
G02Y1612790I0J-1502D01*
G01X566909D01*
G37*
G36*
G01X591029D02*
G02Y1615794I0J1502D01*
G01X594429D01*
G02Y1612790I0J-1502D01*
G01X591029D01*
G37*
G36*
G01X603089D02*
G02Y1615794I0J1502D01*
G01X606489D01*
G02Y1612790I0J-1502D01*
G01X603089D01*
G37*
G36*
G01X461769Y1615794D02*
G02Y1612790I0J-1502D01*
G01X458369D01*
G02Y1615794I0J1502D01*
G01X461769D01*
G37*
G36*
G01X470429Y1612790D02*
G02Y1615794I0J1502D01*
G01X473829D01*
G02Y1612790I0J-1502D01*
G01X470429D01*
G37*
G36*
G01X506609Y1600878D02*
G02Y1603882I0J1502D01*
G01X510009D01*
G02Y1600878I0J-1502D01*
G01X506609D01*
G37*
G36*
G01Y1612790D02*
G02Y1615794I0J1502D01*
G01X510009D01*
G02Y1612790I0J-1502D01*
G01X506609D01*
G37*
G36*
G01X522069Y1615794D02*
G02Y1612790I0J-1502D01*
G01X518669D01*
G02Y1615794I0J1502D01*
G01X522069D01*
G37*
G36*
G01X530729Y1612790D02*
G02Y1615794I0J1502D01*
G01X534129D01*
G02Y1612790I0J-1502D01*
G01X530729D01*
G37*
G36*
G01X542789D02*
G02Y1615794I0J1502D01*
G01X546189D01*
G02Y1612790I0J-1502D01*
G01X542789D01*
G37*
G36*
G01X188166Y1622790D02*
G02Y1625794I0J1502D01*
G01X191566D01*
G02Y1622790I0J-1502D01*
G01X188166D01*
G37*
G36*
G01Y1590878D02*
G02Y1593882I0J1502D01*
G01X191566D01*
G02Y1590878I0J-1502D01*
G01X188166D01*
G37*
G36*
G01X326856Y1612790D02*
G02Y1615794I0J1502D01*
G01X330256D01*
G02Y1612790I0J-1502D01*
G01X326856D01*
G37*
G36*
G01X377813Y1461092D02*
G02Y1464098I0J1503D01*
G01X381213D01*
G02Y1461092I0J-1503D01*
G01X377813D01*
G37*
G36*
G01X206256Y1612790D02*
G02Y1615794I0J1502D01*
G01X209656D01*
G02Y1612790I0J-1502D01*
G01X206256D01*
G37*
G36*
G01X308766Y1622790D02*
G02Y1625794I0J1502D01*
G01X312166D01*
G02Y1622790I0J-1502D01*
G01X308766D01*
G37*
G36*
G01Y1590878D02*
G02Y1593882I0J1502D01*
G01X312166D01*
G02Y1590878I0J-1502D01*
G01X308766D01*
G37*
G36*
G01X296706Y1622790D02*
G02Y1625794I0J1502D01*
G01X300106D01*
G02Y1622790I0J-1502D01*
G01X296706D01*
G37*
G36*
G01X284646Y1590878D02*
G02Y1593882I0J1502D01*
G01X288046D01*
G02Y1590878I0J-1502D01*
G01X284646D01*
G37*
G36*
G01Y1622790D02*
G02Y1625794I0J1502D01*
G01X288046D01*
G02Y1622790I0J-1502D01*
G01X284646D01*
G37*
G36*
G01X272586D02*
G02Y1625794I0J1502D01*
G01X275986D01*
G02Y1622790I0J-1502D01*
G01X272586D01*
G37*
G36*
G01X1183924Y1484392D02*
G02Y1487398I0J1503D01*
G01X1187324D01*
G02Y1484392I0J-1503D01*
G01X1183924D01*
G37*
G36*
G01X260526Y1590878D02*
G02Y1593882I0J1502D01*
G01X263926D01*
G02Y1590878I0J-1502D01*
G01X260526D01*
G37*
G36*
G01Y1622790D02*
G02Y1625794I0J1502D01*
G01X263926D01*
G02Y1622790I0J-1502D01*
G01X260526D01*
G37*
G36*
G01X248466D02*
G02Y1625794I0J1502D01*
G01X251866D01*
G02Y1622790I0J-1502D01*
G01X248466D01*
G37*
G36*
G01X236406D02*
G02Y1625794I0J1502D01*
G01X239806D01*
G02Y1622790I0J-1502D01*
G01X236406D01*
G37*
G36*
G01X224346D02*
G02Y1625794I0J1502D01*
G01X227746D01*
G02Y1622790I0J-1502D01*
G01X224346D01*
G37*
G36*
G01Y1590878D02*
G02Y1593882I0J1502D01*
G01X227746D01*
G02Y1590878I0J-1502D01*
G01X224346D01*
G37*
G36*
G01X1237524Y1484392D02*
G02Y1487398I0J1503D01*
G01X1240924D01*
G02Y1484392I0J-1503D01*
G01X1237524D01*
G37*
G36*
G01X1210724D02*
G02Y1487398I0J1503D01*
G01X1214124D01*
G02Y1484392I0J-1503D01*
G01X1210724D01*
G37*
G36*
G01X351013Y1461092D02*
G02Y1464098I0J1503D01*
G01X354413D01*
G02Y1461092I0J-1503D01*
G01X351013D01*
G37*
G36*
G01X1378986Y1503792D02*
G02Y1506798I0J1503D01*
G01X1382386D01*
G02Y1503792I0J-1503D01*
G01X1378986D01*
G37*
G36*
G01X320826Y1622790D02*
G02Y1625794I0J1502D01*
G01X324226D01*
G02Y1622790I0J-1502D01*
G01X320826D01*
G37*
G36*
G01X332886D02*
G02Y1625794I0J1502D01*
G01X336286D01*
G02Y1622790I0J-1502D01*
G01X332886D01*
G37*
G36*
G01X344946D02*
G02Y1625794I0J1502D01*
G01X348346D01*
G02Y1622790I0J-1502D01*
G01X344946D01*
G37*
G36*
G01X369066Y1590878D02*
G02Y1593882I0J1502D01*
G01X372466D01*
G02Y1590878I0J-1502D01*
G01X369066D01*
G37*
G36*
G01X452339Y1622790D02*
G02Y1625794I0J1502D01*
G01X455739D01*
G02Y1622790I0J-1502D01*
G01X452339D01*
G37*
G36*
G01X369066D02*
G02Y1625794I0J1502D01*
G01X372466D01*
G02Y1622790I0J-1502D01*
G01X369066D01*
G37*
G36*
G01X1538603Y1645790D02*
G02Y1648794I0J1502D01*
G01X1542003D01*
G02Y1645790I0J-1502D01*
G01X1538603D01*
G37*
G36*
G01X1550663D02*
G02Y1648794I0J1502D01*
G01X1554063D01*
G02Y1645790I0J-1502D01*
G01X1550663D01*
G37*
G36*
G01X1562723D02*
G02Y1648794I0J1502D01*
G01X1566123D01*
G02Y1645790I0J-1502D01*
G01X1562723D01*
G37*
G36*
G01X200226Y1622790D02*
G02Y1625794I0J1502D01*
G01X203626D01*
G02Y1622790I0J-1502D01*
G01X200226D01*
G37*
G36*
G01X320826Y1590878D02*
G02Y1593882I0J1502D01*
G01X324226D01*
G02Y1590878I0J-1502D01*
G01X320826D01*
G37*
G36*
G01X1568753Y1655790D02*
G02Y1658794I0J1502D01*
G01X1572153D01*
G02Y1655790I0J-1502D01*
G01X1568753D01*
G37*
G36*
G01X1580813D02*
G02Y1658794I0J1502D01*
G01X1584213D01*
G02Y1655790I0J-1502D01*
G01X1580813D01*
G37*
G36*
G01X1382969Y1645790D02*
G02Y1648794I0J1502D01*
G01X1386369D01*
G02Y1645790I0J-1502D01*
G01X1382969D01*
G37*
G36*
G01X1586843D02*
G02Y1648794I0J1502D01*
G01X1590243D01*
G02Y1645790I0J-1502D01*
G01X1586843D01*
G37*
G36*
G01X1610963D02*
G02Y1648794I0J1502D01*
G01X1614363D01*
G02Y1645790I0J-1502D01*
G01X1610963D01*
G37*
G36*
G01X1623023Y1633878D02*
G02Y1636882I0J1502D01*
G01X1626423D01*
G02Y1633878I0J-1502D01*
G01X1623023D01*
G37*
G36*
G01Y1645790D02*
G02Y1648794I0J1502D01*
G01X1626423D01*
G02Y1645790I0J-1502D01*
G01X1623023D01*
G37*
G36*
G01X1635083D02*
G02Y1648794I0J1502D01*
G01X1638483D01*
G02Y1645790I0J-1502D01*
G01X1635083D01*
G37*
G36*
G01X1466243D02*
G02Y1648794I0J1502D01*
G01X1469643D01*
G02Y1645790I0J-1502D01*
G01X1466243D01*
G37*
G36*
G01X1478303D02*
G02Y1648794I0J1502D01*
G01X1481703D01*
G02Y1645790I0J-1502D01*
G01X1478303D01*
G37*
G36*
G01X1490363D02*
G02Y1648794I0J1502D01*
G01X1493763D01*
G02Y1645790I0J-1502D01*
G01X1490363D01*
G37*
G36*
G01X1502423Y1633878D02*
G02Y1636882I0J1502D01*
G01X1505823D01*
G02Y1633878I0J-1502D01*
G01X1502423D01*
G37*
G36*
G01Y1645790D02*
G02Y1648794I0J1502D01*
G01X1505823D01*
G02Y1645790I0J-1502D01*
G01X1502423D01*
G37*
G36*
G01X1514483D02*
G02Y1648794I0J1502D01*
G01X1517883D01*
G02Y1645790I0J-1502D01*
G01X1514483D01*
G37*
G36*
G01X1526543D02*
G02Y1648794I0J1502D01*
G01X1529943D01*
G02Y1645790I0J-1502D01*
G01X1526543D01*
G37*
G36*
G01X1461498Y1503792D02*
G02Y1506798I0J1503D01*
G01X1464898D01*
G02Y1503792I0J-1503D01*
G01X1461498D01*
G37*
G36*
G01X1569460Y1494092D02*
G02Y1497098I0J1503D01*
G01X1572860D01*
G02Y1494092I0J-1503D01*
G01X1569460D01*
G37*
G36*
G01X1602960Y1484392D02*
G02Y1487398I0J1503D01*
G01X1606360D01*
G02Y1484392I0J-1503D01*
G01X1602960D01*
G37*
G36*
G01X1474898D02*
G02Y1487398I0J1503D01*
G01X1478298D01*
G02Y1484392I0J-1503D01*
G01X1474898D01*
G37*
G36*
G01X1556693Y1623878D02*
G02Y1626882I0J1502D01*
G01X1560093D01*
G02Y1623878I0J-1502D01*
G01X1556693D01*
G37*
G36*
G01Y1655790D02*
G02Y1658794I0J1502D01*
G01X1560093D01*
G02Y1655790I0J-1502D01*
G01X1556693D01*
G37*
G36*
G01X1496393D02*
G02Y1658794I0J1502D01*
G01X1499793D01*
G02Y1655790I0J-1502D01*
G01X1496393D01*
G37*
G36*
G01X1508453D02*
G02Y1658794I0J1502D01*
G01X1511853D01*
G02Y1655790I0J-1502D01*
G01X1508453D01*
G37*
G36*
G01X1532573Y1623878D02*
G02Y1626882I0J1502D01*
G01X1535973D01*
G02Y1623878I0J-1502D01*
G01X1532573D01*
G37*
G36*
G01X1520513Y1655790D02*
G02Y1658794I0J1502D01*
G01X1523913D01*
G02Y1655790I0J-1502D01*
G01X1520513D01*
G37*
G36*
G01X1532573D02*
G02Y1658794I0J1502D01*
G01X1535973D01*
G02Y1655790I0J-1502D01*
G01X1532573D01*
G37*
G36*
G01X1544633D02*
G02Y1658794I0J1502D01*
G01X1548033D01*
G02Y1655790I0J-1502D01*
G01X1544633D01*
G37*
G36*
G01X1484333D02*
G02Y1658794I0J1502D01*
G01X1487733D01*
G02Y1655790I0J-1502D01*
G01X1484333D01*
G37*
G36*
G01X1262369Y1645790D02*
G02Y1648794I0J1502D01*
G01X1265769D01*
G02Y1645790I0J-1502D01*
G01X1262369D01*
G37*
G36*
G01Y1633878D02*
G02Y1636882I0J1502D01*
G01X1265769D01*
G02Y1633878I0J-1502D01*
G01X1262369D01*
G37*
G36*
G01X1274429D02*
G02Y1636882I0J1502D01*
G01X1277829D01*
G02Y1633878I0J-1502D01*
G01X1274429D01*
G37*
G36*
G01X1214129Y1645790D02*
G02Y1648794I0J1502D01*
G01X1217529D01*
G02Y1645790I0J-1502D01*
G01X1214129D01*
G37*
G36*
G01X1238249D02*
G02Y1648794I0J1502D01*
G01X1241649D01*
G02Y1645790I0J-1502D01*
G01X1238249D01*
G37*
G36*
G01X1250309D02*
G02Y1648794I0J1502D01*
G01X1253709D01*
G02Y1645790I0J-1502D01*
G01X1250309D01*
G37*
G36*
G01X1364879Y1655790D02*
G02Y1658794I0J1502D01*
G01X1368279D01*
G02Y1655790I0J-1502D01*
G01X1364879D01*
G37*
G36*
G01X354527Y1520264D02*
G02X355587Y1520900I1060J-565D01*
G02X356790Y1519698I1J-1202D01*
G02X356629Y1519098I-1204J1D01*
G01X355084Y1516425D01*
X355082Y1516421D01*
G02X354012Y1515768I-1070J550D01*
G02X352810Y1516970I0J1202D01*
G01Y1516972D01*
G02X352959Y1517551I1202J-1D01*
G01X354525Y1520261D01*
X354527Y1520264D01*
G37*
G36*
G01X482380Y140440D02*
G02Y143444I0J1502D01*
G01X485780D01*
G02Y140440I0J-1502D01*
G01X482380D01*
G37*
G36*
G01X537148Y89555D02*
G02X539273Y91680I1062J1062D01*
G01X541678Y89276D01*
G02X542118Y88214I-1063J-1063D01*
G01Y88213D01*
G02X540615Y86710I-1503J0D01*
G01X540614D01*
G02X539552Y87150I1J1503D01*
G01X537148Y89555D01*
G37*
G36*
G01X472895Y128518D02*
G02Y131522I0J1502D01*
G01X476295D01*
G02Y128518I0J-1502D01*
G01X472895D01*
G37*
G36*
G01X445014Y93182D02*
G02Y96186I0J1502D01*
G01X448414D01*
G02Y93182I0J-1502D01*
G01X445014D01*
G37*
G36*
G01X514240Y95644D02*
G02Y98648I0J1502D01*
G01X517640D01*
G02Y95644I0J-1502D01*
G01X514240D01*
G37*
G36*
G01X552105Y110700D02*
G02Y113706I0J1503D01*
G01X555505D01*
G02Y110700I0J-1503D01*
G01X552105D01*
G37*
G36*
G01X330905Y1520264D02*
G02X331965Y1520900I1060J-565D01*
G02X333168Y1519698I1J-1202D01*
G02X333007Y1519098I-1204J1D01*
G01X331462Y1516425D01*
X331460Y1516421D01*
G02X330390Y1515768I-1070J550D01*
G02X329188Y1516970I0J1202D01*
G01Y1516972D01*
G02X329337Y1517551I1202J-1D01*
G01X330903Y1520261D01*
X330905Y1520264D01*
G37*
G36*
G01X452102Y87208D02*
G02Y90214I0J1503D01*
G01X455502D01*
G02Y87208I0J-1503D01*
G01X452102D01*
G37*
G36*
G01X321456Y1520264D02*
G02X322516Y1520900I1060J-565D01*
G02X323718Y1519698I0J-1202D01*
G02X323558Y1519098I-1203J0D01*
G01X322013Y1516425D01*
X322011Y1516421D01*
G02X320941Y1515768I-1070J550D01*
G02X319738Y1516970I-1J1202D01*
G01Y1516972D01*
G02X319888Y1517551I1203J-3D01*
G01X321454Y1520261D01*
X321456Y1520264D01*
G37*
G36*
G01X316732D02*
G02X317792Y1520900I1060J-565D01*
G02X318994Y1519698I0J-1202D01*
G02X318834Y1519098I-1203J0D01*
G01X317289Y1516425D01*
X317287Y1516421D01*
G02X316217Y1515768I-1070J550D01*
G02X315014Y1516970I-1J1202D01*
G01Y1516972D01*
G02X315164Y1517551I1203J-3D01*
G01X316730Y1520261D01*
X316732Y1520264D01*
G37*
G36*
G01X459056Y93598D02*
G02Y96604I0J1503D01*
G01X462456D01*
G02Y93598I0J-1503D01*
G01X459056D01*
G37*
G36*
G01X363976Y1520264D02*
G02X365036Y1520900I1060J-565D01*
G02X366238Y1519698I0J-1202D01*
G02X366078Y1519098I-1203J0D01*
G01X364533Y1516425D01*
X364531Y1516421D01*
G02X363461Y1515768I-1070J550D01*
G02X362258Y1516970I-1J1202D01*
G01Y1516972D01*
G02X362408Y1517551I1203J-3D01*
G01X363974Y1520261D01*
X363976Y1520264D01*
G37*
G36*
G01X490380Y129940D02*
G02Y132944I0J1502D01*
G01X493780D01*
G02Y129940I0J-1502D01*
G01X490380D01*
G37*
G36*
G01X349802Y1520264D02*
G02X350862Y1520900I1060J-565D01*
G02X352064Y1519698I0J-1202D01*
G02X351904Y1519098I-1203J0D01*
G01X350359Y1516425D01*
X350357Y1516421D01*
G02X349287Y1515768I-1070J550D01*
G02X348084Y1516970I-1J1202D01*
G01Y1516972D01*
G02X348234Y1517551I1203J-3D01*
G01X349800Y1520261D01*
X349802Y1520264D01*
G37*
G36*
G01X533918Y45564D02*
G02Y48570I0J1503D01*
G01X537318D01*
G02Y45564I0J-1503D01*
G01X533918D01*
G37*
G36*
G01X1549274Y24974D02*
G02Y27980I0J1503D01*
G01X1552674D01*
G02Y24974I0J-1503D01*
G01X1549274D01*
G37*
G36*
G01X1685967D02*
G02Y27980I0J1503D01*
G01X1689367D01*
G02Y24974I0J-1503D01*
G01X1685967D01*
G37*
G36*
G01X1612566Y73838D02*
G02Y76842I0J1502D01*
G01X1615966D01*
G02Y73838I0J-1502D01*
G01X1612566D01*
G37*
G36*
G01X1623562Y67840D02*
G02Y70846I0J1503D01*
G01X1626962D01*
G02Y67840I0J-1503D01*
G01X1623562D01*
G37*
G36*
G01X1563447Y24974D02*
G02Y27980I0J1503D01*
G01X1566847D01*
G02Y24974I0J-1503D01*
G01X1563447D01*
G37*
G36*
G01X1627660D02*
G02Y27980I0J1503D01*
G01X1631060D01*
G02Y24974I0J-1503D01*
G01X1627660D01*
G37*
G36*
G01X1598899Y18038D02*
G02Y21044I0J1503D01*
G01X1602299D01*
G02Y18038I0J-1503D01*
G01X1598899D01*
G37*
G36*
G01X1570552D02*
G02Y21044I0J1503D01*
G01X1573952D01*
G02Y18038I0J-1503D01*
G01X1570552D01*
G37*
G36*
G01X1591794Y24974D02*
G02Y27980I0J1503D01*
G01X1595194D01*
G02Y24974I0J-1503D01*
G01X1591794D01*
G37*
G36*
G01X1648938Y18038D02*
G02Y21044I0J1503D01*
G01X1652338D01*
G02Y18038I0J-1503D01*
G01X1648938D01*
G37*
G36*
G01X1601562Y67840D02*
G02Y70846I0J1503D01*
G01X1604962D01*
G02Y67840I0J-1503D01*
G01X1601562D01*
G37*
G36*
G01X1701904Y73838D02*
G02Y76842I0J1502D01*
G01X1705304D01*
G02Y73838I0J-1502D01*
G01X1701904D01*
G37*
G36*
G01X1679904D02*
G02Y76842I0J1502D01*
G01X1683304D01*
G02Y73838I0J-1502D01*
G01X1679904D01*
G37*
G36*
G01X1668770Y67838D02*
G02Y70842I0J1502D01*
G01X1672170D01*
G02Y67838I0J-1502D01*
G01X1668770D01*
G37*
G36*
G01X1657766Y73840D02*
G02Y76846I0J1503D01*
G01X1661166D01*
G02Y73840I0J-1503D01*
G01X1657766D01*
G37*
G36*
G01X1646770Y67838D02*
G02Y70842I0J1502D01*
G01X1650170D01*
G02Y67838I0J-1502D01*
G01X1646770D01*
G37*
G36*
G01X1635770Y73838D02*
G02Y76842I0J1502D01*
G01X1639170D01*
G02Y73838I0J-1502D01*
G01X1635770D01*
G37*
G36*
G01X1584725Y18038D02*
G02Y21044I0J1503D01*
G01X1588125D01*
G02Y18038I0J-1503D01*
G01X1584725D01*
G37*
G36*
G01X1671794Y24974D02*
G02Y27980I0J1503D01*
G01X1675194D01*
G02Y24974I0J-1503D01*
G01X1671794D01*
G37*
G36*
G01X1590566Y73838D02*
G02Y76842I0J1502D01*
G01X1593966D01*
G02Y73838I0J-1502D01*
G01X1590566D01*
G37*
G36*
G01X1546562Y73840D02*
G02Y76846I0J1503D01*
G01X1549962D01*
G02Y73840I0J-1503D01*
G01X1546562D01*
G37*
G36*
G01X1579566Y67838D02*
G02Y70842I0J1502D01*
G01X1582966D01*
G02Y67838I0J-1502D01*
G01X1579566D01*
G37*
G36*
G01X1557566D02*
G02Y70842I0J1502D01*
G01X1560966D01*
G02Y67838I0J-1502D01*
G01X1557566D01*
G37*
G36*
G01X1535566D02*
G02Y70842I0J1502D01*
G01X1538966D01*
G02Y67838I0J-1502D01*
G01X1535566D01*
G37*
G36*
G01X1568566Y73838D02*
G02Y76842I0J1502D01*
G01X1571966D01*
G02Y73838I0J-1502D01*
G01X1568566D01*
G37*
G36*
G01X218663Y18038D02*
G02Y21044I0J1503D01*
G01X222063D01*
G02Y18038I0J-1503D01*
G01X218663D01*
G37*
G36*
G01X211558Y24974D02*
G02Y27980I0J1503D01*
G01X214958D01*
G02Y24974I0J-1503D01*
G01X211558D01*
G37*
G36*
G01X204490Y18038D02*
G02Y21044I0J1503D01*
G01X207890D01*
G02Y18038I0J-1503D01*
G01X204490D01*
G37*
G36*
G01X197385Y24974D02*
G02Y27980I0J1503D01*
G01X200785D01*
G02Y24974I0J-1503D01*
G01X197385D01*
G37*
G36*
G01X174529Y18038D02*
G02Y21044I0J1503D01*
G01X177929D01*
G02Y18038I0J-1503D01*
G01X174529D01*
G37*
G36*
G01X160356D02*
G02Y21044I0J1503D01*
G01X163756D01*
G02Y18038I0J-1503D01*
G01X160356D01*
G37*
G36*
G01X167424Y24974D02*
G02Y27980I0J1503D01*
G01X170824D01*
G02Y24974I0J-1503D01*
G01X167424D01*
G37*
G36*
G01X153251D02*
G02Y27980I0J1503D01*
G01X156651D01*
G02Y24974I0J-1503D01*
G01X153251D01*
G37*
G36*
G01X124490Y18038D02*
G02Y21044I0J1503D01*
G01X127890D01*
G02Y18038I0J-1503D01*
G01X124490D01*
G37*
G36*
G01X117385Y24974D02*
G02Y27980I0J1503D01*
G01X120785D01*
G02Y24974I0J-1503D01*
G01X117385D01*
G37*
G36*
G01X110316Y18038D02*
G02Y21044I0J1503D01*
G01X113716D01*
G02Y18038I0J-1503D01*
G01X110316D01*
G37*
G36*
G01X103211Y24974D02*
G02Y27980I0J1503D01*
G01X106611D01*
G02Y24974I0J-1503D01*
G01X103211D01*
G37*
G36*
G01X96143Y18038D02*
G02Y21044I0J1503D01*
G01X99543D01*
G02Y18038I0J-1503D01*
G01X96143D01*
G37*
G36*
G01X89038Y24974D02*
G02Y27980I0J1503D01*
G01X92438D01*
G02Y24974I0J-1503D01*
G01X89038D01*
G37*
G36*
G01X74865D02*
G02Y27980I0J1503D01*
G01X78265D01*
G02Y24974I0J-1503D01*
G01X74865D01*
G37*
G36*
G01X81970Y18038D02*
G02Y21044I0J1503D01*
G01X85370D01*
G02Y18038I0J-1503D01*
G01X81970D01*
G37*
G36*
G01X227495Y73838D02*
G02Y76842I0J1502D01*
G01X230895D01*
G02Y73838I0J-1502D01*
G01X227495D01*
G37*
G36*
G01X216491Y67840D02*
G02Y70846I0J1503D01*
G01X219891D01*
G02Y67840I0J-1503D01*
G01X216491D01*
G37*
G36*
G01X205495Y73838D02*
G02Y76842I0J1502D01*
G01X208895D01*
G02Y73838I0J-1502D01*
G01X205495D01*
G37*
G36*
G01X194361Y67838D02*
G02Y70842I0J1502D01*
G01X197761D01*
G02Y67838I0J-1502D01*
G01X194361D01*
G37*
G36*
G01X172361D02*
G02Y70842I0J1502D01*
G01X175761D01*
G02Y67838I0J-1502D01*
G01X172361D01*
G37*
G36*
G01X183357Y73840D02*
G02Y76846I0J1503D01*
G01X186757D01*
G02Y73840I0J-1503D01*
G01X183357D01*
G37*
G36*
G01X161361Y73838D02*
G02Y76842I0J1502D01*
G01X164761D01*
G02Y73838I0J-1502D01*
G01X161361D01*
G37*
G36*
G01X149153Y67840D02*
G02Y70846I0J1503D01*
G01X152553D01*
G02Y67840I0J-1503D01*
G01X149153D01*
G37*
G36*
G01X138157Y73838D02*
G02Y76842I0J1502D01*
G01X141557D01*
G02Y73838I0J-1502D01*
G01X138157D01*
G37*
G36*
G01X127153Y67840D02*
G02Y70846I0J1503D01*
G01X130553D01*
G02Y67840I0J-1503D01*
G01X127153D01*
G37*
G36*
G01X116157Y73838D02*
G02Y76842I0J1502D01*
G01X119557D01*
G02Y73838I0J-1502D01*
G01X116157D01*
G37*
G36*
G01X105157Y67838D02*
G02Y70842I0J1502D01*
G01X108557D01*
G02Y67838I0J-1502D01*
G01X105157D01*
G37*
G36*
G01X83157D02*
G02Y70842I0J1502D01*
G01X86557D01*
G02Y67838I0J-1502D01*
G01X83157D01*
G37*
G36*
G01X94157Y73838D02*
G02Y76842I0J1502D01*
G01X97557D01*
G02Y73838I0J-1502D01*
G01X94157D01*
G37*
G36*
G01X72153Y73840D02*
G02Y76846I0J1503D01*
G01X75553D01*
G02Y73840I0J-1503D01*
G01X72153D01*
G37*
G36*
G01X61157Y67838D02*
G02Y70842I0J1502D01*
G01X64557D01*
G02Y67838I0J-1502D01*
G01X61157D01*
G37*
G36*
G01X1690900Y67840D02*
G02Y70846I0J1503D01*
G01X1694300D01*
G02Y67840I0J-1503D01*
G01X1690900D01*
G37*
G36*
G01X1693072Y18038D02*
G02Y21044I0J1503D01*
G01X1696472D01*
G02Y18038I0J-1503D01*
G01X1693072D01*
G37*
G36*
G01X1641833Y24974D02*
G02Y27980I0J1503D01*
G01X1645233D01*
G02Y24974I0J-1503D01*
G01X1641833D01*
G37*
G36*
G01X1634765Y18038D02*
G02Y21044I0J1503D01*
G01X1638165D01*
G02Y18038I0J-1503D01*
G01X1634765D01*
G37*
G36*
G01X1678899D02*
G02Y21044I0J1503D01*
G01X1682299D01*
G02Y18038I0J-1503D01*
G01X1678899D01*
G37*
G36*
G01X1577620Y24974D02*
G02Y27980I0J1503D01*
G01X1581020D01*
G02Y24974I0J-1503D01*
G01X1577620D01*
G37*
G36*
G01X1556379Y18038D02*
G02Y21044I0J1503D01*
G01X1559779D01*
G02Y18038I0J-1503D01*
G01X1556379D01*
G37*
G36*
G01X373424Y1520264D02*
G02X374484Y1520900I1060J-565D01*
G02X375686Y1519698I0J-1202D01*
G02X375526Y1519098I-1203J0D01*
G01X373981Y1516425D01*
X373979Y1516421D01*
G02X372909Y1515768I-1070J550D01*
G02X371706Y1516970I-1J1202D01*
G01Y1516972D01*
G02X371856Y1517551I1203J-3D01*
G01X373422Y1520261D01*
X373424Y1520264D01*
G37*
G36*
G01X555176Y69934D02*
G02Y72938I0J1502D01*
G01X558576D01*
G02Y69934I0J-1502D01*
G01X555176D01*
G37*
G36*
G01X45812Y450100D02*
G02Y453104I0J1502D01*
G01X49212D01*
G02Y450100I0J-1502D01*
G01X45812D01*
G37*
G36*
G01X519765Y38826D02*
G02Y41830I0J1502D01*
G01X523165D01*
G02Y38826I0J-1502D01*
G01X519765D01*
G37*
G36*
G01X519743Y69934D02*
G02Y72938I0J1502D01*
G01X523143D01*
G02Y69934I0J-1502D01*
G01X519743D01*
G37*
G36*
G01X1311986Y1484392D02*
G02Y1487398I0J1503D01*
G01X1315386D01*
G02Y1484392I0J-1503D01*
G01X1311986D01*
G37*
G36*
G01X1358849Y1645790D02*
G02Y1648794I0J1502D01*
G01X1362249D01*
G02Y1645790I0J-1502D01*
G01X1358849D01*
G37*
G36*
G01X1334729Y1633878D02*
G02Y1636882I0J1502D01*
G01X1338129D01*
G02Y1633878I0J-1502D01*
G01X1334729D01*
G37*
G36*
G01X1298549Y1645790D02*
G02Y1648794I0J1502D01*
G01X1301949D01*
G02Y1645790I0J-1502D01*
G01X1298549D01*
G37*
G36*
G01X1472273Y1655790D02*
G02Y1658794I0J1502D01*
G01X1475673D01*
G02Y1655790I0J-1502D01*
G01X1472273D01*
G37*
G36*
G01X1604933D02*
G02Y1658794I0J1502D01*
G01X1608333D01*
G02Y1655790I0J-1502D01*
G01X1604933D01*
G37*
G36*
G01X1635083Y1633878D02*
G02Y1636882I0J1502D01*
G01X1638483D01*
G02Y1633878I0J-1502D01*
G01X1635083D01*
G37*
G36*
G01X1629053Y1655790D02*
G02Y1658794I0J1502D01*
G01X1632453D01*
G02Y1655790I0J-1502D01*
G01X1629053D01*
G37*
G36*
G01X1647143Y1645790D02*
G02Y1648794I0J1502D01*
G01X1650543D01*
G02Y1645790I0J-1502D01*
G01X1647143D01*
G37*
G36*
G01X1598903D02*
G02Y1648794I0J1502D01*
G01X1602303D01*
G02Y1645790I0J-1502D01*
G01X1598903D01*
G37*
G36*
G01X1574783D02*
G02Y1648794I0J1502D01*
G01X1578183D01*
G02Y1645790I0J-1502D01*
G01X1574783D01*
G37*
G36*
G01X1346789D02*
G02Y1648794I0J1502D01*
G01X1350189D01*
G02Y1645790I0J-1502D01*
G01X1346789D01*
G37*
G36*
G01X1641113Y1623878D02*
G02Y1626882I0J1502D01*
G01X1644513D01*
G02Y1623878I0J-1502D01*
G01X1641113D01*
G37*
G36*
G01X1607250Y1731341D02*
G02X1607552Y1731644I302J1D01*
G01X1611252D01*
G02X1611554Y1731341I-1J-303D01*
G01Y1721335D01*
G02X1611252Y1721032I-302J-1D01*
G01X1607552D01*
G02X1607250Y1721335I1J303D01*
G01Y1731341D01*
G37*
G36*
G01X1622998D02*
G02X1623300Y1731644I302J1D01*
G01X1627000D01*
G02X1627302Y1731341I-1J-303D01*
G01Y1721335D01*
G02X1627000Y1721032I-302J-1D01*
G01X1623300D01*
G02X1622998Y1721335I1J303D01*
G01Y1731341D01*
G37*
G36*
G01X1599376Y1727404D02*
G02X1599678Y1727706I302J0D01*
G01X1603378D01*
G02X1603680Y1727404I0J-302D01*
G01Y1717398D01*
G02X1603378Y1717096I-302J0D01*
G01X1599678D01*
G02X1599376Y1717398I0J302D01*
G01Y1727404D01*
G37*
G36*
G01X1615124D02*
G02X1615426Y1727706I302J0D01*
G01X1619126D01*
G02X1619428Y1727404I0J-302D01*
G01Y1717398D01*
G02X1619126Y1717096I-302J0D01*
G01X1615426D01*
G02X1615124Y1717398I0J302D01*
G01Y1727404D01*
G37*
G36*
G01X1607250Y1717168D02*
G02X1607552Y1717470I302J0D01*
G01X1611252D01*
G02X1611554Y1717168I0J-302D01*
G01Y1707162D01*
G02X1611252Y1706860I-302J0D01*
G01X1607552D01*
G02X1607250Y1707162I0J302D01*
G01Y1717168D01*
G37*
G36*
G01X1622998D02*
G02X1623300Y1717470I302J0D01*
G01X1627000D01*
G02X1627302Y1717168I0J-302D01*
G01Y1707162D01*
G02X1627000Y1706860I-302J0D01*
G01X1623300D01*
G02X1622998Y1707162I0J302D01*
G01Y1717168D01*
G37*
G36*
G01X1599376Y1713231D02*
G02X1599678Y1713534I302J1D01*
G01X1603378D01*
G02X1603680Y1713231I-1J-303D01*
G01Y1703225D01*
G02X1603378Y1702922I-302J-1D01*
G01X1599678D01*
G02X1599376Y1703225I1J303D01*
G01Y1713231D01*
G37*
G36*
G01X1615124D02*
G02X1615426Y1713534I302J1D01*
G01X1619126D01*
G02X1619428Y1713231I-1J-303D01*
G01Y1703225D01*
G02X1619126Y1702922I-302J-1D01*
G01X1615426D01*
G02X1615124Y1703225I1J303D01*
G01Y1713231D01*
G37*
G36*
G01X1607250Y1702995D02*
G02X1607553Y1703298I303J0D01*
G01X1611253D01*
G02X1611556Y1702995I0J-303D01*
G01Y1692989D01*
G02X1611253Y1692686I-303J0D01*
G01X1607553D01*
G02X1607250Y1692989I0J303D01*
G01Y1702995D01*
G37*
G36*
G01X1622998D02*
G02X1623301Y1703298I303J0D01*
G01X1627001D01*
G02X1627304Y1702995I0J-303D01*
G01Y1692989D01*
G02X1627001Y1692686I-303J0D01*
G01X1623301D01*
G02X1622998Y1692989I0J303D01*
G01Y1702995D01*
G37*
G36*
G01X1599376Y1699058D02*
G02X1599679Y1699360I303J-1D01*
G01X1603379D01*
G02X1603682Y1699058I1J-302D01*
G01Y1689052D01*
G02X1603379Y1688750I-303J1D01*
G01X1599679D01*
G02X1599376Y1689052I-1J302D01*
G01Y1699058D01*
G37*
G36*
G01X1615124D02*
G02X1615427Y1699360I303J-1D01*
G01X1619127D01*
G02X1619430Y1699058I1J-302D01*
G01Y1689052D01*
G02X1619127Y1688750I-303J1D01*
G01X1615427D01*
G02X1615124Y1689052I-1J302D01*
G01Y1699058D01*
G37*
G36*
G01X1607250Y1685958D02*
Y1688820D01*
G02X1607552Y1689122I302J0D01*
G01X1611252D01*
G02X1611554Y1688820I0J-302D01*
G01Y1678814D01*
G02X1611252Y1678512I-302J0D01*
G01X1607552D01*
G02X1607250Y1678814I0J302D01*
G01Y1681678D01*
G02X1607281Y1681812I302J1D01*
G01X1608200Y1683687D01*
G03Y1683949I-267J131D01*
G01X1607281Y1685824D01*
G02X1607250Y1685958I271J133D01*
G37*
G36*
G01X1622998Y1685959D02*
Y1688821D01*
G02X1623300Y1689124I302J1D01*
G01X1627000D01*
G02X1627302Y1688821I-1J-303D01*
G01Y1678815D01*
G02X1627000Y1678512I-302J-1D01*
G01X1623300D01*
G02X1622998Y1678815I1J303D01*
G01Y1681679D01*
G02X1623029Y1681813I302J1D01*
G01X1623948Y1683688D01*
G03Y1683950I-267J131D01*
G01X1623029Y1685825D01*
G02X1622998Y1685959I271J133D01*
G37*
G36*
G01X1599376Y1682022D02*
Y1684884D01*
G02X1599678Y1685186I302J0D01*
G01X1603378D01*
G02X1603680Y1684884I0J-302D01*
G01Y1674878D01*
G02X1603378Y1674576I-302J0D01*
G01X1599678D01*
G02X1599376Y1674878I0J302D01*
G01Y1677742D01*
G02X1599407Y1677876I302J1D01*
G01X1600326Y1679751D01*
G03Y1680013I-267J131D01*
G01X1599407Y1681888D01*
G02X1599376Y1682022I271J133D01*
G37*
G36*
G01X1615124D02*
Y1684884D01*
G02X1615426Y1685186I302J0D01*
G01X1619126D01*
G02X1619428Y1684884I0J-302D01*
G01Y1674878D01*
G02X1619126Y1674576I-302J0D01*
G01X1615426D01*
G02X1615124Y1674878I0J302D01*
G01Y1677742D01*
G02X1615155Y1677876I302J1D01*
G01X1616074Y1679751D01*
G03Y1680013I-267J131D01*
G01X1615155Y1681888D01*
G02X1615124Y1682022I271J133D01*
G37*
G36*
G01X1575754Y1731341D02*
G02X1576056Y1731644I302J1D01*
G01X1579756D01*
G02X1580058Y1731341I-1J-303D01*
G01Y1721335D01*
G02X1579756Y1721032I-302J-1D01*
G01X1576056D01*
G02X1575754Y1721335I1J303D01*
G01Y1731341D01*
G37*
G36*
G01X1591502D02*
G02X1591804Y1731644I302J1D01*
G01X1595504D01*
G02X1595806Y1731341I-1J-303D01*
G01Y1721335D01*
G02X1595504Y1721032I-302J-1D01*
G01X1591804D01*
G02X1591502Y1721335I1J303D01*
G01Y1731341D01*
G37*
G36*
G01X1567880Y1727404D02*
G02X1568182Y1727706I302J0D01*
G01X1571882D01*
G02X1572184Y1727404I0J-302D01*
G01Y1717398D01*
G02X1571882Y1717096I-302J0D01*
G01X1568182D01*
G02X1567880Y1717398I0J302D01*
G01Y1727404D01*
G37*
G36*
G01X1583628D02*
G02X1583930Y1727706I302J0D01*
G01X1587630D01*
G02X1587932Y1727404I0J-302D01*
G01Y1717398D01*
G02X1587630Y1717096I-302J0D01*
G01X1583930D01*
G02X1583628Y1717398I0J302D01*
G01Y1727404D01*
G37*
G36*
G01X1575754Y1717168D02*
G02X1576056Y1717470I302J0D01*
G01X1579756D01*
G02X1580058Y1717168I0J-302D01*
G01Y1707162D01*
G02X1579756Y1706860I-302J0D01*
G01X1576056D01*
G02X1575754Y1707162I0J302D01*
G01Y1717168D01*
G37*
G36*
G01X1591502D02*
G02X1591804Y1717470I302J0D01*
G01X1595504D01*
G02X1595806Y1717168I0J-302D01*
G01Y1707162D01*
G02X1595504Y1706860I-302J0D01*
G01X1591804D01*
G02X1591502Y1707162I0J302D01*
G01Y1717168D01*
G37*
G36*
G01X1567880Y1713231D02*
G02X1568182Y1713534I302J1D01*
G01X1571882D01*
G02X1572184Y1713231I-1J-303D01*
G01Y1703225D01*
G02X1571882Y1702922I-302J-1D01*
G01X1568182D01*
G02X1567880Y1703225I1J303D01*
G01Y1713231D01*
G37*
G36*
G01X1583628D02*
G02X1583930Y1713534I302J1D01*
G01X1587630D01*
G02X1587932Y1713231I-1J-303D01*
G01Y1703225D01*
G02X1587630Y1702922I-302J-1D01*
G01X1583930D01*
G02X1583628Y1703225I1J303D01*
G01Y1713231D01*
G37*
G36*
G01X1575754Y1702995D02*
G02X1576057Y1703298I303J0D01*
G01X1579757D01*
G02X1580060Y1702995I0J-303D01*
G01Y1692989D01*
G02X1579757Y1692686I-303J0D01*
G01X1576057D01*
G02X1575754Y1692989I0J303D01*
G01Y1702995D01*
G37*
G36*
G01X1591502D02*
G02X1591805Y1703298I303J0D01*
G01X1595505D01*
G02X1595808Y1702995I0J-303D01*
G01Y1692989D01*
G02X1595505Y1692686I-303J0D01*
G01X1591805D01*
G02X1591502Y1692989I0J303D01*
G01Y1702995D01*
G37*
G36*
G01X1567880Y1699058D02*
G02X1568183Y1699360I303J-1D01*
G01X1571883D01*
G02X1572186Y1699058I1J-302D01*
G01Y1689052D01*
G02X1571883Y1688750I-303J1D01*
G01X1568183D01*
G02X1567880Y1689052I-1J302D01*
G01Y1699058D01*
G37*
G36*
G01X1583628D02*
G02X1583931Y1699360I303J-1D01*
G01X1587631D01*
G02X1587934Y1699058I1J-302D01*
G01Y1689052D01*
G02X1587631Y1688750I-303J1D01*
G01X1583931D01*
G02X1583628Y1689052I-1J302D01*
G01Y1699058D01*
G37*
G36*
G01X1575754Y1685959D02*
Y1688821D01*
G02X1576056Y1689124I302J1D01*
G01X1579756D01*
G02X1580058Y1688821I-1J-303D01*
G01Y1678815D01*
G02X1579756Y1678512I-302J-1D01*
G01X1576056D01*
G02X1575754Y1678815I1J303D01*
G01Y1681679D01*
G02X1575785Y1681813I302J1D01*
G01X1576704Y1683688D01*
G03Y1683950I-267J131D01*
G01X1575785Y1685825D01*
G02X1575754Y1685959I271J133D01*
G37*
G36*
G01X1591502D02*
Y1688821D01*
G02X1591804Y1689124I302J1D01*
G01X1595504D01*
G02X1595806Y1688821I-1J-303D01*
G01Y1678815D01*
G02X1595504Y1678512I-302J-1D01*
G01X1591804D01*
G02X1591502Y1678815I1J303D01*
G01Y1681679D01*
G02X1591533Y1681813I302J1D01*
G01X1592452Y1683688D01*
G03Y1683950I-267J131D01*
G01X1591533Y1685825D01*
G02X1591502Y1685959I271J133D01*
G37*
G36*
G01X1567880Y1682022D02*
Y1684884D01*
G02X1568182Y1685186I302J0D01*
G01X1571882D01*
G02X1572184Y1684884I0J-302D01*
G01Y1674878D01*
G02X1571882Y1674576I-302J0D01*
G01X1568182D01*
G02X1567880Y1674878I0J302D01*
G01Y1677742D01*
G02X1567911Y1677876I302J1D01*
G01X1568830Y1679751D01*
G03Y1680013I-267J131D01*
G01X1567911Y1681888D01*
G02X1567880Y1682022I271J133D01*
G37*
G36*
G01X1583628D02*
Y1684884D01*
G02X1583930Y1685186I302J0D01*
G01X1587630D01*
G02X1587932Y1684884I0J-302D01*
G01Y1674878D01*
G02X1587630Y1674576I-302J0D01*
G01X1583930D01*
G02X1583628Y1674878I0J302D01*
G01Y1677742D01*
G02X1583659Y1677876I302J1D01*
G01X1584578Y1679751D01*
G03Y1680013I-267J131D01*
G01X1583659Y1681888D01*
G02X1583628Y1682022I271J133D01*
G37*
G36*
G01X1540320Y1731341D02*
G02X1540623Y1731644I303J0D01*
G01X1544323D01*
G02X1544626Y1731341I0J-303D01*
G01Y1721335D01*
G02X1544323Y1721032I-303J0D01*
G01X1540623D01*
G02X1540320Y1721335I0J303D01*
G01Y1731341D01*
G37*
G36*
G01X1556068D02*
G02X1556371Y1731644I303J0D01*
G01X1560071D01*
G02X1560374Y1731341I0J-303D01*
G01Y1721335D01*
G02X1560071Y1721032I-303J0D01*
G01X1556371D01*
G02X1556068Y1721335I0J303D01*
G01Y1731341D01*
G37*
G36*
G01X1532446Y1727404D02*
G02X1532749Y1727706I303J-1D01*
G01X1536449D01*
G02X1536752Y1727404I1J-302D01*
G01Y1717398D01*
G02X1536449Y1717096I-303J1D01*
G01X1532749D01*
G02X1532446Y1717398I-1J302D01*
G01Y1727404D01*
G37*
G36*
G01X1548194D02*
G02X1548497Y1727706I303J-1D01*
G01X1552197D01*
G02X1552500Y1727404I1J-302D01*
G01Y1717398D01*
G02X1552197Y1717096I-303J1D01*
G01X1548497D01*
G02X1548194Y1717398I-1J302D01*
G01Y1727404D01*
G37*
G36*
G01X1540320Y1717168D02*
G02X1540623Y1717470I303J-1D01*
G01X1544323D01*
G02X1544626Y1717168I1J-302D01*
G01Y1707162D01*
G02X1544323Y1706860I-303J1D01*
G01X1540623D01*
G02X1540320Y1707162I-1J302D01*
G01Y1717168D01*
G37*
G36*
G01X1556068D02*
G02X1556371Y1717470I303J-1D01*
G01X1560071D01*
G02X1560374Y1717168I1J-302D01*
G01Y1707162D01*
G02X1560071Y1706860I-303J1D01*
G01X1556371D01*
G02X1556068Y1707162I-1J302D01*
G01Y1717168D01*
G37*
G36*
G01X1532446Y1713231D02*
G02X1532749Y1713534I303J0D01*
G01X1536449D01*
G02X1536752Y1713231I0J-303D01*
G01Y1703225D01*
G02X1536449Y1702922I-303J0D01*
G01X1532749D01*
G02X1532446Y1703225I0J303D01*
G01Y1713231D01*
G37*
G36*
G01X1548194D02*
G02X1548497Y1713534I303J0D01*
G01X1552197D01*
G02X1552500Y1713231I0J-303D01*
G01Y1703225D01*
G02X1552197Y1702922I-303J0D01*
G01X1548497D01*
G02X1548194Y1703225I0J303D01*
G01Y1713231D01*
G37*
G36*
G01X1540320Y1702995D02*
G02X1540623Y1703298I303J0D01*
G01X1544323D01*
G02X1544626Y1702995I0J-303D01*
G01Y1692989D01*
G02X1544323Y1692686I-303J0D01*
G01X1540623D01*
G02X1540320Y1692989I0J303D01*
G01Y1702995D01*
G37*
G36*
G01X1556068D02*
G02X1556371Y1703298I303J0D01*
G01X1560071D01*
G02X1560374Y1702995I0J-303D01*
G01Y1692989D01*
G02X1560071Y1692686I-303J0D01*
G01X1556371D01*
G02X1556068Y1692989I0J303D01*
G01Y1702995D01*
G37*
G36*
G01X1532446Y1699058D02*
G02X1532749Y1699360I303J-1D01*
G01X1536449D01*
G02X1536752Y1699058I1J-302D01*
G01Y1689052D01*
G02X1536449Y1688750I-303J1D01*
G01X1532749D01*
G02X1532446Y1689052I-1J302D01*
G01Y1699058D01*
G37*
G36*
G01X1548194D02*
G02X1548497Y1699360I303J-1D01*
G01X1552197D01*
G02X1552500Y1699058I1J-302D01*
G01Y1689052D01*
G02X1552197Y1688750I-303J1D01*
G01X1548497D01*
G02X1548194Y1689052I-1J302D01*
G01Y1699058D01*
G37*
G36*
G01X1540320Y1685959D02*
Y1688821D01*
G02X1540623Y1689124I303J0D01*
G01X1544323D01*
G02X1544626Y1688821I0J-303D01*
G01Y1678815D01*
G02X1544323Y1678512I-303J0D01*
G01X1540623D01*
G02X1540320Y1678815I0J303D01*
G01Y1681679D01*
G02X1540352Y1681813I303J-1D01*
G01X1541271Y1683688D01*
G03Y1683950I-267J131D01*
G01X1540352Y1685825D01*
G02X1540320Y1685959I270J135D01*
G37*
G36*
G01X1556068D02*
Y1688821D01*
G02X1556371Y1689124I303J0D01*
G01X1560071D01*
G02X1560374Y1688821I0J-303D01*
G01Y1678815D01*
G02X1560071Y1678512I-303J0D01*
G01X1556371D01*
G02X1556068Y1678815I0J303D01*
G01Y1681679D01*
G02X1556100Y1681813I303J-1D01*
G01X1557019Y1683688D01*
G03Y1683950I-267J131D01*
G01X1556100Y1685825D01*
G02X1556068Y1685959I270J135D01*
G37*
G36*
G01X1532446Y1682022D02*
Y1684884D01*
G02X1532749Y1685186I303J-1D01*
G01X1536449D01*
G02X1536752Y1684884I1J-302D01*
G01Y1674878D01*
G02X1536449Y1674576I-303J1D01*
G01X1532749D01*
G02X1532446Y1674878I-1J302D01*
G01Y1677742D01*
G02X1532478Y1677876I303J-1D01*
G01X1533397Y1679751D01*
G03Y1680013I-267J131D01*
G01X1532478Y1681888D01*
G02X1532446Y1682022I270J135D01*
G37*
G36*
G01X1548194D02*
Y1684884D01*
G02X1548497Y1685186I303J-1D01*
G01X1552197D01*
G02X1552500Y1684884I1J-302D01*
G01Y1674878D01*
G02X1552197Y1674576I-303J1D01*
G01X1548497D01*
G02X1548194Y1674878I-1J302D01*
G01Y1677742D01*
G02X1548226Y1677876I303J-1D01*
G01X1549145Y1679751D01*
G03Y1680013I-267J131D01*
G01X1548226Y1681888D01*
G02X1548194Y1682022I270J135D01*
G37*
G36*
G01X1508824Y1731341D02*
G02X1509127Y1731644I303J0D01*
G01X1512827D01*
G02X1513130Y1731341I0J-303D01*
G01Y1721335D01*
G02X1512827Y1721032I-303J0D01*
G01X1509127D01*
G02X1508824Y1721335I0J303D01*
G01Y1731341D01*
G37*
G36*
G01X1524572D02*
G02X1524875Y1731644I303J0D01*
G01X1528575D01*
G02X1528878Y1731341I0J-303D01*
G01Y1721335D01*
G02X1528575Y1721032I-303J0D01*
G01X1524875D01*
G02X1524572Y1721335I0J303D01*
G01Y1731341D01*
G37*
G36*
G01X1500950Y1727404D02*
G02X1501253Y1727706I303J-1D01*
G01X1504953D01*
G02X1505256Y1727404I1J-302D01*
G01Y1717398D01*
G02X1504953Y1717096I-303J1D01*
G01X1501253D01*
G02X1500950Y1717398I-1J302D01*
G01Y1727404D01*
G37*
G36*
G01X1516698D02*
G02X1517001Y1727706I303J-1D01*
G01X1520701D01*
G02X1521004Y1727404I1J-302D01*
G01Y1717398D01*
G02X1520701Y1717096I-303J1D01*
G01X1517001D01*
G02X1516698Y1717398I-1J302D01*
G01Y1727404D01*
G37*
G36*
G01X1508824Y1717168D02*
G02X1509127Y1717470I303J-1D01*
G01X1512827D01*
G02X1513130Y1717168I1J-302D01*
G01Y1707162D01*
G02X1512827Y1706860I-303J1D01*
G01X1509127D01*
G02X1508824Y1707162I-1J302D01*
G01Y1717168D01*
G37*
G36*
G01X1524572D02*
G02X1524875Y1717470I303J-1D01*
G01X1528575D01*
G02X1528878Y1717168I1J-302D01*
G01Y1707162D01*
G02X1528575Y1706860I-303J1D01*
G01X1524875D01*
G02X1524572Y1707162I-1J302D01*
G01Y1717168D01*
G37*
G36*
G01X1500950Y1713231D02*
G02X1501253Y1713534I303J0D01*
G01X1504953D01*
G02X1505256Y1713231I0J-303D01*
G01Y1703225D01*
G02X1504953Y1702922I-303J0D01*
G01X1501253D01*
G02X1500950Y1703225I0J303D01*
G01Y1713231D01*
G37*
G36*
G01X1516698D02*
G02X1517001Y1713534I303J0D01*
G01X1520701D01*
G02X1521004Y1713231I0J-303D01*
G01Y1703225D01*
G02X1520701Y1702922I-303J0D01*
G01X1517001D01*
G02X1516698Y1703225I0J303D01*
G01Y1713231D01*
G37*
G36*
G01X1508824Y1702995D02*
G02X1509127Y1703298I303J0D01*
G01X1512827D01*
G02X1513130Y1702995I0J-303D01*
G01Y1692989D01*
G02X1512827Y1692686I-303J0D01*
G01X1509127D01*
G02X1508824Y1692989I0J303D01*
G01Y1702995D01*
G37*
G36*
G01X1524572D02*
G02X1524875Y1703298I303J0D01*
G01X1528575D01*
G02X1528878Y1702995I0J-303D01*
G01Y1692989D01*
G02X1528575Y1692686I-303J0D01*
G01X1524875D01*
G02X1524572Y1692989I0J303D01*
G01Y1702995D01*
G37*
G36*
G01X1500950Y1699058D02*
G02X1501253Y1699360I303J-1D01*
G01X1504953D01*
G02X1505256Y1699058I1J-302D01*
G01Y1689052D01*
G02X1504953Y1688750I-303J1D01*
G01X1501253D01*
G02X1500950Y1689052I-1J302D01*
G01Y1699058D01*
G37*
G36*
G01X1516698D02*
G02X1517001Y1699360I303J-1D01*
G01X1520701D01*
G02X1521004Y1699058I1J-302D01*
G01Y1689052D01*
G02X1520701Y1688750I-303J1D01*
G01X1517001D01*
G02X1516698Y1689052I-1J302D01*
G01Y1699058D01*
G37*
G36*
G01X1508824Y1685959D02*
Y1688821D01*
G02X1509127Y1689124I303J0D01*
G01X1512827D01*
G02X1513130Y1688821I0J-303D01*
G01Y1678815D01*
G02X1512827Y1678512I-303J0D01*
G01X1509127D01*
G02X1508824Y1678815I0J303D01*
G01Y1681679D01*
G02X1508856Y1681813I303J-1D01*
G01X1509775Y1683688D01*
G03Y1683950I-267J131D01*
G01X1508856Y1685825D01*
G02X1508824Y1685959I270J135D01*
G37*
G36*
G01X1524572D02*
Y1688821D01*
G02X1524875Y1689124I303J0D01*
G01X1528575D01*
G02X1528878Y1688821I0J-303D01*
G01Y1678815D01*
G02X1528575Y1678512I-303J0D01*
G01X1524875D01*
G02X1524572Y1678815I0J303D01*
G01Y1681679D01*
G02X1524604Y1681813I303J-1D01*
G01X1525523Y1683688D01*
G03Y1683950I-267J131D01*
G01X1524604Y1685825D01*
G02X1524572Y1685959I270J135D01*
G37*
G36*
G01X1500950Y1682022D02*
Y1684884D01*
G02X1501253Y1685186I303J-1D01*
G01X1504953D01*
G02X1505256Y1684884I1J-302D01*
G01Y1674878D01*
G02X1504953Y1674576I-303J1D01*
G01X1501253D01*
G02X1500950Y1674878I-1J302D01*
G01Y1677742D01*
G02X1500982Y1677876I303J-1D01*
G01X1501901Y1679751D01*
G03Y1680013I-267J131D01*
G01X1500982Y1681888D01*
G02X1500950Y1682022I270J135D01*
G37*
G36*
G01X1516698D02*
Y1684884D01*
G02X1517001Y1685186I303J-1D01*
G01X1520701D01*
G02X1521004Y1684884I1J-302D01*
G01Y1674878D01*
G02X1520701Y1674576I-303J1D01*
G01X1517001D01*
G02X1516698Y1674878I-1J302D01*
G01Y1677742D01*
G02X1516730Y1677876I303J-1D01*
G01X1517649Y1679751D01*
G03Y1680013I-267J131D01*
G01X1516730Y1681888D01*
G02X1516698Y1682022I270J135D01*
G37*
G36*
G01X1343076Y1731341D02*
G02X1343378Y1731644I302J1D01*
G01X1347078D01*
G02X1347380Y1731341I-1J-303D01*
G01Y1721335D01*
G02X1347078Y1721032I-302J-1D01*
G01X1343378D01*
G02X1343076Y1721335I1J303D01*
G01Y1731341D01*
G37*
G36*
G01X1358824D02*
G02X1359126Y1731644I302J1D01*
G01X1362826D01*
G02X1363128Y1731341I-1J-303D01*
G01Y1721335D01*
G02X1362826Y1721032I-302J-1D01*
G01X1359126D01*
G02X1358824Y1721335I1J303D01*
G01Y1731341D01*
G37*
G36*
G01X1335202Y1727404D02*
G02X1335504Y1727706I302J0D01*
G01X1339204D01*
G02X1339506Y1727404I0J-302D01*
G01Y1717398D01*
G02X1339204Y1717096I-302J0D01*
G01X1335504D01*
G02X1335202Y1717398I0J302D01*
G01Y1727404D01*
G37*
G36*
G01X1350950D02*
G02X1351252Y1727706I302J0D01*
G01X1354952D01*
G02X1355254Y1727404I0J-302D01*
G01Y1717398D01*
G02X1354952Y1717096I-302J0D01*
G01X1351252D01*
G02X1350950Y1717398I0J302D01*
G01Y1727404D01*
G37*
G36*
G01X1343076Y1717168D02*
G02X1343378Y1717470I302J0D01*
G01X1347078D01*
G02X1347380Y1717168I0J-302D01*
G01Y1707162D01*
G02X1347078Y1706860I-302J0D01*
G01X1343378D01*
G02X1343076Y1707162I0J302D01*
G01Y1717168D01*
G37*
G36*
G01X1358824D02*
G02X1359126Y1717470I302J0D01*
G01X1362826D01*
G02X1363128Y1717168I0J-302D01*
G01Y1707162D01*
G02X1362826Y1706860I-302J0D01*
G01X1359126D01*
G02X1358824Y1707162I0J302D01*
G01Y1717168D01*
G37*
G36*
G01X1335202Y1713231D02*
G02X1335504Y1713534I302J1D01*
G01X1339204D01*
G02X1339506Y1713231I-1J-303D01*
G01Y1703225D01*
G02X1339204Y1702922I-302J-1D01*
G01X1335504D01*
G02X1335202Y1703225I1J303D01*
G01Y1713231D01*
G37*
G36*
G01X1350950D02*
G02X1351252Y1713534I302J1D01*
G01X1354952D01*
G02X1355254Y1713231I-1J-303D01*
G01Y1703225D01*
G02X1354952Y1702922I-302J-1D01*
G01X1351252D01*
G02X1350950Y1703225I1J303D01*
G01Y1713231D01*
G37*
G36*
G01X1343076Y1702995D02*
G02X1343379Y1703298I303J0D01*
G01X1347079D01*
G02X1347382Y1702995I0J-303D01*
G01Y1692989D01*
G02X1347079Y1692686I-303J0D01*
G01X1343379D01*
G02X1343076Y1692989I0J303D01*
G01Y1702995D01*
G37*
G36*
G01X1358824D02*
G02X1359127Y1703298I303J0D01*
G01X1362827D01*
G02X1363130Y1702995I0J-303D01*
G01Y1692989D01*
G02X1362827Y1692686I-303J0D01*
G01X1359127D01*
G02X1358824Y1692989I0J303D01*
G01Y1702995D01*
G37*
G36*
G01X1335202Y1699058D02*
G02X1335505Y1699360I303J-1D01*
G01X1339205D01*
G02X1339508Y1699058I1J-302D01*
G01Y1689052D01*
G02X1339205Y1688750I-303J1D01*
G01X1335505D01*
G02X1335202Y1689052I-1J302D01*
G01Y1699058D01*
G37*
G36*
G01X1350950D02*
G02X1351253Y1699360I303J-1D01*
G01X1354953D01*
G02X1355256Y1699058I1J-302D01*
G01Y1689052D01*
G02X1354953Y1688750I-303J1D01*
G01X1351253D01*
G02X1350950Y1689052I-1J302D01*
G01Y1699058D01*
G37*
G36*
G01X1343076Y1685958D02*
Y1688820D01*
G02X1343378Y1689122I302J0D01*
G01X1347078D01*
G02X1347380Y1688820I0J-302D01*
G01Y1678814D01*
G02X1347078Y1678512I-302J0D01*
G01X1343378D01*
G02X1343076Y1678814I0J302D01*
G01Y1681678D01*
G02X1343107Y1681812I302J1D01*
G01X1344026Y1683687D01*
G03Y1683949I-267J131D01*
G01X1343107Y1685824D01*
G02X1343076Y1685958I271J133D01*
G37*
G36*
G01X1358824Y1685959D02*
Y1688821D01*
G02X1359126Y1689124I302J1D01*
G01X1362826D01*
G02X1363128Y1688821I-1J-303D01*
G01Y1678815D01*
G02X1362826Y1678512I-302J-1D01*
G01X1359126D01*
G02X1358824Y1678815I1J303D01*
G01Y1681679D01*
G02X1358855Y1681813I302J1D01*
G01X1359774Y1683688D01*
G03Y1683950I-267J131D01*
G01X1358855Y1685825D01*
G02X1358824Y1685959I271J133D01*
G37*
G36*
G01X1335202Y1682022D02*
Y1684884D01*
G02X1335504Y1685186I302J0D01*
G01X1339204D01*
G02X1339506Y1684884I0J-302D01*
G01Y1674878D01*
G02X1339204Y1674576I-302J0D01*
G01X1335504D01*
G02X1335202Y1674878I0J302D01*
G01Y1677742D01*
G02X1335233Y1677876I302J1D01*
G01X1336152Y1679751D01*
G03Y1680013I-267J131D01*
G01X1335233Y1681888D01*
G02X1335202Y1682022I271J133D01*
G37*
G36*
G01X1350950D02*
Y1684884D01*
G02X1351252Y1685186I302J0D01*
G01X1354952D01*
G02X1355254Y1684884I0J-302D01*
G01Y1674878D01*
G02X1354952Y1674576I-302J0D01*
G01X1351252D01*
G02X1350950Y1674878I0J302D01*
G01Y1677742D01*
G02X1350981Y1677876I302J1D01*
G01X1351900Y1679751D01*
G03Y1680013I-267J131D01*
G01X1350981Y1681888D01*
G02X1350950Y1682022I271J133D01*
G37*
G36*
G01X1311580Y1731341D02*
G02X1311882Y1731644I302J1D01*
G01X1315582D01*
G02X1315884Y1731341I-1J-303D01*
G01Y1721335D01*
G02X1315582Y1721032I-302J-1D01*
G01X1311882D01*
G02X1311580Y1721335I1J303D01*
G01Y1731341D01*
G37*
G36*
G01X1327328D02*
G02X1327630Y1731644I302J1D01*
G01X1331330D01*
G02X1331632Y1731341I-1J-303D01*
G01Y1721335D01*
G02X1331330Y1721032I-302J-1D01*
G01X1327630D01*
G02X1327328Y1721335I1J303D01*
G01Y1731341D01*
G37*
G36*
G01X1303706Y1727404D02*
G02X1304008Y1727706I302J0D01*
G01X1307708D01*
G02X1308010Y1727404I0J-302D01*
G01Y1717398D01*
G02X1307708Y1717096I-302J0D01*
G01X1304008D01*
G02X1303706Y1717398I0J302D01*
G01Y1727404D01*
G37*
G36*
G01X1319454D02*
G02X1319756Y1727706I302J0D01*
G01X1323456D01*
G02X1323758Y1727404I0J-302D01*
G01Y1717398D01*
G02X1323456Y1717096I-302J0D01*
G01X1319756D01*
G02X1319454Y1717398I0J302D01*
G01Y1727404D01*
G37*
G36*
G01X1311580Y1717168D02*
G02X1311882Y1717470I302J0D01*
G01X1315582D01*
G02X1315884Y1717168I0J-302D01*
G01Y1707162D01*
G02X1315582Y1706860I-302J0D01*
G01X1311882D01*
G02X1311580Y1707162I0J302D01*
G01Y1717168D01*
G37*
G36*
G01X1327328D02*
G02X1327630Y1717470I302J0D01*
G01X1331330D01*
G02X1331632Y1717168I0J-302D01*
G01Y1707162D01*
G02X1331330Y1706860I-302J0D01*
G01X1327630D01*
G02X1327328Y1707162I0J302D01*
G01Y1717168D01*
G37*
G36*
G01X1303706Y1713231D02*
G02X1304008Y1713534I302J1D01*
G01X1307708D01*
G02X1308010Y1713231I-1J-303D01*
G01Y1703225D01*
G02X1307708Y1702922I-302J-1D01*
G01X1304008D01*
G02X1303706Y1703225I1J303D01*
G01Y1713231D01*
G37*
G36*
G01X1319454D02*
G02X1319756Y1713534I302J1D01*
G01X1323456D01*
G02X1323758Y1713231I-1J-303D01*
G01Y1703225D01*
G02X1323456Y1702922I-302J-1D01*
G01X1319756D01*
G02X1319454Y1703225I1J303D01*
G01Y1713231D01*
G37*
G36*
G01X1311580Y1702995D02*
G02X1311883Y1703298I303J0D01*
G01X1315583D01*
G02X1315886Y1702995I0J-303D01*
G01Y1692989D01*
G02X1315583Y1692686I-303J0D01*
G01X1311883D01*
G02X1311580Y1692989I0J303D01*
G01Y1702995D01*
G37*
G36*
G01X1327328D02*
G02X1327631Y1703298I303J0D01*
G01X1331331D01*
G02X1331634Y1702995I0J-303D01*
G01Y1692989D01*
G02X1331331Y1692686I-303J0D01*
G01X1327631D01*
G02X1327328Y1692989I0J303D01*
G01Y1702995D01*
G37*
G36*
G01X1303706Y1699058D02*
G02X1304009Y1699360I303J-1D01*
G01X1307709D01*
G02X1308012Y1699058I1J-302D01*
G01Y1689052D01*
G02X1307709Y1688750I-303J1D01*
G01X1304009D01*
G02X1303706Y1689052I-1J302D01*
G01Y1699058D01*
G37*
G36*
G01X1319454D02*
G02X1319757Y1699360I303J-1D01*
G01X1323457D01*
G02X1323760Y1699058I1J-302D01*
G01Y1689052D01*
G02X1323457Y1688750I-303J1D01*
G01X1319757D01*
G02X1319454Y1689052I-1J302D01*
G01Y1699058D01*
G37*
G36*
G01X1311580Y1685959D02*
Y1688821D01*
G02X1311882Y1689124I302J1D01*
G01X1315582D01*
G02X1315884Y1688821I-1J-303D01*
G01Y1678815D01*
G02X1315582Y1678512I-302J-1D01*
G01X1311882D01*
G02X1311580Y1678815I1J303D01*
G01Y1681679D01*
G02X1311611Y1681813I302J1D01*
G01X1312530Y1683688D01*
G03Y1683950I-267J131D01*
G01X1311611Y1685825D01*
G02X1311580Y1685959I271J133D01*
G37*
G36*
G01X1327328D02*
Y1688821D01*
G02X1327630Y1689124I302J1D01*
G01X1331330D01*
G02X1331632Y1688821I-1J-303D01*
G01Y1678815D01*
G02X1331330Y1678512I-302J-1D01*
G01X1327630D01*
G02X1327328Y1678815I1J303D01*
G01Y1681679D01*
G02X1327359Y1681813I302J1D01*
G01X1328278Y1683688D01*
G03Y1683950I-267J131D01*
G01X1327359Y1685825D01*
G02X1327328Y1685959I271J133D01*
G37*
G36*
G01X1303706Y1682022D02*
Y1684884D01*
G02X1304008Y1685186I302J0D01*
G01X1307708D01*
G02X1308010Y1684884I0J-302D01*
G01Y1674878D01*
G02X1307708Y1674576I-302J0D01*
G01X1304008D01*
G02X1303706Y1674878I0J302D01*
G01Y1677742D01*
G02X1303737Y1677876I302J1D01*
G01X1304656Y1679751D01*
G03Y1680013I-267J131D01*
G01X1303737Y1681888D01*
G02X1303706Y1682022I271J133D01*
G37*
G36*
G01X1319454D02*
Y1684884D01*
G02X1319756Y1685186I302J0D01*
G01X1323456D01*
G02X1323758Y1684884I0J-302D01*
G01Y1674878D01*
G02X1323456Y1674576I-302J0D01*
G01X1319756D01*
G02X1319454Y1674878I0J302D01*
G01Y1677742D01*
G02X1319485Y1677876I302J1D01*
G01X1320404Y1679751D01*
G03Y1680013I-267J131D01*
G01X1319485Y1681888D01*
G02X1319454Y1682022I271J133D01*
G37*
G36*
G01X1276146Y1731341D02*
G02X1276449Y1731644I303J0D01*
G01X1280149D01*
G02X1280452Y1731341I0J-303D01*
G01Y1721335D01*
G02X1280149Y1721032I-303J0D01*
G01X1276449D01*
G02X1276146Y1721335I0J303D01*
G01Y1731341D01*
G37*
G36*
G01X1291894D02*
G02X1292197Y1731644I303J0D01*
G01X1295897D01*
G02X1296200Y1731341I0J-303D01*
G01Y1721335D01*
G02X1295897Y1721032I-303J0D01*
G01X1292197D01*
G02X1291894Y1721335I0J303D01*
G01Y1731341D01*
G37*
G36*
G01X1268272Y1727404D02*
G02X1268575Y1727706I303J-1D01*
G01X1272275D01*
G02X1272578Y1727404I1J-302D01*
G01Y1717398D01*
G02X1272275Y1717096I-303J1D01*
G01X1268575D01*
G02X1268272Y1717398I-1J302D01*
G01Y1727404D01*
G37*
G36*
G01X1284020D02*
G02X1284323Y1727706I303J-1D01*
G01X1288023D01*
G02X1288326Y1727404I1J-302D01*
G01Y1717398D01*
G02X1288023Y1717096I-303J1D01*
G01X1284323D01*
G02X1284020Y1717398I-1J302D01*
G01Y1727404D01*
G37*
G36*
G01X1276146Y1717168D02*
G02X1276449Y1717470I303J-1D01*
G01X1280149D01*
G02X1280452Y1717168I1J-302D01*
G01Y1707162D01*
G02X1280149Y1706860I-303J1D01*
G01X1276449D01*
G02X1276146Y1707162I-1J302D01*
G01Y1717168D01*
G37*
G36*
G01X1291894D02*
G02X1292197Y1717470I303J-1D01*
G01X1295897D01*
G02X1296200Y1717168I1J-302D01*
G01Y1707162D01*
G02X1295897Y1706860I-303J1D01*
G01X1292197D01*
G02X1291894Y1707162I-1J302D01*
G01Y1717168D01*
G37*
G36*
G01X1268272Y1713231D02*
G02X1268575Y1713534I303J0D01*
G01X1272275D01*
G02X1272578Y1713231I0J-303D01*
G01Y1703225D01*
G02X1272275Y1702922I-303J0D01*
G01X1268575D01*
G02X1268272Y1703225I0J303D01*
G01Y1713231D01*
G37*
G36*
G01X1284020D02*
G02X1284323Y1713534I303J0D01*
G01X1288023D01*
G02X1288326Y1713231I0J-303D01*
G01Y1703225D01*
G02X1288023Y1702922I-303J0D01*
G01X1284323D01*
G02X1284020Y1703225I0J303D01*
G01Y1713231D01*
G37*
G36*
G01X1276146Y1702995D02*
G02X1276449Y1703298I303J0D01*
G01X1280149D01*
G02X1280452Y1702995I0J-303D01*
G01Y1692989D01*
G02X1280149Y1692686I-303J0D01*
G01X1276449D01*
G02X1276146Y1692989I0J303D01*
G01Y1702995D01*
G37*
G36*
G01X1291894D02*
G02X1292197Y1703298I303J0D01*
G01X1295897D01*
G02X1296200Y1702995I0J-303D01*
G01Y1692989D01*
G02X1295897Y1692686I-303J0D01*
G01X1292197D01*
G02X1291894Y1692989I0J303D01*
G01Y1702995D01*
G37*
G36*
G01X1268272Y1699058D02*
G02X1268575Y1699360I303J-1D01*
G01X1272275D01*
G02X1272578Y1699058I1J-302D01*
G01Y1689052D01*
G02X1272275Y1688750I-303J1D01*
G01X1268575D01*
G02X1268272Y1689052I-1J302D01*
G01Y1699058D01*
G37*
G36*
G01X1284020D02*
G02X1284323Y1699360I303J-1D01*
G01X1288023D01*
G02X1288326Y1699058I1J-302D01*
G01Y1689052D01*
G02X1288023Y1688750I-303J1D01*
G01X1284323D01*
G02X1284020Y1689052I-1J302D01*
G01Y1699058D01*
G37*
G36*
G01X1276146Y1685959D02*
Y1688821D01*
G02X1276449Y1689124I303J0D01*
G01X1280149D01*
G02X1280452Y1688821I0J-303D01*
G01Y1678815D01*
G02X1280149Y1678512I-303J0D01*
G01X1276449D01*
G02X1276146Y1678815I0J303D01*
G01Y1681679D01*
G02X1276178Y1681813I303J-1D01*
G01X1277097Y1683688D01*
G03Y1683950I-267J131D01*
G01X1276178Y1685825D01*
G02X1276146Y1685959I270J135D01*
G37*
G36*
G01X1291894D02*
Y1688821D01*
G02X1292197Y1689124I303J0D01*
G01X1295897D01*
G02X1296200Y1688821I0J-303D01*
G01Y1678815D01*
G02X1295897Y1678512I-303J0D01*
G01X1292197D01*
G02X1291894Y1678815I0J303D01*
G01Y1681679D01*
G02X1291926Y1681813I303J-1D01*
G01X1292845Y1683688D01*
G03Y1683950I-267J131D01*
G01X1291926Y1685825D01*
G02X1291894Y1685959I270J135D01*
G37*
G36*
G01X1268272Y1682022D02*
Y1684884D01*
G02X1268575Y1685186I303J-1D01*
G01X1272275D01*
G02X1272578Y1684884I1J-302D01*
G01Y1674878D01*
G02X1272275Y1674576I-303J1D01*
G01X1268575D01*
G02X1268272Y1674878I-1J302D01*
G01Y1677742D01*
G02X1268304Y1677876I303J-1D01*
G01X1269223Y1679751D01*
G03Y1680013I-267J131D01*
G01X1268304Y1681888D01*
G02X1268272Y1682022I270J135D01*
G37*
G36*
G01X1284020D02*
Y1684884D01*
G02X1284323Y1685186I303J-1D01*
G01X1288023D01*
G02X1288326Y1684884I1J-302D01*
G01Y1674878D01*
G02X1288023Y1674576I-303J1D01*
G01X1284323D01*
G02X1284020Y1674878I-1J302D01*
G01Y1677742D01*
G02X1284052Y1677876I303J-1D01*
G01X1284971Y1679751D01*
G03Y1680013I-267J131D01*
G01X1284052Y1681888D01*
G02X1284020Y1682022I270J135D01*
G37*
G36*
G01X1244650Y1731341D02*
G02X1244953Y1731644I303J0D01*
G01X1248653D01*
G02X1248956Y1731341I0J-303D01*
G01Y1721335D01*
G02X1248653Y1721032I-303J0D01*
G01X1244953D01*
G02X1244650Y1721335I0J303D01*
G01Y1731341D01*
G37*
G36*
G01X1260398D02*
G02X1260701Y1731644I303J0D01*
G01X1264401D01*
G02X1264704Y1731341I0J-303D01*
G01Y1721335D01*
G02X1264401Y1721032I-303J0D01*
G01X1260701D01*
G02X1260398Y1721335I0J303D01*
G01Y1731341D01*
G37*
G36*
G01X1236776Y1727404D02*
G02X1237079Y1727706I303J-1D01*
G01X1240779D01*
G02X1241082Y1727404I1J-302D01*
G01Y1717398D01*
G02X1240779Y1717096I-303J1D01*
G01X1237079D01*
G02X1236776Y1717398I-1J302D01*
G01Y1727404D01*
G37*
G36*
G01X1252524D02*
G02X1252827Y1727706I303J-1D01*
G01X1256527D01*
G02X1256830Y1727404I1J-302D01*
G01Y1717398D01*
G02X1256527Y1717096I-303J1D01*
G01X1252827D01*
G02X1252524Y1717398I-1J302D01*
G01Y1727404D01*
G37*
G36*
G01X1244650Y1717168D02*
G02X1244953Y1717470I303J-1D01*
G01X1248653D01*
G02X1248956Y1717168I1J-302D01*
G01Y1707162D01*
G02X1248653Y1706860I-303J1D01*
G01X1244953D01*
G02X1244650Y1707162I-1J302D01*
G01Y1717168D01*
G37*
G36*
G01X1260398D02*
G02X1260701Y1717470I303J-1D01*
G01X1264401D01*
G02X1264704Y1717168I1J-302D01*
G01Y1707162D01*
G02X1264401Y1706860I-303J1D01*
G01X1260701D01*
G02X1260398Y1707162I-1J302D01*
G01Y1717168D01*
G37*
G36*
G01X1236776Y1713231D02*
G02X1237079Y1713534I303J0D01*
G01X1240779D01*
G02X1241082Y1713231I0J-303D01*
G01Y1703225D01*
G02X1240779Y1702922I-303J0D01*
G01X1237079D01*
G02X1236776Y1703225I0J303D01*
G01Y1713231D01*
G37*
G36*
G01X1252524D02*
G02X1252827Y1713534I303J0D01*
G01X1256527D01*
G02X1256830Y1713231I0J-303D01*
G01Y1703225D01*
G02X1256527Y1702922I-303J0D01*
G01X1252827D01*
G02X1252524Y1703225I0J303D01*
G01Y1713231D01*
G37*
G36*
G01X1244650Y1702995D02*
G02X1244953Y1703298I303J0D01*
G01X1248653D01*
G02X1248956Y1702995I0J-303D01*
G01Y1692989D01*
G02X1248653Y1692686I-303J0D01*
G01X1244953D01*
G02X1244650Y1692989I0J303D01*
G01Y1702995D01*
G37*
G36*
G01X1260398D02*
G02X1260701Y1703298I303J0D01*
G01X1264401D01*
G02X1264704Y1702995I0J-303D01*
G01Y1692989D01*
G02X1264401Y1692686I-303J0D01*
G01X1260701D01*
G02X1260398Y1692989I0J303D01*
G01Y1702995D01*
G37*
G36*
G01X1236776Y1699058D02*
G02X1237079Y1699360I303J-1D01*
G01X1240779D01*
G02X1241082Y1699058I1J-302D01*
G01Y1689052D01*
G02X1240779Y1688750I-303J1D01*
G01X1237079D01*
G02X1236776Y1689052I-1J302D01*
G01Y1699058D01*
G37*
G36*
G01X1252524D02*
G02X1252827Y1699360I303J-1D01*
G01X1256527D01*
G02X1256830Y1699058I1J-302D01*
G01Y1689052D01*
G02X1256527Y1688750I-303J1D01*
G01X1252827D01*
G02X1252524Y1689052I-1J302D01*
G01Y1699058D01*
G37*
G36*
G01X1244650Y1685959D02*
Y1688821D01*
G02X1244953Y1689124I303J0D01*
G01X1248653D01*
G02X1248956Y1688821I0J-303D01*
G01Y1678815D01*
G02X1248653Y1678512I-303J0D01*
G01X1244953D01*
G02X1244650Y1678815I0J303D01*
G01Y1681679D01*
G02X1244682Y1681813I303J-1D01*
G01X1245601Y1683688D01*
G03Y1683950I-267J131D01*
G01X1244682Y1685825D01*
G02X1244650Y1685959I270J135D01*
G37*
G36*
G01X1260398D02*
Y1688821D01*
G02X1260701Y1689124I303J0D01*
G01X1264401D01*
G02X1264704Y1688821I0J-303D01*
G01Y1678815D01*
G02X1264401Y1678512I-303J0D01*
G01X1260701D01*
G02X1260398Y1678815I0J303D01*
G01Y1681679D01*
G02X1260430Y1681813I303J-1D01*
G01X1261349Y1683688D01*
G03Y1683950I-267J131D01*
G01X1260430Y1685825D01*
G02X1260398Y1685959I270J135D01*
G37*
G36*
G01X1236776Y1682022D02*
Y1684884D01*
G02X1237079Y1685186I303J-1D01*
G01X1240779D01*
G02X1241082Y1684884I1J-302D01*
G01Y1674878D01*
G02X1240779Y1674576I-303J1D01*
G01X1237079D01*
G02X1236776Y1674878I-1J302D01*
G01Y1677742D01*
G02X1236808Y1677876I303J-1D01*
G01X1237727Y1679751D01*
G03Y1680013I-267J131D01*
G01X1236808Y1681888D01*
G02X1236776Y1682022I270J135D01*
G37*
G36*
G01X1252524D02*
Y1684884D01*
G02X1252827Y1685186I303J-1D01*
G01X1256527D01*
G02X1256830Y1684884I1J-302D01*
G01Y1674878D01*
G02X1256527Y1674576I-303J1D01*
G01X1252827D01*
G02X1252524Y1674878I-1J302D01*
G01Y1677742D01*
G02X1252556Y1677876I303J-1D01*
G01X1253475Y1679751D01*
G03Y1680013I-267J131D01*
G01X1252556Y1681888D01*
G02X1252524Y1682022I270J135D01*
G37*
G36*
G01X599374Y1731340D02*
G02X599677Y1731642I303J-1D01*
G01X603377D01*
G02X603680Y1731340I1J-302D01*
G01Y1721334D01*
G02X603377Y1721032I-303J1D01*
G01X599677D01*
G02X599374Y1721334I-1J302D01*
G01Y1731340D01*
G37*
G36*
G01X615122D02*
G02X615425Y1731642I303J-1D01*
G01X619125D01*
G02X619428Y1731340I1J-302D01*
G01Y1721334D01*
G02X619125Y1721032I-303J1D01*
G01X615425D01*
G02X615122Y1721334I-1J302D01*
G01Y1731340D01*
G37*
G36*
G01X591500Y1727403D02*
G02X591803Y1727706I303J0D01*
G01X595503D01*
G02X595806Y1727403I0J-303D01*
G01Y1717397D01*
G02X595503Y1717094I-303J0D01*
G01X591803D01*
G02X591500Y1717397I0J303D01*
G01Y1727403D01*
G37*
G36*
G01X607248D02*
G02X607551Y1727706I303J0D01*
G01X611251D01*
G02X611554Y1727403I0J-303D01*
G01Y1717397D01*
G02X611251Y1717094I-303J0D01*
G01X607551D01*
G02X607248Y1717397I0J303D01*
G01Y1727403D01*
G37*
G36*
G01X599374Y1717167D02*
G02X599677Y1717470I303J0D01*
G01X603377D01*
G02X603680Y1717167I0J-303D01*
G01Y1707161D01*
G02X603377Y1706858I-303J0D01*
G01X599677D01*
G02X599374Y1707161I0J303D01*
G01Y1717167D01*
G37*
G36*
G01X615122D02*
G02X615425Y1717470I303J0D01*
G01X619125D01*
G02X619428Y1717167I0J-303D01*
G01Y1707161D01*
G02X619125Y1706858I-303J0D01*
G01X615425D01*
G02X615122Y1707161I0J303D01*
G01Y1717167D01*
G37*
G36*
G01X591500Y1713230D02*
G02X591803Y1713532I303J-1D01*
G01X595503D01*
G02X595806Y1713230I1J-302D01*
G01Y1703224D01*
G02X595503Y1702922I-303J1D01*
G01X591803D01*
G02X591500Y1703224I-1J302D01*
G01Y1713230D01*
G37*
G36*
G01X607248D02*
G02X607551Y1713532I303J-1D01*
G01X611251D01*
G02X611554Y1713230I1J-302D01*
G01Y1703224D01*
G02X611251Y1702922I-303J1D01*
G01X607551D01*
G02X607248Y1703224I-1J302D01*
G01Y1713230D01*
G37*
G36*
G01X599376Y1702994D02*
G02X599678Y1703296I302J0D01*
G01X603378D01*
G02X603680Y1702994I0J-302D01*
G01Y1692988D01*
G02X603378Y1692686I-302J0D01*
G01X599678D01*
G02X599376Y1692988I0J302D01*
G01Y1702994D01*
G37*
G36*
G01X615124D02*
G02X615426Y1703296I302J0D01*
G01X619126D01*
G02X619428Y1702994I0J-302D01*
G01Y1692988D01*
G02X619126Y1692686I-302J0D01*
G01X615426D01*
G02X615124Y1692988I0J302D01*
G01Y1702994D01*
G37*
G36*
G01X591502Y1699057D02*
G02X591804Y1699360I302J1D01*
G01X595504D01*
G02X595806Y1699057I-1J-303D01*
G01Y1689051D01*
G02X595504Y1688748I-302J-1D01*
G01X591804D01*
G02X591502Y1689051I1J303D01*
G01Y1699057D01*
G37*
G36*
G01X607250D02*
G02X607552Y1699360I302J1D01*
G01X611252D01*
G02X611554Y1699057I-1J-303D01*
G01Y1689051D01*
G02X611252Y1688748I-302J-1D01*
G01X607552D01*
G02X607250Y1689051I1J303D01*
G01Y1699057D01*
G37*
G36*
G01X599376Y1685958D02*
Y1688820D01*
G02X599678Y1689122I302J0D01*
G01X603378D01*
G02X603680Y1688820I0J-302D01*
G01Y1678814D01*
G02X603378Y1678512I-302J0D01*
G01X599678D01*
G02X599376Y1678814I0J302D01*
G01Y1681678D01*
G02X599407Y1681812I302J1D01*
G01X600326Y1683687D01*
G03Y1683949I-267J131D01*
G01X599407Y1685824D01*
G02X599376Y1685958I271J133D01*
G37*
G36*
G01X615124D02*
Y1688820D01*
G02X615426Y1689122I302J0D01*
G01X619126D01*
G02X619428Y1688820I0J-302D01*
G01Y1678814D01*
G02X619126Y1678512I-302J0D01*
G01X615426D01*
G02X615124Y1678814I0J302D01*
G01Y1681678D01*
G02X615155Y1681812I302J1D01*
G01X616074Y1683687D01*
G03Y1683949I-267J131D01*
G01X615155Y1685824D01*
G02X615124Y1685958I271J133D01*
G37*
G36*
G01X591502Y1682022D02*
Y1684884D01*
G02X591804Y1685186I302J0D01*
G01X595504D01*
G02X595806Y1684884I0J-302D01*
G01Y1674878D01*
G02X595504Y1674576I-302J0D01*
G01X591804D01*
G02X591502Y1674878I0J302D01*
G01Y1677742D01*
G02X591533Y1677876I302J1D01*
G01X592452Y1679751D01*
G03Y1680013I-267J131D01*
G01X591533Y1681888D01*
G02X591502Y1682022I271J133D01*
G37*
G36*
G01X607250D02*
Y1684884D01*
G02X607552Y1685186I302J0D01*
G01X611252D01*
G02X611554Y1684884I0J-302D01*
G01Y1674878D01*
G02X611252Y1674576I-302J0D01*
G01X607552D01*
G02X607250Y1674878I0J302D01*
G01Y1677742D01*
G02X607281Y1677876I302J1D01*
G01X608200Y1679751D01*
G03Y1680013I-267J131D01*
G01X607281Y1681888D01*
G02X607250Y1682022I271J133D01*
G37*
G36*
G01X567878Y1731340D02*
G02X568181Y1731642I303J-1D01*
G01X571881D01*
G02X572184Y1731340I1J-302D01*
G01Y1721334D01*
G02X571881Y1721032I-303J1D01*
G01X568181D01*
G02X567878Y1721334I-1J302D01*
G01Y1731340D01*
G37*
G36*
G01X583626D02*
G02X583929Y1731642I303J-1D01*
G01X587629D01*
G02X587932Y1731340I1J-302D01*
G01Y1721334D01*
G02X587629Y1721032I-303J1D01*
G01X583929D01*
G02X583626Y1721334I-1J302D01*
G01Y1731340D01*
G37*
G36*
G01X560004Y1727403D02*
G02X560307Y1727706I303J0D01*
G01X564007D01*
G02X564310Y1727403I0J-303D01*
G01Y1717397D01*
G02X564007Y1717094I-303J0D01*
G01X560307D01*
G02X560004Y1717397I0J303D01*
G01Y1727403D01*
G37*
G36*
G01X575752D02*
G02X576055Y1727706I303J0D01*
G01X579755D01*
G02X580058Y1727403I0J-303D01*
G01Y1717397D01*
G02X579755Y1717094I-303J0D01*
G01X576055D01*
G02X575752Y1717397I0J303D01*
G01Y1727403D01*
G37*
G36*
G01X567878Y1717167D02*
G02X568181Y1717470I303J0D01*
G01X571881D01*
G02X572184Y1717167I0J-303D01*
G01Y1707161D01*
G02X571881Y1706858I-303J0D01*
G01X568181D01*
G02X567878Y1707161I0J303D01*
G01Y1717167D01*
G37*
G36*
G01X583626D02*
G02X583929Y1717470I303J0D01*
G01X587629D01*
G02X587932Y1717167I0J-303D01*
G01Y1707161D01*
G02X587629Y1706858I-303J0D01*
G01X583929D01*
G02X583626Y1707161I0J303D01*
G01Y1717167D01*
G37*
G36*
G01X560004Y1713230D02*
G02X560307Y1713532I303J-1D01*
G01X564007D01*
G02X564310Y1713230I1J-302D01*
G01Y1703224D01*
G02X564007Y1702922I-303J1D01*
G01X560307D01*
G02X560004Y1703224I-1J302D01*
G01Y1713230D01*
G37*
G36*
G01X575752D02*
G02X576055Y1713532I303J-1D01*
G01X579755D01*
G02X580058Y1713230I1J-302D01*
G01Y1703224D01*
G02X579755Y1702922I-303J1D01*
G01X576055D01*
G02X575752Y1703224I-1J302D01*
G01Y1713230D01*
G37*
G36*
G01X567880Y1702994D02*
G02X568182Y1703296I302J0D01*
G01X571882D01*
G02X572184Y1702994I0J-302D01*
G01Y1692988D01*
G02X571882Y1692686I-302J0D01*
G01X568182D01*
G02X567880Y1692988I0J302D01*
G01Y1702994D01*
G37*
G36*
G01X583628D02*
G02X583930Y1703296I302J0D01*
G01X587630D01*
G02X587932Y1702994I0J-302D01*
G01Y1692988D01*
G02X587630Y1692686I-302J0D01*
G01X583930D01*
G02X583628Y1692988I0J302D01*
G01Y1702994D01*
G37*
G36*
G01X560006Y1699057D02*
G02X560308Y1699360I302J1D01*
G01X564008D01*
G02X564310Y1699057I-1J-303D01*
G01Y1689051D01*
G02X564008Y1688748I-302J-1D01*
G01X560308D01*
G02X560006Y1689051I1J303D01*
G01Y1699057D01*
G37*
G36*
G01X575754D02*
G02X576056Y1699360I302J1D01*
G01X579756D01*
G02X580058Y1699057I-1J-303D01*
G01Y1689051D01*
G02X579756Y1688748I-302J-1D01*
G01X576056D01*
G02X575754Y1689051I1J303D01*
G01Y1699057D01*
G37*
G36*
G01X567880Y1685958D02*
Y1688820D01*
G02X568182Y1689122I302J0D01*
G01X571882D01*
G02X572184Y1688820I0J-302D01*
G01Y1678814D01*
G02X571882Y1678512I-302J0D01*
G01X568182D01*
G02X567880Y1678814I0J302D01*
G01Y1681678D01*
G02X567911Y1681812I302J1D01*
G01X568830Y1683687D01*
G03Y1683949I-267J131D01*
G01X567911Y1685824D01*
G02X567880Y1685958I271J133D01*
G37*
G36*
G01X583628D02*
Y1688820D01*
G02X583930Y1689122I302J0D01*
G01X587630D01*
G02X587932Y1688820I0J-302D01*
G01Y1678814D01*
G02X587630Y1678512I-302J0D01*
G01X583930D01*
G02X583628Y1678814I0J302D01*
G01Y1681678D01*
G02X583659Y1681812I302J1D01*
G01X584578Y1683687D01*
G03Y1683949I-267J131D01*
G01X583659Y1685824D01*
G02X583628Y1685958I271J133D01*
G37*
G36*
G01X560006Y1682022D02*
Y1684884D01*
G02X560308Y1685186I302J0D01*
G01X564008D01*
G02X564310Y1684884I0J-302D01*
G01Y1674878D01*
G02X564008Y1674576I-302J0D01*
G01X560308D01*
G02X560006Y1674878I0J302D01*
G01Y1677742D01*
G02X560037Y1677876I302J1D01*
G01X560956Y1679751D01*
G03Y1680013I-267J131D01*
G01X560037Y1681888D01*
G02X560006Y1682022I271J133D01*
G37*
G36*
G01X575754D02*
Y1684884D01*
G02X576056Y1685186I302J0D01*
G01X579756D01*
G02X580058Y1684884I0J-302D01*
G01Y1674878D01*
G02X579756Y1674576I-302J0D01*
G01X576056D01*
G02X575754Y1674878I0J302D01*
G01Y1677742D01*
G02X575785Y1677876I302J1D01*
G01X576704Y1679751D01*
G03Y1680013I-267J131D01*
G01X575785Y1681888D01*
G02X575754Y1682022I271J133D01*
G37*
G36*
G01X532446Y1731340D02*
G02X532748Y1731642I302J0D01*
G01X536448D01*
G02X536750Y1731340I0J-302D01*
G01Y1721334D01*
G02X536448Y1721032I-302J0D01*
G01X532748D01*
G02X532446Y1721334I0J302D01*
G01Y1731340D01*
G37*
G36*
G01X548194D02*
G02X548496Y1731642I302J0D01*
G01X552196D01*
G02X552498Y1731340I0J-302D01*
G01Y1721334D01*
G02X552196Y1721032I-302J0D01*
G01X548496D01*
G02X548194Y1721334I0J302D01*
G01Y1731340D01*
G37*
G36*
G01X524572Y1727403D02*
G02X524874Y1727706I302J1D01*
G01X528574D01*
G02X528876Y1727403I-1J-303D01*
G01Y1717397D01*
G02X528574Y1717094I-302J-1D01*
G01X524874D01*
G02X524572Y1717397I1J303D01*
G01Y1727403D01*
G37*
G36*
G01X540320D02*
G02X540622Y1727706I302J1D01*
G01X544322D01*
G02X544624Y1727403I-1J-303D01*
G01Y1717397D01*
G02X544322Y1717094I-302J-1D01*
G01X540622D01*
G02X540320Y1717397I1J303D01*
G01Y1727403D01*
G37*
G36*
G01X532446Y1717167D02*
G02X532748Y1717470I302J1D01*
G01X536448D01*
G02X536750Y1717167I-1J-303D01*
G01Y1707161D01*
G02X536448Y1706858I-302J-1D01*
G01X532748D01*
G02X532446Y1707161I1J303D01*
G01Y1717167D01*
G37*
G36*
G01X548194D02*
G02X548496Y1717470I302J1D01*
G01X552196D01*
G02X552498Y1717167I-1J-303D01*
G01Y1707161D01*
G02X552196Y1706858I-302J-1D01*
G01X548496D01*
G02X548194Y1707161I1J303D01*
G01Y1717167D01*
G37*
G36*
G01X524572Y1713230D02*
G02X524874Y1713532I302J0D01*
G01X528574D01*
G02X528876Y1713230I0J-302D01*
G01Y1703224D01*
G02X528574Y1702922I-302J0D01*
G01X524874D01*
G02X524572Y1703224I0J302D01*
G01Y1713230D01*
G37*
G36*
G01X540320D02*
G02X540622Y1713532I302J0D01*
G01X544322D01*
G02X544624Y1713230I0J-302D01*
G01Y1703224D01*
G02X544322Y1702922I-302J0D01*
G01X540622D01*
G02X540320Y1703224I0J302D01*
G01Y1713230D01*
G37*
G36*
G01X532446Y1702994D02*
G02X532748Y1703296I302J0D01*
G01X536448D01*
G02X536750Y1702994I0J-302D01*
G01Y1692988D01*
G02X536448Y1692686I-302J0D01*
G01X532748D01*
G02X532446Y1692988I0J302D01*
G01Y1702994D01*
G37*
G36*
G01X548194D02*
G02X548496Y1703296I302J0D01*
G01X552196D01*
G02X552498Y1702994I0J-302D01*
G01Y1692988D01*
G02X552196Y1692686I-302J0D01*
G01X548496D01*
G02X548194Y1692988I0J302D01*
G01Y1702994D01*
G37*
G36*
G01X524572Y1699057D02*
G02X524874Y1699360I302J1D01*
G01X528574D01*
G02X528876Y1699057I-1J-303D01*
G01Y1689051D01*
G02X528574Y1688748I-302J-1D01*
G01X524874D01*
G02X524572Y1689051I1J303D01*
G01Y1699057D01*
G37*
G36*
G01X540320D02*
G02X540622Y1699360I302J1D01*
G01X544322D01*
G02X544624Y1699057I-1J-303D01*
G01Y1689051D01*
G02X544322Y1688748I-302J-1D01*
G01X540622D01*
G02X540320Y1689051I1J303D01*
G01Y1699057D01*
G37*
G36*
G01X532446Y1685958D02*
Y1688820D01*
G02X532748Y1689122I302J0D01*
G01X536448D01*
G02X536750Y1688820I0J-302D01*
G01Y1678814D01*
G02X536448Y1678512I-302J0D01*
G01X532748D01*
G02X532446Y1678814I0J302D01*
G01Y1681678D01*
G02X532477Y1681812I302J1D01*
G01X533396Y1683687D01*
G03Y1683949I-267J131D01*
G01X532477Y1685824D01*
G02X532446Y1685958I271J133D01*
G37*
G36*
G01X548194D02*
Y1688820D01*
G02X548496Y1689122I302J0D01*
G01X552196D01*
G02X552498Y1688820I0J-302D01*
G01Y1678814D01*
G02X552196Y1678512I-302J0D01*
G01X548496D01*
G02X548194Y1678814I0J302D01*
G01Y1681678D01*
G02X548225Y1681812I302J1D01*
G01X549144Y1683687D01*
G03Y1683949I-267J131D01*
G01X548225Y1685824D01*
G02X548194Y1685958I271J133D01*
G37*
G36*
G01X524572Y1682022D02*
Y1684884D01*
G02X524874Y1685186I302J0D01*
G01X528574D01*
G02X528876Y1684884I0J-302D01*
G01Y1674878D01*
G02X528574Y1674576I-302J0D01*
G01X524874D01*
G02X524572Y1674878I0J302D01*
G01Y1677742D01*
G02X524603Y1677876I302J1D01*
G01X525522Y1679751D01*
G03Y1680013I-267J131D01*
G01X524603Y1681888D01*
G02X524572Y1682022I271J133D01*
G37*
G36*
G01X540320D02*
Y1684884D01*
G02X540622Y1685186I302J0D01*
G01X544322D01*
G02X544624Y1684884I0J-302D01*
G01Y1674878D01*
G02X544322Y1674576I-302J0D01*
G01X540622D01*
G02X540320Y1674878I0J302D01*
G01Y1677742D01*
G02X540351Y1677876I302J1D01*
G01X541270Y1679751D01*
G03Y1680013I-267J131D01*
G01X540351Y1681888D01*
G02X540320Y1682022I271J133D01*
G37*
G36*
G01X500950Y1731340D02*
G02X501252Y1731642I302J0D01*
G01X504952D01*
G02X505254Y1731340I0J-302D01*
G01Y1721334D01*
G02X504952Y1721032I-302J0D01*
G01X501252D01*
G02X500950Y1721334I0J302D01*
G01Y1731340D01*
G37*
G36*
G01X516698D02*
G02X517000Y1731642I302J0D01*
G01X520700D01*
G02X521002Y1731340I0J-302D01*
G01Y1721334D01*
G02X520700Y1721032I-302J0D01*
G01X517000D01*
G02X516698Y1721334I0J302D01*
G01Y1731340D01*
G37*
G36*
G01X493076Y1727403D02*
G02X493378Y1727706I302J1D01*
G01X497078D01*
G02X497380Y1727403I-1J-303D01*
G01Y1717397D01*
G02X497078Y1717094I-302J-1D01*
G01X493378D01*
G02X493076Y1717397I1J303D01*
G01Y1727403D01*
G37*
G36*
G01X508824D02*
G02X509126Y1727706I302J1D01*
G01X512826D01*
G02X513128Y1727403I-1J-303D01*
G01Y1717397D01*
G02X512826Y1717094I-302J-1D01*
G01X509126D01*
G02X508824Y1717397I1J303D01*
G01Y1727403D01*
G37*
G36*
G01X500950Y1717167D02*
G02X501252Y1717470I302J1D01*
G01X504952D01*
G02X505254Y1717167I-1J-303D01*
G01Y1707161D01*
G02X504952Y1706858I-302J-1D01*
G01X501252D01*
G02X500950Y1707161I1J303D01*
G01Y1717167D01*
G37*
G36*
G01X516698D02*
G02X517000Y1717470I302J1D01*
G01X520700D01*
G02X521002Y1717167I-1J-303D01*
G01Y1707161D01*
G02X520700Y1706858I-302J-1D01*
G01X517000D01*
G02X516698Y1707161I1J303D01*
G01Y1717167D01*
G37*
G36*
G01X493076Y1713230D02*
G02X493378Y1713532I302J0D01*
G01X497078D01*
G02X497380Y1713230I0J-302D01*
G01Y1703224D01*
G02X497078Y1702922I-302J0D01*
G01X493378D01*
G02X493076Y1703224I0J302D01*
G01Y1713230D01*
G37*
G36*
G01X508824D02*
G02X509126Y1713532I302J0D01*
G01X512826D01*
G02X513128Y1713230I0J-302D01*
G01Y1703224D01*
G02X512826Y1702922I-302J0D01*
G01X509126D01*
G02X508824Y1703224I0J302D01*
G01Y1713230D01*
G37*
G36*
G01X500950Y1702994D02*
G02X501252Y1703296I302J0D01*
G01X504952D01*
G02X505254Y1702994I0J-302D01*
G01Y1692988D01*
G02X504952Y1692686I-302J0D01*
G01X501252D01*
G02X500950Y1692988I0J302D01*
G01Y1702994D01*
G37*
G36*
G01X516698D02*
G02X517000Y1703296I302J0D01*
G01X520700D01*
G02X521002Y1702994I0J-302D01*
G01Y1692988D01*
G02X520700Y1692686I-302J0D01*
G01X517000D01*
G02X516698Y1692988I0J302D01*
G01Y1702994D01*
G37*
G36*
G01X493076Y1699057D02*
G02X493378Y1699360I302J1D01*
G01X497078D01*
G02X497380Y1699057I-1J-303D01*
G01Y1689051D01*
G02X497078Y1688748I-302J-1D01*
G01X493378D01*
G02X493076Y1689051I1J303D01*
G01Y1699057D01*
G37*
G36*
G01X508824D02*
G02X509126Y1699360I302J1D01*
G01X512826D01*
G02X513128Y1699057I-1J-303D01*
G01Y1689051D01*
G02X512826Y1688748I-302J-1D01*
G01X509126D01*
G02X508824Y1689051I1J303D01*
G01Y1699057D01*
G37*
G36*
G01X500950Y1685958D02*
Y1688820D01*
G02X501252Y1689122I302J0D01*
G01X504952D01*
G02X505254Y1688820I0J-302D01*
G01Y1678814D01*
G02X504952Y1678512I-302J0D01*
G01X501252D01*
G02X500950Y1678814I0J302D01*
G01Y1681678D01*
G02X500981Y1681812I302J1D01*
G01X501900Y1683687D01*
G03Y1683949I-267J131D01*
G01X500981Y1685824D01*
G02X500950Y1685958I271J133D01*
G37*
G36*
G01X516698D02*
Y1688820D01*
G02X517000Y1689122I302J0D01*
G01X520700D01*
G02X521002Y1688820I0J-302D01*
G01Y1678814D01*
G02X520700Y1678512I-302J0D01*
G01X517000D01*
G02X516698Y1678814I0J302D01*
G01Y1681678D01*
G02X516729Y1681812I302J1D01*
G01X517648Y1683687D01*
G03Y1683949I-267J131D01*
G01X516729Y1685824D01*
G02X516698Y1685958I271J133D01*
G37*
G36*
G01X493076Y1682022D02*
Y1684884D01*
G02X493378Y1685186I302J0D01*
G01X497078D01*
G02X497380Y1684884I0J-302D01*
G01Y1674878D01*
G02X497078Y1674576I-302J0D01*
G01X493378D01*
G02X493076Y1674878I0J302D01*
G01Y1677742D01*
G02X493107Y1677876I302J1D01*
G01X494026Y1679751D01*
G03Y1680013I-267J131D01*
G01X493107Y1681888D01*
G02X493076Y1682022I271J133D01*
G37*
G36*
G01X508824D02*
Y1684884D01*
G02X509126Y1685186I302J0D01*
G01X512826D01*
G02X513128Y1684884I0J-302D01*
G01Y1674878D01*
G02X512826Y1674576I-302J0D01*
G01X509126D01*
G02X508824Y1674878I0J302D01*
G01Y1677742D01*
G02X508855Y1677876I302J1D01*
G01X509774Y1679751D01*
G03Y1680013I-267J131D01*
G01X508855Y1681888D01*
G02X508824Y1682022I271J133D01*
G37*
G36*
G01X335202Y1731341D02*
G02X335504Y1731644I302J1D01*
G01X339204D01*
G02X339506Y1731341I-1J-303D01*
G01Y1721335D01*
G02X339204Y1721032I-302J-1D01*
G01X335504D01*
G02X335202Y1721335I1J303D01*
G01Y1731341D01*
G37*
G36*
G01X350950D02*
G02X351252Y1731644I302J1D01*
G01X354952D01*
G02X355254Y1731341I-1J-303D01*
G01Y1721335D01*
G02X354952Y1721032I-302J-1D01*
G01X351252D01*
G02X350950Y1721335I1J303D01*
G01Y1731341D01*
G37*
G36*
G01X327328Y1727404D02*
G02X327630Y1727706I302J0D01*
G01X331330D01*
G02X331632Y1727404I0J-302D01*
G01Y1717398D01*
G02X331330Y1717096I-302J0D01*
G01X327630D01*
G02X327328Y1717398I0J302D01*
G01Y1727404D01*
G37*
G36*
G01X343076D02*
G02X343378Y1727706I302J0D01*
G01X347078D01*
G02X347380Y1727404I0J-302D01*
G01Y1717398D01*
G02X347078Y1717096I-302J0D01*
G01X343378D01*
G02X343076Y1717398I0J302D01*
G01Y1727404D01*
G37*
G36*
G01X335202Y1717168D02*
G02X335504Y1717470I302J0D01*
G01X339204D01*
G02X339506Y1717168I0J-302D01*
G01Y1707162D01*
G02X339204Y1706860I-302J0D01*
G01X335504D01*
G02X335202Y1707162I0J302D01*
G01Y1717168D01*
G37*
G36*
G01X350950D02*
G02X351252Y1717470I302J0D01*
G01X354952D01*
G02X355254Y1717168I0J-302D01*
G01Y1707162D01*
G02X354952Y1706860I-302J0D01*
G01X351252D01*
G02X350950Y1707162I0J302D01*
G01Y1717168D01*
G37*
G36*
G01X327328Y1713231D02*
G02X327630Y1713534I302J1D01*
G01X331330D01*
G02X331632Y1713231I-1J-303D01*
G01Y1703225D01*
G02X331330Y1702922I-302J-1D01*
G01X327630D01*
G02X327328Y1703225I1J303D01*
G01Y1713231D01*
G37*
G36*
G01X343076D02*
G02X343378Y1713534I302J1D01*
G01X347078D01*
G02X347380Y1713231I-1J-303D01*
G01Y1703225D01*
G02X347078Y1702922I-302J-1D01*
G01X343378D01*
G02X343076Y1703225I1J303D01*
G01Y1713231D01*
G37*
G36*
G01X335202Y1702994D02*
G02X335504Y1703296I302J0D01*
G01X339204D01*
G02X339506Y1702994I0J-302D01*
G01Y1692988D01*
G02X339204Y1692686I-302J0D01*
G01X335504D01*
G02X335202Y1692988I0J302D01*
G01Y1702994D01*
G37*
G36*
G01X350950D02*
G02X351252Y1703296I302J0D01*
G01X354952D01*
G02X355254Y1702994I0J-302D01*
G01Y1692988D01*
G02X354952Y1692686I-302J0D01*
G01X351252D01*
G02X350950Y1692988I0J302D01*
G01Y1702994D01*
G37*
G36*
G01X327328Y1699057D02*
G02X327630Y1699360I302J1D01*
G01X331330D01*
G02X331632Y1699057I-1J-303D01*
G01Y1689051D01*
G02X331330Y1688748I-302J-1D01*
G01X327630D01*
G02X327328Y1689051I1J303D01*
G01Y1699057D01*
G37*
G36*
G01X343076D02*
G02X343378Y1699360I302J1D01*
G01X347078D01*
G02X347380Y1699057I-1J-303D01*
G01Y1689051D01*
G02X347078Y1688748I-302J-1D01*
G01X343378D01*
G02X343076Y1689051I1J303D01*
G01Y1699057D01*
G37*
G36*
G01X335202Y1685959D02*
Y1688821D01*
G02X335504Y1689124I302J1D01*
G01X339204D01*
G02X339506Y1688821I-1J-303D01*
G01Y1678815D01*
G02X339204Y1678512I-302J-1D01*
G01X335504D01*
G02X335202Y1678815I1J303D01*
G01Y1681679D01*
G02X335233Y1681813I302J1D01*
G01X336152Y1683688D01*
G03Y1683950I-267J131D01*
G01X335233Y1685825D01*
G02X335202Y1685959I271J133D01*
G37*
G36*
G01X350950D02*
Y1688821D01*
G02X351252Y1689124I302J1D01*
G01X354952D01*
G02X355254Y1688821I-1J-303D01*
G01Y1678815D01*
G02X354952Y1678512I-302J-1D01*
G01X351252D01*
G02X350950Y1678815I1J303D01*
G01Y1681679D01*
G02X350981Y1681813I302J1D01*
G01X351900Y1683688D01*
G03Y1683950I-267J131D01*
G01X350981Y1685825D01*
G02X350950Y1685959I271J133D01*
G37*
G36*
G01X327328Y1682022D02*
Y1684884D01*
G02X327630Y1685186I302J0D01*
G01X331330D01*
G02X331632Y1684884I0J-302D01*
G01Y1674878D01*
G02X331330Y1674576I-302J0D01*
G01X327630D01*
G02X327328Y1674878I0J302D01*
G01Y1677742D01*
G02X327359Y1677876I302J1D01*
G01X328278Y1679751D01*
G03Y1680013I-267J131D01*
G01X327359Y1681888D01*
G02X327328Y1682022I271J133D01*
G37*
G36*
G01X343076D02*
Y1684884D01*
G02X343378Y1685186I302J0D01*
G01X347078D01*
G02X347380Y1684884I0J-302D01*
G01Y1674878D01*
G02X347078Y1674576I-302J0D01*
G01X343378D01*
G02X343076Y1674878I0J302D01*
G01Y1677742D01*
G02X343107Y1677876I302J1D01*
G01X344026Y1679751D01*
G03Y1680013I-267J131D01*
G01X343107Y1681888D01*
G02X343076Y1682022I271J133D01*
G37*
G36*
G01X303706Y1731341D02*
G02X304008Y1731644I302J1D01*
G01X307708D01*
G02X308010Y1731341I-1J-303D01*
G01Y1721335D01*
G02X307708Y1721032I-302J-1D01*
G01X304008D01*
G02X303706Y1721335I1J303D01*
G01Y1731341D01*
G37*
G36*
G01X319454D02*
G02X319756Y1731644I302J1D01*
G01X323456D01*
G02X323758Y1731341I-1J-303D01*
G01Y1721335D01*
G02X323456Y1721032I-302J-1D01*
G01X319756D01*
G02X319454Y1721335I1J303D01*
G01Y1731341D01*
G37*
G36*
G01X295832Y1727404D02*
G02X296134Y1727706I302J0D01*
G01X299834D01*
G02X300136Y1727404I0J-302D01*
G01Y1717398D01*
G02X299834Y1717096I-302J0D01*
G01X296134D01*
G02X295832Y1717398I0J302D01*
G01Y1727404D01*
G37*
G36*
G01X311580D02*
G02X311882Y1727706I302J0D01*
G01X315582D01*
G02X315884Y1727404I0J-302D01*
G01Y1717398D01*
G02X315582Y1717096I-302J0D01*
G01X311882D01*
G02X311580Y1717398I0J302D01*
G01Y1727404D01*
G37*
G36*
G01X303706Y1717168D02*
G02X304008Y1717470I302J0D01*
G01X307708D01*
G02X308010Y1717168I0J-302D01*
G01Y1707162D01*
G02X307708Y1706860I-302J0D01*
G01X304008D01*
G02X303706Y1707162I0J302D01*
G01Y1717168D01*
G37*
G36*
G01X319454D02*
G02X319756Y1717470I302J0D01*
G01X323456D01*
G02X323758Y1717168I0J-302D01*
G01Y1707162D01*
G02X323456Y1706860I-302J0D01*
G01X319756D01*
G02X319454Y1707162I0J302D01*
G01Y1717168D01*
G37*
G36*
G01X295832Y1713231D02*
G02X296134Y1713534I302J1D01*
G01X299834D01*
G02X300136Y1713231I-1J-303D01*
G01Y1703225D01*
G02X299834Y1702922I-302J-1D01*
G01X296134D01*
G02X295832Y1703225I1J303D01*
G01Y1713231D01*
G37*
G36*
G01X311580D02*
G02X311882Y1713534I302J1D01*
G01X315582D01*
G02X315884Y1713231I-1J-303D01*
G01Y1703225D01*
G02X315582Y1702922I-302J-1D01*
G01X311882D01*
G02X311580Y1703225I1J303D01*
G01Y1713231D01*
G37*
G36*
G01X303706Y1702994D02*
G02X304008Y1703296I302J0D01*
G01X307708D01*
G02X308010Y1702994I0J-302D01*
G01Y1692988D01*
G02X307708Y1692686I-302J0D01*
G01X304008D01*
G02X303706Y1692988I0J302D01*
G01Y1702994D01*
G37*
G36*
G01X319454D02*
G02X319756Y1703296I302J0D01*
G01X323456D01*
G02X323758Y1702994I0J-302D01*
G01Y1692988D01*
G02X323456Y1692686I-302J0D01*
G01X319756D01*
G02X319454Y1692988I0J302D01*
G01Y1702994D01*
G37*
G36*
G01X295832Y1699057D02*
G02X296134Y1699360I302J1D01*
G01X299834D01*
G02X300136Y1699057I-1J-303D01*
G01Y1689051D01*
G02X299834Y1688748I-302J-1D01*
G01X296134D01*
G02X295832Y1689051I1J303D01*
G01Y1699057D01*
G37*
G36*
G01X311580D02*
G02X311882Y1699360I302J1D01*
G01X315582D01*
G02X315884Y1699057I-1J-303D01*
G01Y1689051D01*
G02X315582Y1688748I-302J-1D01*
G01X311882D01*
G02X311580Y1689051I1J303D01*
G01Y1699057D01*
G37*
G36*
G01X303706Y1685959D02*
Y1688821D01*
G02X304008Y1689124I302J1D01*
G01X307708D01*
G02X308010Y1688821I-1J-303D01*
G01Y1678815D01*
G02X307708Y1678512I-302J-1D01*
G01X304008D01*
G02X303706Y1678815I1J303D01*
G01Y1681679D01*
G02X303737Y1681813I302J1D01*
G01X304656Y1683688D01*
G03Y1683950I-267J131D01*
G01X303737Y1685825D01*
G02X303706Y1685959I271J133D01*
G37*
G36*
G01X319454D02*
Y1688821D01*
G02X319756Y1689124I302J1D01*
G01X323456D01*
G02X323758Y1688821I-1J-303D01*
G01Y1678815D01*
G02X323456Y1678512I-302J-1D01*
G01X319756D01*
G02X319454Y1678815I1J303D01*
G01Y1681679D01*
G02X319485Y1681813I302J1D01*
G01X320404Y1683688D01*
G03Y1683950I-267J131D01*
G01X319485Y1685825D01*
G02X319454Y1685959I271J133D01*
G37*
G36*
G01X295832Y1682022D02*
Y1684884D01*
G02X296134Y1685186I302J0D01*
G01X299834D01*
G02X300136Y1684884I0J-302D01*
G01Y1674878D01*
G02X299834Y1674576I-302J0D01*
G01X296134D01*
G02X295832Y1674878I0J302D01*
G01Y1677742D01*
G02X295863Y1677876I302J1D01*
G01X296782Y1679751D01*
G03Y1680013I-267J131D01*
G01X295863Y1681888D01*
G02X295832Y1682022I271J133D01*
G37*
G36*
G01X311580D02*
Y1684884D01*
G02X311882Y1685186I302J0D01*
G01X315582D01*
G02X315884Y1684884I0J-302D01*
G01Y1674878D01*
G02X315582Y1674576I-302J0D01*
G01X311882D01*
G02X311580Y1674878I0J302D01*
G01Y1677742D01*
G02X311611Y1677876I302J1D01*
G01X312530Y1679751D01*
G03Y1680013I-267J131D01*
G01X311611Y1681888D01*
G02X311580Y1682022I271J133D01*
G37*
G36*
G01X268272Y1731341D02*
G02X268575Y1731644I303J0D01*
G01X272275D01*
G02X272578Y1731341I0J-303D01*
G01Y1721335D01*
G02X272275Y1721032I-303J0D01*
G01X268575D01*
G02X268272Y1721335I0J303D01*
G01Y1731341D01*
G37*
G36*
G01X284020D02*
G02X284323Y1731644I303J0D01*
G01X288023D01*
G02X288326Y1731341I0J-303D01*
G01Y1721335D01*
G02X288023Y1721032I-303J0D01*
G01X284323D01*
G02X284020Y1721335I0J303D01*
G01Y1731341D01*
G37*
G36*
G01X260398Y1727404D02*
G02X260701Y1727706I303J-1D01*
G01X264401D01*
G02X264704Y1727404I1J-302D01*
G01Y1717398D01*
G02X264401Y1717096I-303J1D01*
G01X260701D01*
G02X260398Y1717398I-1J302D01*
G01Y1727404D01*
G37*
G36*
G01X276146D02*
G02X276449Y1727706I303J-1D01*
G01X280149D01*
G02X280452Y1727404I1J-302D01*
G01Y1717398D01*
G02X280149Y1717096I-303J1D01*
G01X276449D01*
G02X276146Y1717398I-1J302D01*
G01Y1727404D01*
G37*
G36*
G01X268272Y1717168D02*
G02X268575Y1717470I303J-1D01*
G01X272275D01*
G02X272578Y1717168I1J-302D01*
G01Y1707162D01*
G02X272275Y1706860I-303J1D01*
G01X268575D01*
G02X268272Y1707162I-1J302D01*
G01Y1717168D01*
G37*
G36*
G01X284020D02*
G02X284323Y1717470I303J-1D01*
G01X288023D01*
G02X288326Y1717168I1J-302D01*
G01Y1707162D01*
G02X288023Y1706860I-303J1D01*
G01X284323D01*
G02X284020Y1707162I-1J302D01*
G01Y1717168D01*
G37*
G36*
G01X260398Y1713231D02*
G02X260701Y1713534I303J0D01*
G01X264401D01*
G02X264704Y1713231I0J-303D01*
G01Y1703225D01*
G02X264401Y1702922I-303J0D01*
G01X260701D01*
G02X260398Y1703225I0J303D01*
G01Y1713231D01*
G37*
G36*
G01X276146D02*
G02X276449Y1713534I303J0D01*
G01X280149D01*
G02X280452Y1713231I0J-303D01*
G01Y1703225D01*
G02X280149Y1702922I-303J0D01*
G01X276449D01*
G02X276146Y1703225I0J303D01*
G01Y1713231D01*
G37*
G36*
G01X268272Y1702994D02*
G02X268575Y1703296I303J-1D01*
G01X272275D01*
G02X272578Y1702994I1J-302D01*
G01Y1692988D01*
G02X272275Y1692686I-303J1D01*
G01X268575D01*
G02X268272Y1692988I-1J302D01*
G01Y1702994D01*
G37*
G36*
G01X284020D02*
G02X284323Y1703296I303J-1D01*
G01X288023D01*
G02X288326Y1702994I1J-302D01*
G01Y1692988D01*
G02X288023Y1692686I-303J1D01*
G01X284323D01*
G02X284020Y1692988I-1J302D01*
G01Y1702994D01*
G37*
G36*
G01X260398Y1699057D02*
G02X260701Y1699360I303J0D01*
G01X264401D01*
G02X264704Y1699057I0J-303D01*
G01Y1689051D01*
G02X264401Y1688748I-303J0D01*
G01X260701D01*
G02X260398Y1689051I0J303D01*
G01Y1699057D01*
G37*
G36*
G01X276146D02*
G02X276449Y1699360I303J0D01*
G01X280149D01*
G02X280452Y1699057I0J-303D01*
G01Y1689051D01*
G02X280149Y1688748I-303J0D01*
G01X276449D01*
G02X276146Y1689051I0J303D01*
G01Y1699057D01*
G37*
G36*
G01X268272Y1685959D02*
Y1688821D01*
G02X268575Y1689124I303J0D01*
G01X272275D01*
G02X272578Y1688821I0J-303D01*
G01Y1678815D01*
G02X272275Y1678512I-303J0D01*
G01X268575D01*
G02X268272Y1678815I0J303D01*
G01Y1681679D01*
G02X268304Y1681813I303J-1D01*
G01X269223Y1683688D01*
G03Y1683950I-267J131D01*
G01X268304Y1685825D01*
G02X268272Y1685959I270J135D01*
G37*
G36*
G01X284020D02*
Y1688821D01*
G02X284323Y1689124I303J0D01*
G01X288023D01*
G02X288326Y1688821I0J-303D01*
G01Y1678815D01*
G02X288023Y1678512I-303J0D01*
G01X284323D01*
G02X284020Y1678815I0J303D01*
G01Y1681679D01*
G02X284052Y1681813I303J-1D01*
G01X284971Y1683688D01*
G03Y1683950I-267J131D01*
G01X284052Y1685825D01*
G02X284020Y1685959I270J135D01*
G37*
G36*
G01X260398Y1682022D02*
Y1684884D01*
G02X260701Y1685186I303J-1D01*
G01X264401D01*
G02X264704Y1684884I1J-302D01*
G01Y1674878D01*
G02X264401Y1674576I-303J1D01*
G01X260701D01*
G02X260398Y1674878I-1J302D01*
G01Y1677742D01*
G02X260430Y1677876I303J-1D01*
G01X261349Y1679751D01*
G03Y1680013I-267J131D01*
G01X260430Y1681888D01*
G02X260398Y1682022I270J135D01*
G37*
G36*
G01X276146D02*
Y1684884D01*
G02X276449Y1685186I303J-1D01*
G01X280149D01*
G02X280452Y1684884I1J-302D01*
G01Y1674878D01*
G02X280149Y1674576I-303J1D01*
G01X276449D01*
G02X276146Y1674878I-1J302D01*
G01Y1677742D01*
G02X276178Y1677876I303J-1D01*
G01X277097Y1679751D01*
G03Y1680013I-267J131D01*
G01X276178Y1681888D01*
G02X276146Y1682022I270J135D01*
G37*
G36*
G01X268272Y1674648D02*
G02X268575Y1674950I303J-1D01*
G01X272275D01*
G02X272578Y1674648I1J-302D01*
G01Y1664642D01*
G02X272275Y1664340I-303J1D01*
G01X268575D01*
G02X268272Y1664642I-1J302D01*
G01Y1674648D01*
G37*
G36*
G01X284020D02*
G02X284323Y1674950I303J-1D01*
G01X288023D01*
G02X288326Y1674648I1J-302D01*
G01Y1664642D01*
G02X288023Y1664340I-303J1D01*
G01X284323D01*
G02X284020Y1664642I-1J302D01*
G01Y1674648D01*
G37*
G36*
G01X276146Y1670711D02*
G02X276449Y1671014I303J0D01*
G01X280149D01*
G02X280452Y1670711I0J-303D01*
G01Y1660705D01*
G02X280149Y1660402I-303J0D01*
G01X276449D01*
G02X276146Y1660705I0J303D01*
G01Y1670711D01*
G37*
G36*
G01X268272Y1660474D02*
G02X268575Y1660776I303J-1D01*
G01X272275D01*
G02X272578Y1660474I1J-302D01*
G01Y1650468D01*
G02X272275Y1650166I-303J1D01*
G01X268575D01*
G02X268272Y1650468I-1J302D01*
G01Y1660474D01*
G37*
G36*
G01X284020D02*
G02X284323Y1660776I303J-1D01*
G01X288023D01*
G02X288326Y1660474I1J-302D01*
G01Y1650468D01*
G02X288023Y1650166I-303J1D01*
G01X284323D01*
G02X284020Y1650468I-1J302D01*
G01Y1660474D01*
G37*
G36*
G01X276146Y1656537D02*
G02X276449Y1656840I303J0D01*
G01X280149D01*
G02X280452Y1656537I0J-303D01*
G01Y1646531D01*
G02X280149Y1646228I-303J0D01*
G01X276449D01*
G02X276146Y1646531I0J303D01*
G01Y1656537D01*
G37*
G36*
G01X236776Y1731341D02*
G02X237079Y1731644I303J0D01*
G01X240779D01*
G02X241082Y1731341I0J-303D01*
G01Y1721335D01*
G02X240779Y1721032I-303J0D01*
G01X237079D01*
G02X236776Y1721335I0J303D01*
G01Y1731341D01*
G37*
G36*
G01X252524D02*
G02X252827Y1731644I303J0D01*
G01X256527D01*
G02X256830Y1731341I0J-303D01*
G01Y1721335D01*
G02X256527Y1721032I-303J0D01*
G01X252827D01*
G02X252524Y1721335I0J303D01*
G01Y1731341D01*
G37*
G36*
G01X228902Y1727404D02*
G02X229205Y1727706I303J-1D01*
G01X232905D01*
G02X233208Y1727404I1J-302D01*
G01Y1717398D01*
G02X232905Y1717096I-303J1D01*
G01X229205D01*
G02X228902Y1717398I-1J302D01*
G01Y1727404D01*
G37*
G36*
G01X244650D02*
G02X244953Y1727706I303J-1D01*
G01X248653D01*
G02X248956Y1727404I1J-302D01*
G01Y1717398D01*
G02X248653Y1717096I-303J1D01*
G01X244953D01*
G02X244650Y1717398I-1J302D01*
G01Y1727404D01*
G37*
G36*
G01X236776Y1717168D02*
G02X237079Y1717470I303J-1D01*
G01X240779D01*
G02X241082Y1717168I1J-302D01*
G01Y1707162D01*
G02X240779Y1706860I-303J1D01*
G01X237079D01*
G02X236776Y1707162I-1J302D01*
G01Y1717168D01*
G37*
G36*
G01X252524D02*
G02X252827Y1717470I303J-1D01*
G01X256527D01*
G02X256830Y1717168I1J-302D01*
G01Y1707162D01*
G02X256527Y1706860I-303J1D01*
G01X252827D01*
G02X252524Y1707162I-1J302D01*
G01Y1717168D01*
G37*
G36*
G01X228902Y1713231D02*
G02X229205Y1713534I303J0D01*
G01X232905D01*
G02X233208Y1713231I0J-303D01*
G01Y1703225D01*
G02X232905Y1702922I-303J0D01*
G01X229205D01*
G02X228902Y1703225I0J303D01*
G01Y1713231D01*
G37*
G36*
G01X244650D02*
G02X244953Y1713534I303J0D01*
G01X248653D01*
G02X248956Y1713231I0J-303D01*
G01Y1703225D01*
G02X248653Y1702922I-303J0D01*
G01X244953D01*
G02X244650Y1703225I0J303D01*
G01Y1713231D01*
G37*
G36*
G01X236776Y1702994D02*
G02X237079Y1703296I303J-1D01*
G01X240779D01*
G02X241082Y1702994I1J-302D01*
G01Y1692988D01*
G02X240779Y1692686I-303J1D01*
G01X237079D01*
G02X236776Y1692988I-1J302D01*
G01Y1702994D01*
G37*
G36*
G01X252524D02*
G02X252827Y1703296I303J-1D01*
G01X256527D01*
G02X256830Y1702994I1J-302D01*
G01Y1692988D01*
G02X256527Y1692686I-303J1D01*
G01X252827D01*
G02X252524Y1692988I-1J302D01*
G01Y1702994D01*
G37*
G36*
G01X228902Y1699057D02*
G02X229205Y1699360I303J0D01*
G01X232905D01*
G02X233208Y1699057I0J-303D01*
G01Y1689051D01*
G02X232905Y1688748I-303J0D01*
G01X229205D01*
G02X228902Y1689051I0J303D01*
G01Y1699057D01*
G37*
G36*
G01X244650D02*
G02X244953Y1699360I303J0D01*
G01X248653D01*
G02X248956Y1699057I0J-303D01*
G01Y1689051D01*
G02X248653Y1688748I-303J0D01*
G01X244953D01*
G02X244650Y1689051I0J303D01*
G01Y1699057D01*
G37*
G36*
G01X236776Y1685959D02*
Y1688821D01*
G02X237079Y1689124I303J0D01*
G01X240779D01*
G02X241082Y1688821I0J-303D01*
G01Y1678815D01*
G02X240779Y1678512I-303J0D01*
G01X237079D01*
G02X236776Y1678815I0J303D01*
G01Y1681679D01*
G02X236808Y1681813I303J-1D01*
G01X237727Y1683688D01*
G03Y1683950I-267J131D01*
G01X236808Y1685825D01*
G02X236776Y1685959I270J135D01*
G37*
G36*
G01X252524D02*
Y1688821D01*
G02X252827Y1689124I303J0D01*
G01X256527D01*
G02X256830Y1688821I0J-303D01*
G01Y1678815D01*
G02X256527Y1678512I-303J0D01*
G01X252827D01*
G02X252524Y1678815I0J303D01*
G01Y1681679D01*
G02X252556Y1681813I303J-1D01*
G01X253475Y1683688D01*
G03Y1683950I-267J131D01*
G01X252556Y1685825D01*
G02X252524Y1685959I270J135D01*
G37*
G36*
G01X228902Y1682022D02*
Y1684884D01*
G02X229205Y1685186I303J-1D01*
G01X232905D01*
G02X233208Y1684884I1J-302D01*
G01Y1674878D01*
G02X232905Y1674576I-303J1D01*
G01X229205D01*
G02X228902Y1674878I-1J302D01*
G01Y1677742D01*
G02X228934Y1677876I303J-1D01*
G01X229853Y1679751D01*
G03Y1680013I-267J131D01*
G01X228934Y1681888D01*
G02X228902Y1682022I270J135D01*
G37*
G36*
G01X244650D02*
Y1684884D01*
G02X244953Y1685186I303J-1D01*
G01X248653D01*
G02X248956Y1684884I1J-302D01*
G01Y1674878D01*
G02X248653Y1674576I-303J1D01*
G01X244953D01*
G02X244650Y1674878I-1J302D01*
G01Y1677742D01*
G02X244682Y1677876I303J-1D01*
G01X245601Y1679751D01*
G03Y1680013I-267J131D01*
G01X244682Y1681888D01*
G02X244650Y1682022I270J135D01*
G37*
G36*
G01X252524Y1674648D02*
G02X252827Y1674950I303J-1D01*
G01X256527D01*
G02X256830Y1674648I1J-302D01*
G01Y1664642D01*
G02X256527Y1664340I-303J1D01*
G01X252827D01*
G02X252524Y1664642I-1J302D01*
G01Y1674648D01*
G37*
G36*
G01X228902Y1670711D02*
G02X229205Y1671014I303J0D01*
G01X232905D01*
G02X233208Y1670711I0J-303D01*
G01Y1660705D01*
G02X232905Y1660402I-303J0D01*
G01X229205D01*
G02X228902Y1660705I0J303D01*
G01Y1670711D01*
G37*
G36*
G01X244650D02*
G02X244953Y1671014I303J0D01*
G01X248653D01*
G02X248956Y1670711I0J-303D01*
G01Y1660705D01*
G02X248653Y1660402I-303J0D01*
G01X244953D01*
G02X244650Y1660705I0J303D01*
G01Y1670711D01*
G37*
G36*
G01X236776Y1660474D02*
G02X237079Y1660776I303J-1D01*
G01X240779D01*
G02X241082Y1660474I1J-302D01*
G01Y1650468D01*
G02X240779Y1650166I-303J1D01*
G01X237079D01*
G02X236776Y1650468I-1J302D01*
G01Y1660474D01*
G37*
G36*
G01X228902Y1656537D02*
G02X229205Y1656840I303J0D01*
G01X232905D01*
G02X233208Y1656537I0J-303D01*
G01Y1646531D01*
G02X232905Y1646228I-303J0D01*
G01X229205D01*
G02X228902Y1646531I0J303D01*
G01Y1656537D01*
G37*
G36*
G01X226465Y1520264D02*
G02X227525Y1520900I1060J-565D01*
G01X227526D01*
G02X228728Y1519698I0J-1202D01*
G02X228568Y1519098I-1203J0D01*
G01X227023Y1516425D01*
X227021Y1516421D01*
G02X225951Y1515768I-1070J550D01*
G01X225950D01*
G02X224748Y1516970I0J1202D01*
G01Y1516972D01*
G02X224897Y1517551I1202J-1D01*
G01X226463Y1520261D01*
X226465Y1520264D01*
G37*
G36*
G01X231189D02*
G02X232249Y1520900I1060J-565D01*
G01X232250D01*
G02X233452Y1519698I0J-1202D01*
G02X233292Y1519098I-1203J0D01*
G01X231747Y1516425D01*
X231745Y1516421D01*
G02X230675Y1515768I-1070J550D01*
G01X230674D01*
G02X229472Y1516970I0J1202D01*
G01Y1516972D01*
G02X229621Y1517551I1202J-1D01*
G01X231187Y1520261D01*
X231189Y1520264D01*
G37*
G36*
G01X235914D02*
G02X236974Y1520900I1060J-565D01*
G01X236975D01*
G02X238178Y1519698I1J-1202D01*
G02X238017Y1519098I-1204J1D01*
G01X236472Y1516425D01*
X236470Y1516421D01*
G02X235400Y1515768I-1070J550D01*
G01X235399D01*
G02X234196Y1516970I-1J1202D01*
G01Y1516972D01*
G02X234346Y1517551I1203J-3D01*
G01X235912Y1520261D01*
X235914Y1520264D01*
G37*
G36*
G01X240638D02*
G02X241698Y1520900I1060J-565D01*
G01X241699D01*
G02X242902Y1519698I1J-1202D01*
G02X242741Y1519098I-1204J1D01*
G01X241196Y1516425D01*
X241194Y1516421D01*
G02X240124Y1515768I-1070J550D01*
G01X240123D01*
G02X238920Y1516970I-1J1202D01*
G01Y1516972D01*
G02X239070Y1517551I1203J-3D01*
G01X240636Y1520261D01*
X240638Y1520264D01*
G37*
G36*
G01X245362D02*
G02X246422Y1520900I1060J-565D01*
G01X246423D01*
G02X247626Y1519698I1J-1202D01*
G02X247465Y1519098I-1204J1D01*
G01X245920Y1516425D01*
X245918Y1516421D01*
G02X244848Y1515768I-1070J550D01*
G01X244847D01*
G02X243644Y1516970I-1J1202D01*
G01Y1516972D01*
G02X243794Y1517551I1203J-3D01*
G01X245360Y1520261D01*
X245362Y1520264D01*
G37*
G36*
G01X250087D02*
G02X251147Y1520900I1060J-565D01*
G01X251148D01*
G02X252350Y1519698I0J-1202D01*
G02X252190Y1519098I-1203J0D01*
G01X250645Y1516425D01*
X250643Y1516421D01*
G02X249573Y1515768I-1070J550D01*
G01X249572D01*
G02X248370Y1516970I0J1202D01*
G01Y1516972D01*
G02X248519Y1517551I1202J-1D01*
G01X250085Y1520261D01*
X250087Y1520264D01*
G37*
G36*
G01X254811D02*
G02X255871Y1520900I1060J-565D01*
G01X255872D01*
G02X257074Y1519698I0J-1202D01*
G02X256914Y1519098I-1203J0D01*
G01X255369Y1516425D01*
X255367Y1516421D01*
G02X254297Y1515768I-1070J550D01*
G01X254296D01*
G02X253094Y1516970I0J1202D01*
G01Y1516972D01*
G02X253243Y1517551I1202J-1D01*
G01X254809Y1520261D01*
X254811Y1520264D01*
G37*
G36*
G01X259536D02*
G02X260596Y1520900I1060J-565D01*
G01X260597D01*
G02X261800Y1519698I1J-1202D01*
G02X261639Y1519098I-1204J1D01*
G01X260094Y1516425D01*
X260092Y1516421D01*
G02X259022Y1515768I-1070J550D01*
G01X259021D01*
G02X257818Y1516970I-1J1202D01*
G01Y1516972D01*
G02X257968Y1517551I1203J-3D01*
G01X259534Y1520261D01*
X259536Y1520264D01*
G37*
G36*
G01X186968Y1530801D02*
G02X187102Y1531189I1187J-193D01*
G01X188666Y1533895D01*
X188667Y1533898D01*
G02X189730Y1534538I1063J-563D01*
G02X190932Y1533336I0J-1202D01*
G01Y1533335D01*
G02X190779Y1532748I-1202J0D01*
G01X190774Y1532738D01*
X190773D01*
X190772Y1532736D01*
X189229Y1530066D01*
X189227Y1530061D01*
G02X186968Y1530800I-1072J545D01*
G01Y1530801D01*
G37*
G36*
G01X191692D02*
G02X191826Y1531189I1187J-193D01*
G01X193390Y1533895D01*
X193391Y1533898D01*
G02X194454Y1534538I1063J-563D01*
G02X195656Y1533336I0J-1202D01*
G01Y1533335D01*
G02X195503Y1532748I-1202J0D01*
G01X195498Y1532738D01*
X195497D01*
X195496Y1532736D01*
X193953Y1530066D01*
X193951Y1530061D01*
G02X191692Y1530800I-1072J545D01*
G01Y1530801D01*
G37*
G36*
G01X196416D02*
G02X196550Y1531189I1187J-193D01*
G01X198114Y1533895D01*
X198115Y1533898D01*
G02X199178Y1534538I1063J-563D01*
G02X200380Y1533336I0J-1202D01*
G01Y1533335D01*
G02X200227Y1532748I-1202J0D01*
G01X200222Y1532738D01*
X200221D01*
X200220Y1532736D01*
X198677Y1530066D01*
X198675Y1530061D01*
G02X196416Y1530800I-1072J545D01*
G01Y1530801D01*
G37*
G36*
G01X201141D02*
G02X201275Y1531189I1187J-193D01*
G01X202839Y1533895D01*
X202840Y1533898D01*
G02X203903Y1534538I1063J-563D01*
G02X205106Y1533336I1J-1202D01*
G01Y1533335D01*
G02X204952Y1532748I-1203J2D01*
G01X204947Y1532738D01*
X204946D01*
X204945Y1532736D01*
X203402Y1530066D01*
X203400Y1530061D01*
G02X201141Y1530800I-1072J545D01*
G01Y1530801D01*
G37*
G36*
G01X205865D02*
G02X205999Y1531189I1187J-193D01*
G01X207563Y1533895D01*
X207564Y1533898D01*
G02X208627Y1534538I1063J-563D01*
G02X209830Y1533336I1J-1202D01*
G01Y1533335D01*
G02X209676Y1532748I-1203J2D01*
G01X209671Y1532738D01*
X209670D01*
X209669Y1532736D01*
X208126Y1530066D01*
X208124Y1530061D01*
G02X205865Y1530800I-1072J545D01*
G01Y1530801D01*
G37*
G36*
G01X210590D02*
G02X210724Y1531189I1187J-193D01*
G01X212288Y1533895D01*
X212289Y1533898D01*
G02X213352Y1534538I1063J-563D01*
G02X214554Y1533336I0J-1202D01*
G01Y1533335D01*
G02X214401Y1532748I-1202J0D01*
G01X214396Y1532738D01*
X214395D01*
X214394Y1532736D01*
X212851Y1530066D01*
X212849Y1530061D01*
G02X210590Y1530800I-1072J545D01*
G01Y1530801D01*
G37*
G36*
G01X215314D02*
G02X215448Y1531189I1187J-193D01*
G01X217012Y1533895D01*
X217013Y1533898D01*
G02X218076Y1534538I1063J-563D01*
G02X219278Y1533336I0J-1202D01*
G01Y1533335D01*
G02X219125Y1532748I-1202J0D01*
G01X219120Y1532738D01*
X219119D01*
X219118Y1532736D01*
X217575Y1530066D01*
X217573Y1530061D01*
G02X215314Y1530800I-1072J545D01*
G01Y1530801D01*
G37*
G36*
G01X220038D02*
G02X220172Y1531189I1187J-193D01*
G01X221736Y1533895D01*
X221737Y1533898D01*
G02X222800Y1534538I1063J-563D01*
G02X224002Y1533336I0J-1202D01*
G01Y1533335D01*
G02X223849Y1532748I-1202J0D01*
G01X223844Y1532738D01*
X223843D01*
X223842Y1532736D01*
X222299Y1530066D01*
X222297Y1530061D01*
G02X220038Y1530800I-1072J545D01*
G01Y1530801D01*
G37*
G36*
G01X224763D02*
G02X224897Y1531189I1187J-193D01*
G01X226461Y1533895D01*
X226462Y1533898D01*
G02X227525Y1534538I1063J-563D01*
G02X228728Y1533336I1J-1202D01*
G01Y1533335D01*
G02X228574Y1532748I-1203J2D01*
G01X228569Y1532738D01*
X228568D01*
X228567Y1532736D01*
X227024Y1530066D01*
X227022Y1530061D01*
G02X224763Y1530800I-1072J545D01*
G01Y1530801D01*
G37*
G36*
G01X229487D02*
G02X229621Y1531189I1187J-193D01*
G01X231185Y1533895D01*
X231186Y1533898D01*
G02X232249Y1534538I1063J-563D01*
G02X233452Y1533336I1J-1202D01*
G01Y1533335D01*
G02X233298Y1532748I-1203J2D01*
G01X233293Y1532738D01*
X233292D01*
X233291Y1532736D01*
X231748Y1530066D01*
X231746Y1530061D01*
G02X229487Y1530800I-1072J545D01*
G01Y1530801D01*
G37*
G36*
G01X234212D02*
G02X234346Y1531189I1187J-193D01*
G01X235910Y1533895D01*
X235911Y1533898D01*
G02X236974Y1534538I1063J-563D01*
G02X238176Y1533336I0J-1202D01*
G01Y1533335D01*
G02X238023Y1532748I-1202J0D01*
G01X238018Y1532738D01*
X238017D01*
X238016Y1532736D01*
X236473Y1530066D01*
X236471Y1530061D01*
G02X234212Y1530800I-1072J545D01*
G01Y1530801D01*
G37*
G36*
G01X238936D02*
G02X239070Y1531189I1187J-193D01*
G01X240634Y1533895D01*
X240635Y1533898D01*
G02X241698Y1534538I1063J-563D01*
G02X242900Y1533336I0J-1202D01*
G01Y1533335D01*
G02X242747Y1532748I-1202J0D01*
G01X242742Y1532738D01*
X242741D01*
X242740Y1532736D01*
X241197Y1530066D01*
X241195Y1530061D01*
G02X238936Y1530800I-1072J545D01*
G01Y1530801D01*
G37*
G36*
G01X243660D02*
G02X243794Y1531189I1187J-193D01*
G01X245358Y1533895D01*
X245359Y1533898D01*
G02X246422Y1534538I1063J-563D01*
G02X247624Y1533336I0J-1202D01*
G01Y1533335D01*
G02X247471Y1532748I-1202J0D01*
G01X247466Y1532738D01*
X247465D01*
X247464Y1532736D01*
X245921Y1530066D01*
X245919Y1530061D01*
G02X243660Y1530800I-1072J545D01*
G01Y1530801D01*
G37*
G36*
G01X248385D02*
G02X248519Y1531189I1187J-193D01*
G01X250083Y1533895D01*
X250084Y1533898D01*
G02X251147Y1534538I1063J-563D01*
G02X252350Y1533336I1J-1202D01*
G01Y1533335D01*
G02X252196Y1532748I-1203J2D01*
G01X252191Y1532738D01*
X252190D01*
X252189Y1532736D01*
X250646Y1530066D01*
X250644Y1530061D01*
G02X248385Y1530800I-1072J545D01*
G01Y1530801D01*
G37*
G36*
G01X253109D02*
G02X253243Y1531189I1187J-193D01*
G01X254807Y1533895D01*
X254808Y1533898D01*
G02X255871Y1534538I1063J-563D01*
G02X257074Y1533336I1J-1202D01*
G01Y1533335D01*
G02X256920Y1532748I-1203J2D01*
G01X256915Y1532738D01*
X256914D01*
X256913Y1532736D01*
X255370Y1530066D01*
X255368Y1530061D01*
G02X253109Y1530800I-1072J545D01*
G01Y1530801D01*
G37*
G36*
G01X257834D02*
G02X257968Y1531189I1187J-193D01*
G01X259532Y1533895D01*
X259533Y1533898D01*
G02X260596Y1534538I1063J-563D01*
G02X261798Y1533336I0J-1202D01*
G01Y1533335D01*
G02X261645Y1532748I-1202J0D01*
G01X261640Y1532738D01*
X261639D01*
X261638Y1532736D01*
X260095Y1530066D01*
X260093Y1530061D01*
G02X257834Y1530800I-1072J545D01*
G01Y1530801D01*
G37*
G36*
G01X315030D02*
G02X315164Y1531189I1187J-193D01*
G01X316728Y1533895D01*
X316729Y1533898D01*
G02X317792Y1534538I1063J-563D01*
G02X318994Y1533336I0J-1202D01*
G01Y1533335D01*
G02X318841Y1532748I-1202J0D01*
G01X318836Y1532738D01*
X318835D01*
X318834Y1532736D01*
X317291Y1530066D01*
X317289Y1530061D01*
G02X315030Y1530800I-1072J545D01*
G01Y1530801D01*
G37*
G36*
G01X319754D02*
G02X319888Y1531189I1187J-193D01*
G01X321452Y1533895D01*
X321453Y1533898D01*
G02X322516Y1534538I1063J-563D01*
G02X323718Y1533336I0J-1202D01*
G01Y1533335D01*
G02X323565Y1532748I-1202J0D01*
G01X323560Y1532738D01*
X323559D01*
X323558Y1532736D01*
X322015Y1530066D01*
X322013Y1530061D01*
G02X319754Y1530800I-1072J545D01*
G01Y1530801D01*
G37*
G36*
G01X324478D02*
G02X324612Y1531189I1187J-193D01*
G01X326176Y1533895D01*
X326177Y1533898D01*
G02X327240Y1534538I1063J-563D01*
G02X328442Y1533336I0J-1202D01*
G01Y1533335D01*
G02X328289Y1532748I-1202J0D01*
G01X328284Y1532738D01*
X328283D01*
X328282Y1532736D01*
X326739Y1530066D01*
X326737Y1530061D01*
G02X324478Y1530800I-1072J545D01*
G01Y1530801D01*
G37*
G36*
G01X329203D02*
G02X329337Y1531189I1187J-193D01*
G01X330901Y1533895D01*
X330902Y1533898D01*
G02X331965Y1534538I1063J-563D01*
G02X333168Y1533336I1J-1202D01*
G01Y1533335D01*
G02X333014Y1532748I-1203J2D01*
G01X333009Y1532738D01*
X333008D01*
X333007Y1532736D01*
X331464Y1530066D01*
X331462Y1530061D01*
G02X329203Y1530800I-1072J545D01*
G01Y1530801D01*
G37*
G36*
G01X333927D02*
G02X334061Y1531189I1187J-193D01*
G01X335625Y1533895D01*
X335626Y1533898D01*
G02X336689Y1534538I1063J-563D01*
G02X337892Y1533336I1J-1202D01*
G01Y1533335D01*
G02X337738Y1532748I-1203J2D01*
G01X337733Y1532738D01*
X337732D01*
X337731Y1532736D01*
X336188Y1530066D01*
X336186Y1530061D01*
G02X333927Y1530800I-1072J545D01*
G01Y1530801D01*
G37*
G36*
G01X338652D02*
G02X338786Y1531189I1187J-193D01*
G01X340350Y1533895D01*
X340351Y1533898D01*
G02X341414Y1534538I1063J-563D01*
G02X342616Y1533336I0J-1202D01*
G01Y1533335D01*
G02X342463Y1532748I-1202J0D01*
G01X342458Y1532738D01*
X342457D01*
X342456Y1532736D01*
X340913Y1530066D01*
X340911Y1530061D01*
G02X338652Y1530800I-1072J545D01*
G01Y1530801D01*
G37*
G36*
G01X343376D02*
G02X343510Y1531189I1187J-193D01*
G01X345074Y1533895D01*
X345075Y1533898D01*
G02X346138Y1534538I1063J-563D01*
G02X347340Y1533336I0J-1202D01*
G01Y1533335D01*
G02X347187Y1532748I-1202J0D01*
G01X347182Y1532738D01*
X347181D01*
X347180Y1532736D01*
X345637Y1530066D01*
X345635Y1530061D01*
G02X343376Y1530800I-1072J545D01*
G01Y1530801D01*
G37*
G36*
G01X348100D02*
G02X348234Y1531189I1187J-193D01*
G01X349798Y1533895D01*
X349799Y1533898D01*
G02X350862Y1534538I1063J-563D01*
G02X352064Y1533336I0J-1202D01*
G01Y1533335D01*
G02X351911Y1532748I-1202J0D01*
G01X351906Y1532738D01*
X351905D01*
X351904Y1532736D01*
X350361Y1530066D01*
X350359Y1530061D01*
G02X348100Y1530800I-1072J545D01*
G01Y1530801D01*
G37*
G36*
G01X352825D02*
G02X352959Y1531189I1187J-193D01*
G01X354523Y1533895D01*
X354524Y1533898D01*
G02X355587Y1534538I1063J-563D01*
G02X356790Y1533336I1J-1202D01*
G01Y1533335D01*
G02X356636Y1532748I-1203J2D01*
G01X356631Y1532738D01*
X356630D01*
X356629Y1532736D01*
X355086Y1530066D01*
X355084Y1530061D01*
G02X352825Y1530800I-1072J545D01*
G01Y1530801D01*
G37*
G36*
G01X357549D02*
G02X357683Y1531189I1187J-193D01*
G01X359247Y1533895D01*
X359248Y1533898D01*
G02X360311Y1534538I1063J-563D01*
G02X361514Y1533336I1J-1202D01*
G01Y1533335D01*
G02X361360Y1532748I-1203J2D01*
G01X361355Y1532738D01*
X361354D01*
X361353Y1532736D01*
X359810Y1530066D01*
X359808Y1530061D01*
G02X357549Y1530800I-1072J545D01*
G01Y1530801D01*
G37*
G36*
G01X362274D02*
G02X362408Y1531189I1187J-193D01*
G01X363972Y1533895D01*
X363973Y1533898D01*
G02X365036Y1534538I1063J-563D01*
G02X366238Y1533336I0J-1202D01*
G01Y1533335D01*
G02X366085Y1532748I-1202J0D01*
G01X366080Y1532738D01*
X366079D01*
X366078Y1532736D01*
X364535Y1530066D01*
X364533Y1530061D01*
G02X362274Y1530800I-1072J545D01*
G01Y1530801D01*
G37*
G36*
G01X366998D02*
G02X367132Y1531189I1187J-193D01*
G01X368696Y1533895D01*
X368697Y1533898D01*
G02X369760Y1534538I1063J-563D01*
G02X370962Y1533336I0J-1202D01*
G01Y1533335D01*
G02X370809Y1532748I-1202J0D01*
G01X370804Y1532738D01*
X370803D01*
X370802Y1532736D01*
X369259Y1530066D01*
X369257Y1530061D01*
G02X366998Y1530800I-1072J545D01*
G01Y1530801D01*
G37*
G36*
G01X371722D02*
G02X371856Y1531189I1187J-193D01*
G01X373420Y1533895D01*
X373421Y1533898D01*
G02X374484Y1534538I1063J-563D01*
G02X375686Y1533336I0J-1202D01*
G01Y1533335D01*
G02X375533Y1532748I-1202J0D01*
G01X375528Y1532738D01*
X375527D01*
X375526Y1532736D01*
X373983Y1530066D01*
X373981Y1530061D01*
G02X371722Y1530800I-1072J545D01*
G01Y1530801D01*
G37*
G36*
G01X376447D02*
G02X376581Y1531189I1187J-193D01*
G01X378145Y1533895D01*
X378146Y1533898D01*
G02X379209Y1534538I1063J-563D01*
G02X380412Y1533336I1J-1202D01*
G01Y1533335D01*
G02X380258Y1532748I-1203J2D01*
G01X380253Y1532738D01*
X380252D01*
X380251Y1532736D01*
X378708Y1530066D01*
X378706Y1530061D01*
G02X376447Y1530800I-1072J545D01*
G01Y1530801D01*
G37*
G36*
G01X381171D02*
G02X381305Y1531189I1187J-193D01*
G01X382869Y1533895D01*
X382870Y1533898D01*
G02X383933Y1534538I1063J-563D01*
G02X385136Y1533336I1J-1202D01*
G01Y1533335D01*
G02X384982Y1532748I-1203J2D01*
G01X384977Y1532738D01*
X384976D01*
X384975Y1532736D01*
X383432Y1530066D01*
X383430Y1530061D01*
G02X381171Y1530800I-1072J545D01*
G01Y1530801D01*
G37*
G36*
G01X385896D02*
G02X386030Y1531189I1187J-193D01*
G01X387594Y1533895D01*
X387595Y1533898D01*
G02X388658Y1534538I1063J-563D01*
G02X389860Y1533336I0J-1202D01*
G01Y1533335D01*
G02X389707Y1532748I-1202J0D01*
G01X389702Y1532738D01*
X389701D01*
X389700Y1532736D01*
X388157Y1530066D01*
X388155Y1530061D01*
G02X385896Y1530800I-1072J545D01*
G01Y1530801D01*
G37*
G36*
G01X451141D02*
G02X451275Y1531189I1187J-193D01*
G01X452839Y1533895D01*
X452840Y1533898D01*
G02X453903Y1534538I1063J-563D01*
G02X455106Y1533336I1J-1202D01*
G01Y1533335D01*
G02X454952Y1532748I-1203J2D01*
G01X454947Y1532738D01*
X454946D01*
X454945Y1532736D01*
X453402Y1530066D01*
X453400Y1530061D01*
G02X451141Y1530800I-1072J545D01*
G01Y1530801D01*
G37*
G36*
G01X455865D02*
G02X455999Y1531189I1187J-193D01*
G01X457563Y1533895D01*
X457564Y1533898D01*
G02X458627Y1534538I1063J-563D01*
G02X459830Y1533336I1J-1202D01*
G01Y1533335D01*
G02X459676Y1532748I-1203J2D01*
G01X459671Y1532738D01*
X459670D01*
X459669Y1532736D01*
X458126Y1530066D01*
X458124Y1530061D01*
G02X455865Y1530800I-1072J545D01*
G01Y1530801D01*
G37*
G36*
G01X460589D02*
G02X460723Y1531189I1187J-193D01*
G01X462287Y1533895D01*
X462288Y1533898D01*
G02X463351Y1534538I1063J-563D01*
G02X464554Y1533336I1J-1202D01*
G01Y1533335D01*
G02X464400Y1532748I-1203J2D01*
G01X464395Y1532738D01*
X464394D01*
X464393Y1532736D01*
X462850Y1530066D01*
X462848Y1530061D01*
G02X460589Y1530800I-1072J545D01*
G01Y1530801D01*
G37*
G36*
G01X465314D02*
G02X465448Y1531189I1187J-193D01*
G01X467012Y1533895D01*
X467013Y1533898D01*
G02X468076Y1534538I1063J-563D01*
G02X469278Y1533336I0J-1202D01*
G01Y1533335D01*
G02X469125Y1532748I-1202J0D01*
G01X469120Y1532738D01*
X469119D01*
X469118Y1532736D01*
X467575Y1530066D01*
X467573Y1530061D01*
G02X465314Y1530800I-1072J545D01*
G01Y1530801D01*
G37*
G36*
G01X470038D02*
G02X470172Y1531189I1187J-193D01*
G01X471736Y1533895D01*
X471737Y1533898D01*
G02X472800Y1534538I1063J-563D01*
G02X474002Y1533336I0J-1202D01*
G01Y1533335D01*
G02X473849Y1532748I-1202J0D01*
G01X473844Y1532738D01*
X473843D01*
X473842Y1532736D01*
X472299Y1530066D01*
X472297Y1530061D01*
G02X470038Y1530800I-1072J545D01*
G01Y1530801D01*
G37*
G36*
G01X474763D02*
G02X474897Y1531189I1187J-193D01*
G01X476461Y1533895D01*
X476462Y1533898D01*
G02X477525Y1534538I1063J-563D01*
G02X478728Y1533336I1J-1202D01*
G01Y1533335D01*
G02X478574Y1532748I-1203J2D01*
G01X478569Y1532738D01*
X478568D01*
X478567Y1532736D01*
X477024Y1530066D01*
X477022Y1530061D01*
G02X474763Y1530800I-1072J545D01*
G01Y1530801D01*
G37*
G36*
G01X479487D02*
G02X479621Y1531189I1187J-193D01*
G01X481185Y1533895D01*
X481186Y1533898D01*
G02X482249Y1534538I1063J-563D01*
G02X483452Y1533336I1J-1202D01*
G01Y1533335D01*
G02X483298Y1532748I-1203J2D01*
G01X483293Y1532738D01*
X483292D01*
X483291Y1532736D01*
X481748Y1530066D01*
X481746Y1530061D01*
G02X479487Y1530800I-1072J545D01*
G01Y1530801D01*
G37*
G36*
G01X484211D02*
G02X484345Y1531189I1187J-193D01*
G01X485909Y1533895D01*
X485910Y1533898D01*
G02X486973Y1534538I1063J-563D01*
G02X488176Y1533336I1J-1202D01*
G01Y1533335D01*
G02X488022Y1532748I-1203J2D01*
G01X488017Y1532738D01*
X488016D01*
X488015Y1532736D01*
X486472Y1530066D01*
X486470Y1530061D01*
G02X484211Y1530800I-1072J545D01*
G01Y1530801D01*
G37*
G36*
G01X488936D02*
G02X489070Y1531189I1187J-193D01*
G01X490634Y1533895D01*
X490635Y1533898D01*
G02X491698Y1534538I1063J-563D01*
G02X492900Y1533336I0J-1202D01*
G01Y1533335D01*
G02X492747Y1532748I-1202J0D01*
G01X492742Y1532738D01*
X492741D01*
X492740Y1532736D01*
X491197Y1530066D01*
X491195Y1530061D01*
G02X488936Y1530800I-1072J545D01*
G01Y1530801D01*
G37*
G36*
G01X493660D02*
G02X493794Y1531189I1187J-193D01*
G01X495358Y1533895D01*
X495359Y1533898D01*
G02X496422Y1534538I1063J-563D01*
G02X497624Y1533336I0J-1202D01*
G01Y1533335D01*
G02X497471Y1532748I-1202J0D01*
G01X497466Y1532738D01*
X497465D01*
X497464Y1532736D01*
X495921Y1530066D01*
X495919Y1530061D01*
G02X493660Y1530800I-1072J545D01*
G01Y1530801D01*
G37*
G36*
G01X498385D02*
G02X498519Y1531189I1187J-193D01*
G01X500083Y1533895D01*
X500084Y1533898D01*
G02X501147Y1534538I1063J-563D01*
G02X502350Y1533336I1J-1202D01*
G01Y1533335D01*
G02X502196Y1532748I-1203J2D01*
G01X502191Y1532738D01*
X502190D01*
X502189Y1532736D01*
X500646Y1530066D01*
X500644Y1530061D01*
G02X498385Y1530800I-1072J545D01*
G01Y1530801D01*
G37*
G36*
G01X503109D02*
G02X503243Y1531189I1187J-193D01*
G01X504807Y1533895D01*
X504808Y1533898D01*
G02X505871Y1534538I1063J-563D01*
G02X507074Y1533336I1J-1202D01*
G01Y1533335D01*
G02X506920Y1532748I-1203J2D01*
G01X506915Y1532738D01*
X506914D01*
X506913Y1532736D01*
X505370Y1530066D01*
X505368Y1530061D01*
G02X503109Y1530800I-1072J545D01*
G01Y1530801D01*
G37*
G36*
G01X507833D02*
G02X507967Y1531189I1187J-193D01*
G01X509531Y1533895D01*
X509532Y1533898D01*
G02X510595Y1534538I1063J-563D01*
G02X511798Y1533336I1J-1202D01*
G01Y1533335D01*
G02X511644Y1532748I-1203J2D01*
G01X511639Y1532738D01*
X511638D01*
X511637Y1532736D01*
X510094Y1530066D01*
X510092Y1530061D01*
G02X507833Y1530800I-1072J545D01*
G01Y1530801D01*
G37*
G36*
G01X512558D02*
G02X512692Y1531189I1187J-193D01*
G01X514256Y1533895D01*
X514257Y1533898D01*
G02X515320Y1534538I1063J-563D01*
G02X516522Y1533336I0J-1202D01*
G01Y1533335D01*
G02X516369Y1532748I-1202J0D01*
G01X516364Y1532738D01*
X516363D01*
X516362Y1532736D01*
X514819Y1530066D01*
X514817Y1530061D01*
G02X512558Y1530800I-1072J545D01*
G01Y1530801D01*
G37*
G36*
G01X517282D02*
G02X517416Y1531189I1187J-193D01*
G01X518980Y1533895D01*
X518981Y1533898D01*
G02X520044Y1534538I1063J-563D01*
G02X521246Y1533336I0J-1202D01*
G01Y1533335D01*
G02X521093Y1532748I-1202J0D01*
G01X521088Y1532738D01*
X521087D01*
X521086Y1532736D01*
X519543Y1530066D01*
X519541Y1530061D01*
G02X517282Y1530800I-1072J545D01*
G01Y1530801D01*
G37*
G36*
G01X522007D02*
G02X522141Y1531189I1187J-193D01*
G01X523705Y1533895D01*
X523706Y1533898D01*
G02X524769Y1534538I1063J-563D01*
G02X525972Y1533336I1J-1202D01*
G01Y1533335D01*
G02X525818Y1532748I-1203J2D01*
G01X525813Y1532738D01*
X525812D01*
X525811Y1532736D01*
X524268Y1530066D01*
X524266Y1530061D01*
G02X522007Y1530800I-1072J545D01*
G01Y1530801D01*
G37*
G36*
G01X1205991Y1553264D02*
G02X1207051Y1553900I1060J-565D01*
G01X1207052D01*
G02X1208254Y1552698I0J-1202D01*
G02X1208094Y1552098I-1203J0D01*
G01X1206549Y1549425D01*
X1206547Y1549421D01*
G02X1205477Y1548768I-1070J550D01*
G01X1205476D01*
G02X1204274Y1549970I0J1202D01*
G01Y1549972D01*
G02X1204423Y1550551I1202J-1D01*
G01X1205989Y1553261D01*
X1205991Y1553264D01*
G37*
G36*
G01X1229613D02*
G02X1230673Y1553900I1060J-565D01*
G01X1230674D01*
G02X1231876Y1552698I0J-1202D01*
G02X1231716Y1552098I-1203J0D01*
G01X1230171Y1549425D01*
X1230169Y1549421D01*
G02X1229099Y1548768I-1070J550D01*
G01X1229098D01*
G02X1227896Y1549970I0J1202D01*
G01Y1549972D01*
G02X1228045Y1550551I1202J-1D01*
G01X1229611Y1553261D01*
X1229613Y1553264D01*
G37*
G36*
G01X1234338D02*
G02X1235398Y1553900I1060J-565D01*
G01X1235399D01*
G02X1236602Y1552698I1J-1202D01*
G02X1236441Y1552098I-1204J1D01*
G01X1234896Y1549425D01*
X1234894Y1549421D01*
G02X1233824Y1548768I-1070J550D01*
G01X1233823D01*
G02X1232620Y1549970I-1J1202D01*
G01Y1549972D01*
G02X1232770Y1550551I1203J-3D01*
G01X1234336Y1553261D01*
X1234338Y1553264D01*
G37*
G36*
G01X1239062D02*
G02X1240122Y1553900I1060J-565D01*
G01X1240123D01*
G02X1241326Y1552698I1J-1202D01*
G02X1241165Y1552098I-1204J1D01*
G01X1239620Y1549425D01*
X1239618Y1549421D01*
G02X1238548Y1548768I-1070J550D01*
G01X1238547D01*
G02X1237344Y1549970I-1J1202D01*
G01Y1549972D01*
G02X1237494Y1550551I1203J-3D01*
G01X1239060Y1553261D01*
X1239062Y1553264D01*
G37*
G36*
G01X1248511D02*
G02X1249571Y1553900I1060J-565D01*
G01X1249572D01*
G02X1250774Y1552698I0J-1202D01*
G02X1250614Y1552098I-1203J0D01*
G01X1249069Y1549425D01*
X1249067Y1549421D01*
G02X1247997Y1548768I-1070J550D01*
G01X1247996D01*
G02X1246794Y1549970I0J1202D01*
G01Y1549972D01*
G02X1246943Y1550551I1202J-1D01*
G01X1248509Y1553261D01*
X1248511Y1553264D01*
G37*
G36*
G01X1257960D02*
G02X1259020Y1553900I1060J-565D01*
G01X1259021D01*
G02X1260224Y1552698I1J-1202D01*
G02X1260063Y1552098I-1204J1D01*
G01X1258518Y1549425D01*
X1258516Y1549421D01*
G02X1257446Y1548768I-1070J550D01*
G01X1257445D01*
G02X1256242Y1549970I-1J1202D01*
G01Y1549972D01*
G02X1256392Y1550551I1203J-3D01*
G01X1257958Y1553261D01*
X1257960Y1553264D01*
G37*
G36*
G01X1334053D02*
G02X1335113Y1553900I1060J-565D01*
G01X1335114D01*
G02X1336316Y1552698I0J-1202D01*
G02X1336156Y1552098I-1203J0D01*
G01X1334611Y1549425D01*
X1334609Y1549421D01*
G02X1333539Y1548768I-1070J550D01*
G01X1333538D01*
G02X1332336Y1549970I0J1202D01*
G01Y1549972D01*
G02X1332485Y1550551I1202J-1D01*
G01X1334051Y1553261D01*
X1334053Y1553264D01*
G37*
G36*
G01X1357675D02*
G02X1358735Y1553900I1060J-565D01*
G01X1358736D01*
G02X1359938Y1552698I0J-1202D01*
G02X1359778Y1552098I-1203J0D01*
G01X1358233Y1549425D01*
X1358231Y1549421D01*
G02X1357161Y1548768I-1070J550D01*
G01X1357160D01*
G02X1355958Y1549970I0J1202D01*
G01Y1549972D01*
G02X1356107Y1550551I1202J-1D01*
G01X1357673Y1553261D01*
X1357675Y1553264D01*
G37*
G36*
G01X1381297D02*
G02X1382357Y1553900I1060J-565D01*
G01X1382358D01*
G02X1383560Y1552698I0J-1202D01*
G02X1383400Y1552098I-1203J0D01*
G01X1381855Y1549425D01*
X1381853Y1549421D01*
G02X1380783Y1548768I-1070J550D01*
G01X1380782D01*
G02X1379580Y1549970I0J1202D01*
G01Y1549972D01*
G02X1379729Y1550551I1202J-1D01*
G01X1381295Y1553261D01*
X1381297Y1553264D01*
G37*
G36*
G01X1390746D02*
G02X1391806Y1553900I1060J-565D01*
G01X1391807D01*
G02X1393010Y1552698I1J-1202D01*
G02X1392849Y1552098I-1204J1D01*
G01X1391304Y1549425D01*
X1391302Y1549421D01*
G02X1390232Y1548768I-1070J550D01*
G01X1390231D01*
G02X1389028Y1549970I-1J1202D01*
G01Y1549972D01*
G02X1389178Y1550551I1203J-3D01*
G01X1390744Y1553261D01*
X1390746Y1553264D01*
G37*
G36*
G01X1322903Y1563801D02*
G02X1323037Y1564189I1187J-193D01*
G01X1324601Y1566895D01*
X1324602Y1566898D01*
G02X1325665Y1567538I1063J-563D01*
G02X1326868Y1566336I1J-1202D01*
G01Y1566335D01*
G02X1326714Y1565748I-1203J2D01*
G01X1326709Y1565738D01*
X1326708D01*
X1326707Y1565736D01*
X1325164Y1563066D01*
X1325162Y1563061D01*
G02X1322903Y1563800I-1072J545D01*
G01Y1563801D01*
G37*
G36*
G01X1327627D02*
G02X1327761Y1564189I1187J-193D01*
G01X1329325Y1566895D01*
X1329326Y1566898D01*
G02X1330389Y1567538I1063J-563D01*
G02X1331592Y1566336I1J-1202D01*
G01Y1566335D01*
G02X1331438Y1565748I-1203J2D01*
G01X1331433Y1565738D01*
X1331432D01*
X1331431Y1565736D01*
X1329888Y1563066D01*
X1329886Y1563061D01*
G02X1327627Y1563800I-1072J545D01*
G01Y1563801D01*
G37*
G36*
G01X1332351D02*
G02X1332485Y1564189I1187J-193D01*
G01X1334049Y1566895D01*
X1334050Y1566898D01*
G02X1335113Y1567538I1063J-563D01*
G02X1336316Y1566336I1J-1202D01*
G01Y1566335D01*
G02X1336162Y1565748I-1203J2D01*
G01X1336157Y1565738D01*
X1336156D01*
X1336155Y1565736D01*
X1334612Y1563066D01*
X1334610Y1563061D01*
G02X1332351Y1563800I-1072J545D01*
G01Y1563801D01*
G37*
G36*
G01X1337076D02*
G02X1337210Y1564189I1187J-193D01*
G01X1338774Y1566895D01*
X1338775Y1566898D01*
G02X1339838Y1567538I1063J-563D01*
G02X1341040Y1566336I0J-1202D01*
G01Y1566335D01*
G02X1340887Y1565748I-1202J0D01*
G01X1340882Y1565738D01*
X1340881D01*
X1340880Y1565736D01*
X1339337Y1563066D01*
X1339335Y1563061D01*
G02X1337076Y1563800I-1072J545D01*
G01Y1563801D01*
G37*
G36*
G01X1341800D02*
G02X1341934Y1564189I1187J-193D01*
G01X1343498Y1566895D01*
X1343499Y1566898D01*
G02X1344562Y1567538I1063J-563D01*
G02X1345764Y1566336I0J-1202D01*
G01Y1566335D01*
G02X1345611Y1565748I-1202J0D01*
G01X1345606Y1565738D01*
X1345605D01*
X1345604Y1565736D01*
X1344061Y1563066D01*
X1344059Y1563061D01*
G02X1341800Y1563800I-1072J545D01*
G01Y1563801D01*
G37*
G36*
G01X1346525D02*
G02X1346659Y1564189I1187J-193D01*
G01X1348223Y1566895D01*
X1348224Y1566898D01*
G02X1349287Y1567538I1063J-563D01*
G02X1350490Y1566336I1J-1202D01*
G01Y1566335D01*
G02X1350336Y1565748I-1203J2D01*
G01X1350331Y1565738D01*
X1350330D01*
X1350329Y1565736D01*
X1348786Y1563066D01*
X1348784Y1563061D01*
G02X1346525Y1563800I-1072J545D01*
G01Y1563801D01*
G37*
G36*
G01X1351249D02*
G02X1351383Y1564189I1187J-193D01*
G01X1352947Y1566895D01*
X1352948Y1566898D01*
G02X1354011Y1567538I1063J-563D01*
G02X1355214Y1566336I1J-1202D01*
G01Y1566335D01*
G02X1355060Y1565748I-1203J2D01*
G01X1355055Y1565738D01*
X1355054D01*
X1355053Y1565736D01*
X1353510Y1563066D01*
X1353508Y1563061D01*
G02X1351249Y1563800I-1072J545D01*
G01Y1563801D01*
G37*
G36*
G01X1355973D02*
G02X1356107Y1564189I1187J-193D01*
G01X1357671Y1566895D01*
X1357672Y1566898D01*
G02X1358735Y1567538I1063J-563D01*
G02X1359938Y1566336I1J-1202D01*
G01Y1566335D01*
G02X1359784Y1565748I-1203J2D01*
G01X1359779Y1565738D01*
X1359778D01*
X1359777Y1565736D01*
X1358234Y1563066D01*
X1358232Y1563061D01*
G02X1355973Y1563800I-1072J545D01*
G01Y1563801D01*
G37*
G36*
G01X1360698D02*
G02X1360832Y1564189I1187J-193D01*
G01X1362396Y1566895D01*
X1362397Y1566898D01*
G02X1363460Y1567538I1063J-563D01*
G02X1364662Y1566336I0J-1202D01*
G01Y1566335D01*
G02X1364509Y1565748I-1202J0D01*
G01X1364504Y1565738D01*
X1364503D01*
X1364502Y1565736D01*
X1362959Y1563066D01*
X1362957Y1563061D01*
G02X1360698Y1563800I-1072J545D01*
G01Y1563801D01*
G37*
G36*
G01X1365422D02*
G02X1365556Y1564189I1187J-193D01*
G01X1367120Y1566895D01*
X1367121Y1566898D01*
G02X1368184Y1567538I1063J-563D01*
G02X1369386Y1566336I0J-1202D01*
G01Y1566335D01*
G02X1369233Y1565748I-1202J0D01*
G01X1369228Y1565738D01*
X1369227D01*
X1369226Y1565736D01*
X1367683Y1563066D01*
X1367681Y1563061D01*
G02X1365422Y1563800I-1072J545D01*
G01Y1563801D01*
G37*
G36*
G01X1370147D02*
G02X1370281Y1564189I1187J-193D01*
G01X1371845Y1566895D01*
X1371846Y1566898D01*
G02X1372909Y1567538I1063J-563D01*
G02X1374112Y1566336I1J-1202D01*
G01Y1566335D01*
G02X1373958Y1565748I-1203J2D01*
G01X1373953Y1565738D01*
X1373952D01*
X1373951Y1565736D01*
X1372408Y1563066D01*
X1372406Y1563061D01*
G02X1370147Y1563800I-1072J545D01*
G01Y1563801D01*
G37*
G36*
G01X1374871D02*
G02X1375005Y1564189I1187J-193D01*
G01X1376569Y1566895D01*
X1376570Y1566898D01*
G02X1377633Y1567538I1063J-563D01*
G02X1378836Y1566336I1J-1202D01*
G01Y1566335D01*
G02X1378682Y1565748I-1203J2D01*
G01X1378677Y1565738D01*
X1378676D01*
X1378675Y1565736D01*
X1377132Y1563066D01*
X1377130Y1563061D01*
G02X1374871Y1563800I-1072J545D01*
G01Y1563801D01*
G37*
G36*
G01X1379595D02*
G02X1379729Y1564189I1187J-193D01*
G01X1381293Y1566895D01*
X1381294Y1566898D01*
G02X1382357Y1567538I1063J-563D01*
G02X1383560Y1566336I1J-1202D01*
G01Y1566335D01*
G02X1383406Y1565748I-1203J2D01*
G01X1383401Y1565738D01*
X1383400D01*
X1383399Y1565736D01*
X1381856Y1563066D01*
X1381854Y1563061D01*
G02X1379595Y1563800I-1072J545D01*
G01Y1563801D01*
G37*
G36*
G01X1384320D02*
G02X1384454Y1564189I1187J-193D01*
G01X1386018Y1566895D01*
X1386019Y1566898D01*
G02X1387082Y1567538I1063J-563D01*
G02X1388284Y1566336I0J-1202D01*
G01Y1566335D01*
G02X1388131Y1565748I-1202J0D01*
G01X1388126Y1565738D01*
X1388125D01*
X1388124Y1565736D01*
X1386581Y1563066D01*
X1386579Y1563061D01*
G02X1384320Y1563800I-1072J545D01*
G01Y1563801D01*
G37*
G36*
G01X1389044D02*
G02X1389178Y1564189I1187J-193D01*
G01X1390742Y1566895D01*
X1390743Y1566898D01*
G02X1391806Y1567538I1063J-563D01*
G02X1393008Y1566336I0J-1202D01*
G01Y1566335D01*
G02X1392855Y1565748I-1202J0D01*
G01X1392850Y1565738D01*
X1392849D01*
X1392848Y1565736D01*
X1391305Y1563066D01*
X1391303Y1563061D01*
G02X1389044Y1563800I-1072J545D01*
G01Y1563801D01*
G37*
G36*
G01X1393769D02*
G02X1393903Y1564189I1187J-193D01*
G01X1395467Y1566895D01*
X1395468Y1566898D01*
G02X1396531Y1567538I1063J-563D01*
G02X1397734Y1566336I1J-1202D01*
G01Y1566335D01*
G02X1397580Y1565748I-1203J2D01*
G01X1397575Y1565738D01*
X1397574D01*
X1397573Y1565736D01*
X1396030Y1563066D01*
X1396028Y1563061D01*
G02X1393769Y1563800I-1072J545D01*
G01Y1563801D01*
G37*
G36*
G01X1459015D02*
G02X1459149Y1564189I1187J-193D01*
G01X1460713Y1566895D01*
X1460714Y1566898D01*
G02X1461777Y1567538I1063J-563D01*
G02X1462980Y1566336I1J-1202D01*
G01Y1566335D01*
G02X1462826Y1565748I-1203J2D01*
G01X1462821Y1565738D01*
X1462820D01*
X1462819Y1565736D01*
X1461276Y1563066D01*
X1461274Y1563061D01*
G02X1459015Y1563800I-1072J545D01*
G01Y1563801D01*
G37*
G36*
G01X1463739D02*
G02X1463873Y1564189I1187J-193D01*
G01X1465437Y1566895D01*
X1465438Y1566898D01*
G02X1466501Y1567538I1063J-563D01*
G02X1467704Y1566336I1J-1202D01*
G01Y1566335D01*
G02X1467550Y1565748I-1203J2D01*
G01X1467545Y1565738D01*
X1467544D01*
X1467543Y1565736D01*
X1466000Y1563066D01*
X1465998Y1563061D01*
G02X1463739Y1563800I-1072J545D01*
G01Y1563801D01*
G37*
G36*
G01X1468463D02*
G02X1468597Y1564189I1187J-193D01*
G01X1470161Y1566895D01*
X1470162Y1566898D01*
G02X1471225Y1567538I1063J-563D01*
G02X1472428Y1566336I1J-1202D01*
G01Y1566335D01*
G02X1472274Y1565748I-1203J2D01*
G01X1472269Y1565738D01*
X1472268D01*
X1472267Y1565736D01*
X1470724Y1563066D01*
X1470722Y1563061D01*
G02X1468463Y1563800I-1072J545D01*
G01Y1563801D01*
G37*
G36*
G01X1473188D02*
G02X1473322Y1564189I1187J-193D01*
G01X1474886Y1566895D01*
X1474887Y1566898D01*
G02X1475950Y1567538I1063J-563D01*
G02X1477152Y1566336I0J-1202D01*
G01Y1566335D01*
G02X1476999Y1565748I-1202J0D01*
G01X1476994Y1565738D01*
X1476993D01*
X1476992Y1565736D01*
X1475449Y1563066D01*
X1475447Y1563061D01*
G02X1473188Y1563800I-1072J545D01*
G01Y1563801D01*
G37*
G36*
G01X1477912D02*
G02X1478046Y1564189I1187J-193D01*
G01X1479610Y1566895D01*
X1479611Y1566898D01*
G02X1480674Y1567538I1063J-563D01*
G02X1481876Y1566336I0J-1202D01*
G01Y1566335D01*
G02X1481723Y1565748I-1202J0D01*
G01X1481718Y1565738D01*
X1481717D01*
X1481716Y1565736D01*
X1480173Y1563066D01*
X1480171Y1563061D01*
G02X1477912Y1563800I-1072J545D01*
G01Y1563801D01*
G37*
G36*
G01X1482637D02*
G02X1482771Y1564189I1187J-193D01*
G01X1484335Y1566895D01*
X1484336Y1566898D01*
G02X1485399Y1567538I1063J-563D01*
G02X1486602Y1566336I1J-1202D01*
G01Y1566335D01*
G02X1486448Y1565748I-1203J2D01*
G01X1486443Y1565738D01*
X1486442D01*
X1486441Y1565736D01*
X1484898Y1563066D01*
X1484896Y1563061D01*
G02X1482637Y1563800I-1072J545D01*
G01Y1563801D01*
G37*
G36*
G01X1487361D02*
G02X1487495Y1564189I1187J-193D01*
G01X1489059Y1566895D01*
X1489060Y1566898D01*
G02X1490123Y1567538I1063J-563D01*
G02X1491326Y1566336I1J-1202D01*
G01Y1566335D01*
G02X1491172Y1565748I-1203J2D01*
G01X1491167Y1565738D01*
X1491166D01*
X1491165Y1565736D01*
X1489622Y1563066D01*
X1489620Y1563061D01*
G02X1487361Y1563800I-1072J545D01*
G01Y1563801D01*
G37*
G36*
G01X1492085D02*
G02X1492219Y1564189I1187J-193D01*
G01X1493783Y1566895D01*
X1493784Y1566898D01*
G02X1494847Y1567538I1063J-563D01*
G02X1496050Y1566336I1J-1202D01*
G01Y1566335D01*
G02X1495896Y1565748I-1203J2D01*
G01X1495891Y1565738D01*
X1495890D01*
X1495889Y1565736D01*
X1494346Y1563066D01*
X1494344Y1563061D01*
G02X1492085Y1563800I-1072J545D01*
G01Y1563801D01*
G37*
G36*
G01X1496810D02*
G02X1496944Y1564189I1187J-193D01*
G01X1498508Y1566895D01*
X1498509Y1566898D01*
G02X1499572Y1567538I1063J-563D01*
G02X1500774Y1566336I0J-1202D01*
G01Y1566335D01*
G02X1500621Y1565748I-1202J0D01*
G01X1500616Y1565738D01*
X1500615D01*
X1500614Y1565736D01*
X1499071Y1563066D01*
X1499069Y1563061D01*
G02X1496810Y1563800I-1072J545D01*
G01Y1563801D01*
G37*
G36*
G01X1501534D02*
G02X1501668Y1564189I1187J-193D01*
G01X1503232Y1566895D01*
X1503233Y1566898D01*
G02X1504296Y1567538I1063J-563D01*
G02X1505498Y1566336I0J-1202D01*
G01Y1566335D01*
G02X1505345Y1565748I-1202J0D01*
G01X1505340Y1565738D01*
X1505339D01*
X1505338Y1565736D01*
X1503795Y1563066D01*
X1503793Y1563061D01*
G02X1501534Y1563800I-1072J545D01*
G01Y1563801D01*
G37*
G36*
G01X1506259D02*
G02X1506393Y1564189I1187J-193D01*
G01X1507957Y1566895D01*
X1507958Y1566898D01*
G02X1509021Y1567538I1063J-563D01*
G02X1510224Y1566336I1J-1202D01*
G01Y1566335D01*
G02X1510070Y1565748I-1203J2D01*
G01X1510065Y1565738D01*
X1510064D01*
X1510063Y1565736D01*
X1508520Y1563066D01*
X1508518Y1563061D01*
G02X1506259Y1563800I-1072J545D01*
G01Y1563801D01*
G37*
G36*
G01X1510983D02*
G02X1511117Y1564189I1187J-193D01*
G01X1512681Y1566895D01*
X1512682Y1566898D01*
G02X1513745Y1567538I1063J-563D01*
G02X1514948Y1566336I1J-1202D01*
G01Y1566335D01*
G02X1514794Y1565748I-1203J2D01*
G01X1514789Y1565738D01*
X1514788D01*
X1514787Y1565736D01*
X1513244Y1563066D01*
X1513242Y1563061D01*
G02X1510983Y1563800I-1072J545D01*
G01Y1563801D01*
G37*
G36*
G01X1515707D02*
G02X1515841Y1564189I1187J-193D01*
G01X1517405Y1566895D01*
X1517406Y1566898D01*
G02X1518469Y1567538I1063J-563D01*
G02X1519672Y1566336I1J-1202D01*
G01Y1566335D01*
G02X1519518Y1565748I-1203J2D01*
G01X1519513Y1565738D01*
X1519512D01*
X1519511Y1565736D01*
X1517968Y1563066D01*
X1517966Y1563061D01*
G02X1515707Y1563800I-1072J545D01*
G01Y1563801D01*
G37*
G36*
G01X1520432D02*
G02X1520566Y1564189I1187J-193D01*
G01X1522130Y1566895D01*
X1522131Y1566898D01*
G02X1523194Y1567538I1063J-563D01*
G02X1524396Y1566336I0J-1202D01*
G01Y1566335D01*
G02X1524243Y1565748I-1202J0D01*
G01X1524238Y1565738D01*
X1524237D01*
X1524236Y1565736D01*
X1522693Y1563066D01*
X1522691Y1563061D01*
G02X1520432Y1563800I-1072J545D01*
G01Y1563801D01*
G37*
G36*
G01X1525156D02*
G02X1525290Y1564189I1187J-193D01*
G01X1526854Y1566895D01*
X1526855Y1566898D01*
G02X1527918Y1567538I1063J-563D01*
G02X1529120Y1566336I0J-1202D01*
G01Y1566335D01*
G02X1528967Y1565748I-1202J0D01*
G01X1528962Y1565738D01*
X1528961D01*
X1528960Y1565736D01*
X1527417Y1563066D01*
X1527415Y1563061D01*
G02X1525156Y1563800I-1072J545D01*
G01Y1563801D01*
G37*
G36*
G01X1529881D02*
G02X1530015Y1564189I1187J-193D01*
G01X1531579Y1566895D01*
X1531580Y1566898D01*
G02X1532643Y1567538I1063J-563D01*
G02X1533846Y1566336I1J-1202D01*
G01Y1566335D01*
G02X1533692Y1565748I-1203J2D01*
G01X1533687Y1565738D01*
X1533686D01*
X1533685Y1565736D01*
X1532142Y1563066D01*
X1532140Y1563061D01*
G02X1529881Y1563800I-1072J545D01*
G01Y1563801D01*
G37*
G36*
G01X639269Y1612790D02*
G02Y1615794I0J1502D01*
G01X642669D01*
G02Y1612790I0J-1502D01*
G01X639269D01*
G37*
G36*
G01X627209D02*
G02Y1615794I0J1502D01*
G01X630609D01*
G02Y1612790I0J-1502D01*
G01X627209D01*
G37*
G36*
G01X621179Y1590878D02*
G02Y1593882I0J1502D01*
G01X624579D01*
G02Y1590878I0J-1502D01*
G01X621179D01*
G37*
G36*
G01X633239Y1622790D02*
G02Y1625794I0J1502D01*
G01X636639D01*
G02Y1622790I0J-1502D01*
G01X633239D01*
G37*
G36*
G01X615149Y1600878D02*
G02Y1603882I0J1502D01*
G01X618549D01*
G02Y1600878I0J-1502D01*
G01X615149D01*
G37*
G36*
G01X627209D02*
G02Y1603882I0J1502D01*
G01X630609D01*
G02Y1600878I0J-1502D01*
G01X627209D01*
G37*
G36*
G01X639269D02*
G02Y1603882I0J1502D01*
G01X642669D01*
G02Y1600878I0J-1502D01*
G01X639269D01*
G37*
G36*
G01X633239Y1590878D02*
G02Y1593882I0J1502D01*
G01X636639D01*
G02Y1590878I0J-1502D01*
G01X633239D01*
G37*
G36*
G01X609119D02*
G02Y1593882I0J1502D01*
G01X612519D01*
G02Y1590878I0J-1502D01*
G01X609119D01*
G37*
G36*
G01Y1622790D02*
G02Y1625794I0J1502D01*
G01X612519D01*
G02Y1622790I0J-1502D01*
G01X609119D01*
G37*
G36*
G01X621179D02*
G02Y1625794I0J1502D01*
G01X624579D01*
G02Y1622790I0J-1502D01*
G01X621179D01*
G37*
G36*
G01X615149Y1612790D02*
G02Y1615794I0J1502D01*
G01X618549D01*
G02Y1612790I0J-1502D01*
G01X615149D01*
G37*
G54D92*
X766889Y1486756D03*
Y1530256D03*
G54D99*
X1571516Y319099D03*
X1290127Y410635D03*
X1005307Y155043D03*
X944406Y1532791D03*
X820901Y147112D03*
X788710Y1488821D03*
X712291Y106722D03*
X263316Y87665D03*
X101675Y160694D03*
G54D108*
X505185Y41141D03*
X60303Y20354D03*
X1534712D03*
G54D86*
X398673Y-18871D03*
Y-8871D03*
X373673D03*
Y-18871D03*
X398673Y-28871D03*
X373673D03*
X718093Y-8871D03*
Y-18871D03*
X743093D03*
Y-8871D03*
X718093Y-28871D03*
X743093D03*
X850152Y-5011D03*
X825152D03*
X850152Y-15011D03*
X825152D03*
X850152Y-35011D03*
Y-25011D03*
X825152D03*
Y-35011D03*
X850152Y4989D03*
X825152D03*
X850152Y14989D03*
X825152D03*
X850152Y24989D03*
X825152D03*
X1169572Y-5011D03*
X1194572D03*
X1169572Y-15011D03*
X1194572D03*
X1169572Y-25011D03*
Y-35011D03*
X1194572D03*
Y-25011D03*
X1169572Y4989D03*
X1194572D03*
X1169572Y14989D03*
X1194572D03*
X1169572Y24989D03*
X1194572D03*
X1253672Y-15011D03*
X1228672D03*
X1253672Y-35011D03*
Y-25011D03*
X1228672D03*
Y-35011D03*
X1253672Y-5011D03*
X1228672D03*
X1253672Y4989D03*
Y14989D03*
X1228672D03*
Y4989D03*
X1253672Y24989D03*
X1228672D03*
X1428431Y-15011D03*
X1453431D03*
X1428431Y-25011D03*
Y-35011D03*
X1453431D03*
Y-25011D03*
X1428431Y-5011D03*
X1453431D03*
X1428431Y14989D03*
Y4989D03*
X1453431D03*
Y14989D03*
X1428431Y24989D03*
X1453431D03*
X1546966Y-39212D03*
Y-29212D03*
X1521966D03*
Y-39212D03*
X1546966Y-19212D03*
X1521966D03*
X1721725Y-29212D03*
Y-39212D03*
X1746725D03*
Y-29212D03*
X1721725Y-19212D03*
X1746725D03*
G54D93*
X1787330Y24291D03*
X922441Y237697D03*
X929331Y160413D03*
X312921Y24291D03*
G54D96*
X676509Y224606D03*
G54D97*
Y145866D03*
G54D104*
X1066280Y1704890D03*
G54D107*
X1340948Y1179681D03*
G54D98*
X1700840Y1424519D03*
X1524437Y640365D03*
X1487677Y640145D03*
X1415690Y601230D03*
X1320516Y1375715D03*
X1291146D03*
X1166535Y1412479D03*
X754645Y1426892D03*
X433624Y594259D03*
X363731Y653394D03*
X326731D03*
G54D103*
X1131824Y1602293D03*
X1141084Y1644972D03*
X1090958Y1648228D03*
X1115098Y1470571D03*
X1562640Y1558031D03*
X554766Y1525031D03*
X1170404Y1558031D03*
X558876Y1456605D03*
X1298466Y1558031D03*
X426704Y1525031D03*
X165336Y1676777D03*
X85836Y1656843D03*
X1434578Y1558031D03*
X436776Y1612094D03*
X388630Y1238447D03*
X390974Y1221149D03*
X313284Y1216822D03*
X814296Y1385745D03*
X1521718Y1579697D03*
X1516994D03*
X1512270D03*
X1507546D03*
X1474474D03*
X1469750D03*
X1493372D03*
X1488648D03*
X1649780D03*
X1645056D03*
X1640332D03*
X1635608D03*
X1602536D03*
X1597812D03*
X1621434D03*
X1616710D03*
X466600Y1546697D03*
X461876D03*
X1385606Y1579697D03*
X1380882D03*
X1376158D03*
X1371434D03*
X1338362D03*
X1333638D03*
X1357260D03*
X1352536D03*
X499672Y1546697D03*
X641906D03*
X637182D03*
X632458D03*
X627734D03*
X513844D03*
X509120D03*
X504396D03*
X485498D03*
X480774D03*
X1257544Y1579697D03*
X1252820D03*
X1248096D03*
X1243372D03*
X1210300D03*
X1205576D03*
X1229198D03*
X1224474D03*
X589938Y1546697D03*
X608836D03*
X594662D03*
X613560D03*
X1680730Y1515382D03*
X672856Y1482382D03*
X1563222Y1514890D03*
X1552668Y1515382D03*
X1435160Y1514890D03*
X1299048D03*
X555348Y1481890D03*
X544794Y1482382D03*
X427286Y1481890D03*
X387182Y1546697D03*
X382458D03*
X358836D03*
X354112D03*
X339938D03*
X335214D03*
X321040D03*
X316316D03*
X259120D03*
X254396D03*
X230774D03*
X226050D03*
X211876D03*
X207152D03*
X192978D03*
X188254D03*
X142576Y1641863D03*
X555348Y1503690D03*
X1170986Y1536690D03*
Y1514890D03*
X1416556Y1515382D03*
Y1528782D03*
X544794Y1495782D03*
X1680730Y1528782D03*
X1299048Y1536690D03*
X1342036Y1204729D03*
X427286Y1503690D03*
X1563222Y1536690D03*
X526460Y99195D03*
X40922Y1656569D03*
X372000Y844727D03*
Y833497D03*
X672856Y1495782D03*
X1435160Y1536690D03*
X1552668Y1528782D03*
X1288494D03*
Y1515382D03*
X400426Y114515D03*
X570860Y123010D03*
X553780Y122940D03*
X417486Y125879D03*
X50880Y1417263D03*
X35852Y690616D03*
Y679710D03*
Y701522D03*
Y668745D03*
G54D109*
X1681102Y1626654D03*
X163662Y1593661D03*
X1171536Y1626654D03*
X698819Y1482244D03*
X1706693Y1515236D03*
X1145945D03*
X138071Y1482244D03*
X673228Y1593661D03*
G54D102*
X403837Y1610756D03*
X1142917Y1585014D03*
X1118133Y1589698D03*
X1146501Y1653908D03*
X162531Y1525031D03*
X290593D03*
X546253Y1455807D03*
X165491Y1663882D03*
X87891Y1672821D03*
X704771Y169488D03*
X280621Y1495782D03*
X1370685Y1224732D03*
X653999Y1425057D03*
X58349Y1408031D03*
X154945Y1626050D03*
X1531167Y1579697D03*
X1526443D03*
X1502821D03*
X1498097D03*
X1483923D03*
X1479199D03*
X1465025D03*
X1460301D03*
X1659229D03*
X1654505D03*
X1630883D03*
X1626159D03*
X1611985D03*
X1607261D03*
X1593087D03*
X1588363D03*
X476049Y1546697D03*
X471325D03*
X1395055Y1579697D03*
X1390331D03*
X1366709D03*
X1361985D03*
X1347811D03*
X1343087D03*
X1328913D03*
X1324189D03*
X494947Y1546697D03*
X490223D03*
X646631D03*
X623009D03*
X618285D03*
X651355D03*
X518569D03*
X523293D03*
X452427D03*
X457151D03*
X1266993Y1579697D03*
X1262269D03*
X1238647D03*
X1233923D03*
X1219749D03*
X1215025D03*
X1200851D03*
X1196127D03*
X585213Y1546697D03*
X604111D03*
X599387D03*
X580489D03*
X1346063Y1216029D03*
X193679Y1641752D03*
X297323Y1655472D03*
X307255Y1645450D03*
X163113Y1503690D03*
Y1481890D03*
X280621Y1482382D03*
X291175Y1481890D03*
Y1503690D03*
X377733Y1546697D03*
X373009D03*
X368285D03*
X363561D03*
X349387D03*
X344663D03*
X330489D03*
X325765D03*
X249671D03*
X244947D03*
X240223D03*
X235499D03*
X221325D03*
X216601D03*
X202427D03*
X197703D03*
X205479Y1650430D03*
X408683Y1482382D03*
X1315657Y1197832D03*
X408683Y1495782D03*
X163735Y1633669D03*
X99443Y1660231D03*
X100443Y1685763D03*
X41679Y1675023D03*
X371999Y821227D03*
X385001Y815227D03*
X1007587Y774180D03*
Y763246D03*
Y840056D03*
Y829054D03*
Y818052D03*
Y807118D03*
Y796184D03*
Y785182D03*
X559069Y103685D03*
X482255Y131522D03*
X704771Y193110D03*
X716699Y210721D03*
Y198887D03*
Y175387D03*
Y187387D03*
X704771Y216732D03*
Y204921D03*
Y181299D03*
G54D106*
X516020Y107320D03*
X535170Y113180D03*
X80948Y523563D03*
X405606Y127765D03*
X80318Y541363D03*
G54D90*
X1766929Y1714960D03*
G54D94*
X1739745Y605411D03*
X1094076Y605378D03*
X763602Y605413D03*
X117933Y605376D03*
G54D84*
X1729562Y-24215D03*
Y-34215D03*
X1436268Y9986D03*
Y-14D03*
Y-20014D03*
Y-30014D03*
X725930Y-13874D03*
Y-23874D03*
X390846Y-13874D03*
Y-23874D03*
G54D83*
X1837795Y18819D03*
X19685Y-29134D03*
X1804650Y1667292D03*
X441043Y1672205D03*
X1416437D03*
X1800449Y126194D03*
X44000Y154200D03*
X31818Y1424257D03*
X1885039Y49021D03*
X2081889Y-29134D03*
X2081889Y1803261D03*
X1871260Y1291627D03*
G54D105*
X47619Y417134D03*
X1025493Y763769D03*
X62813Y414050D03*
G54D101*
X1829921Y130314D03*
G54D95*
X1057659Y204724D03*
X805690D03*
G54D85*
X1539139Y-24215D03*
Y-34215D03*
X1245845Y9986D03*
Y-14D03*
Y-20014D03*
Y-30014D03*
X1177409Y19986D03*
Y9986D03*
Y-10014D03*
Y-20014D03*
X842325Y19986D03*
Y9986D03*
Y-10014D03*
Y-20014D03*
G54D89*
X274913Y1019214D03*
X606409D03*
X1251055Y1019213D03*
X1582551D03*
G54D88*
X320189Y838505D03*
X1296331Y838504D03*
G54D87*
X561133Y838505D03*
Y1199923D03*
X1537275Y838504D03*
Y1199922D03*
X1296331D03*
X320189Y1199923D03*
G54D91*
X841240Y1420331D03*
X1016240D03*
G54D100*
X177413Y277208D03*
X704185Y277236D03*
X1153555Y277208D03*
X1680327Y277236D03*
%LPC*%
G75*
G36*
G01X923910Y1641951D02*
G03X924794Y1641585I884J885D01*
G01X1071014D01*
G02X1071156Y1641526I0J-200D01*
G01X1102501Y1610181D01*
G02X1102560Y1610039I-141J-142D01*
G01Y1569173D01*
G02X1102501Y1569031I-200J0D01*
G01X1099604Y1566134D01*
G02X1099462Y1566075I-142J141D01*
G01X943079D01*
G02X942937Y1566134I0J200D01*
G01X941792Y1567279D01*
G02X941733Y1567421I141J142D01*
G01Y1598998D01*
G03X941367Y1599882I-1251J0D01*
G01X924961Y1616288D01*
G03X924077Y1616654I-884J-885D01*
G01X904324D01*
G02X904182Y1616713I0J200D01*
G01X894299Y1626596D01*
G03X893415Y1626962I-884J-885D01*
G01X771436D01*
G02X771294Y1627021I0J200D01*
G01X768659Y1629656D01*
G02X768600Y1629798I141J142D01*
G01Y1656300D01*
G02X768659Y1656442I200J0D01*
G03X768660Y1656443I-883J884D01*
G01X810874Y1698657D01*
G03X811240Y1699541I-885J884D01*
G01Y1712907D01*
G02X811299Y1713049I200J0D01*
G01X816611Y1718361D01*
G02X816753Y1718420I142J-141D01*
G01X901267D01*
G02X901409Y1718361I0J-200D01*
G01X904191Y1715579D01*
G02X904250Y1715437I-141J-142D01*
G01Y1662129D01*
G03X904616Y1661245I1251J0D01*
G01X923910Y1641951D01*
G37*
%LPD*%
G75*
G54D14*
X11782Y167036D03*
X18691Y167208D03*
X22409Y230021D03*
X19684Y237154D03*
X19230Y1446459D03*
X34281Y277798D03*
Y282916D03*
X35689Y298207D03*
X34281Y312916D03*
Y307798D03*
X35740Y363337D03*
X39320Y392269D03*
X28562Y517025D03*
X39967Y526709D03*
X30562Y533055D03*
X35952Y551605D03*
X35010Y1289485D03*
X35040Y1292433D03*
X35080Y1298360D03*
X35040Y1295380D03*
X34584Y1307744D03*
Y1310244D03*
Y1312744D03*
Y1315244D03*
X33822Y1477075D03*
Y1486075D03*
Y1483075D03*
Y1480075D03*
X27205Y1501630D03*
Y1498230D03*
X38058Y1591405D03*
X35167Y1598896D03*
Y1626896D03*
Y1629405D03*
X32927Y1668587D03*
X42449Y282916D03*
Y277798D03*
X41492Y292892D03*
Y298207D03*
X47892Y295452D03*
X40500Y288500D03*
X55254Y292892D03*
X42449Y312916D03*
Y307798D03*
X51114Y360862D03*
X43020Y382942D03*
X40940Y387302D03*
X41933Y395652D03*
X47619Y419084D03*
X47618Y415184D03*
X49360Y428806D03*
X45960D03*
X49212Y451602D03*
X45812D03*
X47812Y517635D03*
X42810Y528070D03*
X39952Y551605D03*
X55099Y1298676D03*
Y1292676D03*
X51000Y1339200D03*
X50880Y1415563D03*
Y1418963D03*
X42822Y1477075D03*
Y1483075D03*
Y1486075D03*
Y1480075D03*
X49265Y1490950D03*
Y1493450D03*
X49188Y1499181D03*
X41360Y1498971D03*
X41309Y1496173D03*
X38650Y1499326D03*
X49177Y1496272D03*
X48383Y1532395D03*
X48157Y1536296D03*
X49196Y1551294D03*
X48324Y1545961D03*
X48758Y1559295D03*
X48907Y1554972D03*
X47735Y1584885D03*
X47973Y1589981D03*
X43633Y1606896D03*
X46833Y1612596D03*
X43933Y1613818D03*
X47633Y1600896D03*
X53633Y1629896D03*
X41208Y1619896D03*
X42491Y1638656D03*
X40167Y1632405D03*
X40922Y1654869D03*
Y1658269D03*
X45052Y1684283D03*
X41679Y1673323D03*
Y1676723D03*
X65933Y28406D03*
Y48720D03*
X61157Y69340D03*
X64557D03*
X66650Y265316D03*
X57271Y272357D03*
X59780Y282866D03*
X62567Y295103D03*
X66289Y298207D03*
X59780Y312866D03*
X59322Y360702D03*
X63429D03*
X67681D03*
X53406Y402862D03*
X62812Y412100D03*
X62813Y416000D03*
X64821Y430806D03*
X60921D03*
X63540Y438802D03*
X64442Y510667D03*
X55682Y517595D03*
X62142Y539495D03*
X56192Y537795D03*
X63633Y528229D03*
X58365Y552365D03*
X53299D03*
X56627Y585818D03*
X59259Y737422D03*
X58751Y777718D03*
X61251D03*
Y775218D03*
X58751D03*
X61620Y768510D03*
X56440Y766180D03*
X58751Y790218D03*
Y792718D03*
Y780218D03*
X61251D03*
X56057Y792750D03*
X61251Y792718D03*
Y790218D03*
X56057Y790250D03*
Y787750D03*
X61251Y787718D03*
X56057Y785250D03*
X61251Y785218D03*
Y782718D03*
X56057Y782750D03*
X58751Y782718D03*
Y785218D03*
Y787718D03*
X57752Y808020D03*
X60547Y1276036D03*
X57747Y1270470D03*
X55099Y1289676D03*
X55043Y1295676D03*
X53700Y1342300D03*
X58349Y1406331D03*
Y1409731D03*
X67010Y1476292D03*
X57822Y1477075D03*
X57777Y1490580D03*
X66710Y1485324D03*
Y1482324D03*
X66785Y1479175D03*
X57822Y1482791D03*
Y1485294D03*
Y1480075D03*
X64030Y1491595D03*
X57770Y1488047D03*
X66696Y1488010D03*
X64030Y1499095D03*
Y1501595D03*
Y1494095D03*
Y1496595D03*
X55370Y1551351D03*
X66229Y1549536D03*
X61605Y1546833D03*
X64275Y1546296D03*
X57811Y1598061D03*
X58633Y1587481D03*
X63633D03*
X61110Y1598146D03*
X58633Y1629896D03*
X64133Y1627896D03*
X64633Y1632896D03*
X64427Y1643496D03*
X64462Y1655624D03*
X61927Y1643496D03*
X65257Y1652941D03*
X56815Y1643431D03*
X62202Y1684579D03*
X66127Y1687362D03*
X72153Y75343D03*
X75553D03*
X79726Y145191D03*
X82026Y143491D03*
X71659Y149191D03*
X71779Y165194D03*
X71775Y153194D03*
X72462Y268223D03*
X77680Y378395D03*
Y380895D03*
X68020Y395222D03*
X80948Y525513D03*
Y521613D03*
X80318Y543313D03*
Y539413D03*
X80915Y767400D03*
X80784Y771366D03*
X68354Y1314097D03*
X80378Y1406676D03*
X83441Y1430500D03*
X81052Y1427410D03*
X81132Y1424195D03*
X79055Y1434000D03*
X73820Y1442893D03*
X81401Y1436105D03*
X73820Y1445945D03*
X73757Y1448500D03*
X81822Y1477075D03*
X77883Y1491440D03*
X80932D03*
X80852Y1488638D03*
X75245Y1491440D03*
X81822Y1480075D03*
Y1483075D03*
Y1486075D03*
X72396Y1491290D03*
X72390Y1499211D03*
X77883Y1499240D03*
X80833D03*
X77883Y1494040D03*
Y1496640D03*
X80932Y1494040D03*
Y1496640D03*
X75245Y1499240D03*
Y1494040D03*
Y1496640D03*
X72396Y1493890D03*
Y1496490D03*
X77920Y1538245D03*
X75796Y1545669D03*
X75396Y1542369D03*
X78796Y1545669D03*
X78096Y1542444D03*
X78372Y1556416D03*
Y1558916D03*
X78522Y1562641D03*
Y1565141D03*
Y1567888D03*
X78403Y1580311D03*
X81103D03*
X78522Y1570388D03*
X81468Y1570285D03*
X68133Y1587896D03*
X81006Y1593265D03*
X72660Y1587365D03*
X72375Y1604365D03*
X74133Y1610896D03*
X70567Y1625603D03*
X72255Y1616730D03*
X74134Y1621396D03*
X75380Y1627622D03*
X75764Y1636993D03*
X79164Y1636992D03*
X77427Y1644410D03*
X82127Y1687362D03*
X82500Y1698511D03*
Y1706511D03*
X82000Y1716331D03*
X82500Y1720331D03*
X82000Y1724331D03*
X94157Y75340D03*
X83157Y69340D03*
X97557Y75340D03*
X86557Y69340D03*
X92197Y143853D03*
X87137Y143663D03*
X93775Y197241D03*
Y212241D03*
Y207241D03*
Y202241D03*
X87520Y382219D03*
Y391391D03*
Y395865D03*
X90225Y610351D03*
X84057Y599372D03*
X84038Y602233D03*
X90225Y614351D03*
Y618351D03*
Y622351D03*
X94474Y766871D03*
X95790Y1278014D03*
X82953Y1307607D03*
X83023Y1311607D03*
X97546Y1385912D03*
X85736Y1391597D03*
X86827Y1404080D03*
X93000Y1417000D03*
Y1408000D03*
X93069Y1412500D03*
X85103Y1433051D03*
X93000Y1426000D03*
X97800Y1433000D03*
X93000Y1421500D03*
Y1444500D03*
Y1448500D03*
X84500Y1444500D03*
Y1448500D03*
X88722Y1476741D03*
X89092Y1491106D03*
X89042Y1488506D03*
X83991Y1491440D03*
X83892Y1488840D03*
X88722Y1479741D03*
Y1482741D03*
Y1485741D03*
X83892Y1499140D03*
X83991Y1494040D03*
Y1496540D03*
X84051Y1501690D03*
X83796Y1533746D03*
X83811Y1537296D03*
X91511Y1552296D03*
X93296Y1549142D03*
X97018Y1546331D03*
X88511Y1552296D03*
X83121Y1542294D03*
X94786Y1574205D03*
Y1576705D03*
X97486Y1574205D03*
Y1576705D03*
X83603Y1580311D03*
X84093Y1570285D03*
X90675Y1590783D03*
X96124Y1593458D03*
Y1595958D03*
X93424Y1593458D03*
X90675Y1593283D03*
X93424Y1595958D03*
X90675Y1595783D03*
X93537Y1598506D03*
X96237D03*
X90649Y1598507D03*
X84833Y1611896D03*
X90892Y1654749D03*
X85836Y1655143D03*
Y1658543D03*
X87891Y1671121D03*
Y1674521D03*
X90127Y1687362D03*
X96101Y1696469D03*
X82945Y1702511D03*
X95342Y1713741D03*
X96555Y1705508D03*
X95400Y1719741D03*
X95460Y1725241D03*
X105157Y69340D03*
X108557D03*
X101679Y151191D03*
X101675Y160694D03*
X100818Y165506D03*
Y168906D03*
X110616Y767400D03*
X110485Y771366D03*
X105165Y1300380D03*
Y1302880D03*
X107665D03*
Y1300380D03*
X102665Y1302880D03*
Y1300380D03*
X105165Y1305380D03*
X107665D03*
X102665D03*
Y1307880D03*
Y1310380D03*
Y1312880D03*
X105165Y1307880D03*
Y1310380D03*
Y1312880D03*
X107665D03*
Y1310380D03*
Y1307880D03*
X105165Y1315380D03*
X107665D03*
X105165Y1317880D03*
X107665D03*
X102665D03*
Y1315380D03*
X98101Y1369018D03*
Y1371559D03*
X104863Y1382593D03*
X99594Y1379933D03*
X104863Y1380085D03*
X112305Y1382130D03*
X108817Y1380530D03*
X111555Y1379562D03*
X101874Y1376408D03*
X111600Y1403100D03*
X113500Y1398600D03*
X110000Y1407425D03*
X110075Y1410500D03*
X101637Y1432938D03*
X102076Y1427833D03*
X101955Y1448660D03*
X101500Y1436000D03*
X102398Y1440000D03*
X113500Y1455600D03*
X112481Y1452424D03*
X112100Y1467500D03*
X103571Y1476485D03*
X103555Y1485128D03*
Y1479128D03*
Y1482128D03*
X109733Y1491367D03*
X110605Y1487896D03*
X104184Y1491292D03*
X106784D03*
X105453Y1487893D03*
X108053D03*
X102931Y1488097D03*
X101584Y1491292D03*
X106396Y1485113D03*
X108996D03*
X106371Y1482181D03*
X108971D03*
X107197Y1501756D03*
X109712Y1499196D03*
X104616Y1501811D03*
X107112Y1499196D03*
X109733Y1493967D03*
Y1496567D03*
X106784Y1493892D03*
Y1496492D03*
X101634D03*
X104512Y1499196D03*
X104184Y1496492D03*
Y1493892D03*
X101534Y1499244D03*
X101634Y1493992D03*
X101835Y1501863D03*
X109878Y1501879D03*
X102011Y1550242D03*
X99818Y1546296D03*
X111196Y1542569D03*
X111901Y1545543D03*
X112418Y1555680D03*
X112339Y1565015D03*
Y1562515D03*
X112418Y1558180D03*
X99986Y1574205D03*
Y1576705D03*
X108555Y1574657D03*
Y1577462D03*
X98824Y1593558D03*
X101524D03*
X98824Y1596058D03*
X101524D03*
X101637Y1598606D03*
X98937D03*
X112353Y1646612D03*
X110378Y1670313D03*
X99443Y1661931D03*
Y1658531D03*
X110378Y1674313D03*
X100443Y1684063D03*
Y1687463D03*
X107500Y1707450D03*
X116157Y75340D03*
X127153Y69343D03*
X119557Y75340D03*
X115016Y300281D03*
Y320715D03*
X118407Y526766D03*
X113042Y686285D03*
X113980Y717480D03*
X116480D03*
X118980D03*
X121480D03*
X123980D03*
X113980Y714980D03*
X116480D03*
X118980D03*
X121480D03*
X123980D03*
X116480Y722480D03*
X118980D03*
X121480D03*
X123980D03*
X113980Y719980D03*
X116480D03*
X118980D03*
X121480D03*
X123980D03*
X113980Y722480D03*
X124174Y766871D03*
X120965Y1307880D03*
Y1310380D03*
Y1312880D03*
X118465D03*
Y1310380D03*
Y1307880D03*
Y1300380D03*
X123465Y1302880D03*
Y1300380D03*
X120965Y1305380D03*
X118465D03*
X123465D03*
Y1307880D03*
Y1310380D03*
Y1312880D03*
X120965Y1300380D03*
Y1302880D03*
X118465D03*
X120965Y1315380D03*
X118465D03*
X120965Y1317880D03*
X118465D03*
X123465D03*
Y1315380D03*
X121207Y1363643D03*
X115321Y1372872D03*
X120181D03*
X117751D03*
X121241Y1367047D03*
Y1369947D03*
X127211Y1373177D03*
Y1378977D03*
X125111Y1377577D03*
X122945Y1379207D03*
X127211Y1376077D03*
X125011Y1374577D03*
X122945Y1376307D03*
X122050Y1403750D03*
X129200Y1401000D03*
X124700D03*
X126000Y1414000D03*
Y1418000D03*
X116700Y1415700D03*
Y1410500D03*
X120700Y1408100D03*
X116900Y1449000D03*
X113600Y1449100D03*
X116122Y1458000D03*
X119100Y1460300D03*
X124600Y1465100D03*
X121500Y1467400D03*
X113100Y1537346D03*
X114030Y1542419D03*
X114610Y1545543D03*
X121705Y1619460D03*
X114618Y1624541D03*
X117655Y1621766D03*
X118956Y1635244D03*
X124312Y1633488D03*
X126717Y1635893D03*
X126428Y1658587D03*
X126760Y1682383D03*
X123353Y1695941D03*
X127353Y1696062D03*
X127710Y1700166D03*
X127290Y1705666D03*
X125183Y1716741D03*
X127168Y1721695D03*
X129020Y1726741D03*
X138157Y75340D03*
X141557D03*
X130553Y69343D03*
X140360Y430160D03*
X141642Y488684D03*
Y494147D03*
X139980Y507420D03*
X139890Y503440D03*
X140471Y670445D03*
X131752Y668506D03*
X134902D03*
X140600Y683029D03*
X131752Y686074D03*
X134902D03*
X131960Y679290D03*
X140317Y767400D03*
Y771200D03*
X140265Y1307880D03*
Y1310380D03*
Y1312880D03*
X137765D03*
Y1310380D03*
Y1307880D03*
X135265Y1312880D03*
Y1310380D03*
Y1307880D03*
Y1305380D03*
X140265D03*
X137765D03*
X135265Y1300380D03*
Y1302880D03*
X140265Y1300380D03*
Y1302880D03*
X137765D03*
Y1300380D03*
X140265Y1315380D03*
X137765D03*
X135265D03*
Y1317880D03*
X140265D03*
X137765D03*
X130701Y1369018D03*
Y1371559D03*
X137463Y1382593D03*
X132194Y1379933D03*
X137463Y1380085D03*
X141417Y1380530D03*
X134474Y1376408D03*
X138000Y1400600D03*
X134800Y1408100D03*
X142000Y1414500D03*
X136000Y1432000D03*
X141500Y1433500D03*
Y1429500D03*
X139500Y1446000D03*
X133100Y1444100D03*
X138013Y1440487D03*
X141514Y1436500D03*
X128661Y1464000D03*
X139802Y1556133D03*
X129070Y1608338D03*
X137386Y1626412D03*
X135543Y1637055D03*
X132353Y1646612D03*
X136353D03*
X142465Y1662493D03*
X143000Y1701011D03*
X142293Y1705166D03*
X129493Y1711846D03*
X143000Y1709166D03*
X135722Y1715672D03*
X147920Y28261D03*
X148780Y48720D03*
X149153Y69343D03*
X152553D03*
X149231Y224204D03*
X148228Y216118D03*
X158380Y419760D03*
X147450Y423860D03*
X154770Y441830D03*
X147810Y475710D03*
X146982Y521997D03*
Y530997D03*
X159513Y674855D03*
X152822Y665500D03*
X153875Y766871D03*
X151065Y1307880D03*
Y1310380D03*
Y1312880D03*
X153565D03*
Y1310380D03*
Y1307880D03*
X156065Y1312880D03*
Y1310380D03*
Y1307880D03*
Y1305380D03*
X151065D03*
X153565D03*
X156065Y1300380D03*
Y1302880D03*
X151065Y1300380D03*
Y1302880D03*
X153565D03*
Y1300380D03*
X151065Y1315380D03*
X153565D03*
X156065D03*
Y1317880D03*
X151065D03*
X153565D03*
X152781Y1372872D03*
X150351D03*
X147921D03*
X153741Y1369977D03*
Y1367077D03*
X144905Y1382130D03*
X144155Y1379562D03*
X155545Y1379207D03*
Y1376307D03*
X145000Y1414425D03*
X150900Y1425500D03*
X154443Y1441195D03*
X156174Y1435396D03*
X156477Y1447733D03*
X154083Y1456007D03*
X148340Y1454674D03*
X154671Y1450019D03*
X154305Y1453101D03*
X159000Y1525480D03*
X155618Y1549331D03*
X155071Y1543604D03*
X152843Y1559146D03*
Y1562666D03*
X146453Y1614879D03*
X149171Y1616759D03*
X142576Y1640163D03*
X152353Y1646612D03*
X142576Y1643563D03*
X154111Y1663933D03*
X154010Y1676811D03*
X157410D03*
X143778Y1685087D03*
X147253Y1696343D03*
X155353Y1687843D03*
X159427Y1696652D03*
X152605Y1715941D03*
X149338Y1705603D03*
X156825Y1705510D03*
X146000Y1718241D03*
X146086Y1705603D03*
X145267Y1722241D03*
X152496Y1722941D03*
X146483Y1725636D03*
X155260Y1723682D03*
X161361Y75340D03*
X164761D03*
X162830Y396930D03*
X172120Y412350D03*
X172010Y474900D03*
X166760Y506880D03*
X166670Y502900D03*
X163372Y670863D03*
X172725Y667898D03*
X162482Y679319D03*
X161735Y684456D03*
X172725Y679230D03*
X169987Y767666D03*
Y771266D03*
X170265Y1312880D03*
Y1310380D03*
Y1307880D03*
X167765Y1312880D03*
Y1310380D03*
Y1307880D03*
Y1305380D03*
X170265D03*
X167765Y1300380D03*
Y1302880D03*
X170265D03*
Y1300380D03*
Y1315380D03*
X167765D03*
Y1317880D03*
X170265D03*
X163401Y1369018D03*
Y1371559D03*
X159811Y1373177D03*
X170163Y1382593D03*
X164894Y1379933D03*
X170163Y1380085D03*
X167174Y1376408D03*
X159811Y1378977D03*
Y1376077D03*
X157711Y1377577D03*
X157611Y1374577D03*
X163099Y1414400D03*
X162873Y1411611D03*
X163061Y1409048D03*
Y1406548D03*
X160684Y1441046D03*
X158704Y1439411D03*
X161210Y1443542D03*
X163271Y1441588D03*
X169351Y1462595D03*
X163148Y1474504D03*
X163113Y1483590D03*
Y1480190D03*
X172180Y1490210D03*
X172070Y1495550D03*
X163460Y1491010D03*
X163113Y1501990D03*
Y1505390D03*
X163320Y1494340D03*
X161188Y1510800D03*
X162188Y1518040D03*
X162531Y1523331D03*
Y1526731D03*
X167666Y1550751D03*
X165166D03*
X162666D03*
X170166D03*
X170230Y1542960D03*
X160150Y1553251D03*
Y1555751D03*
X162666D03*
X165166D03*
X167666D03*
X170166D03*
Y1553251D03*
X167666D03*
X165166D03*
X162666D03*
X170166Y1567621D03*
X167666D03*
X165166D03*
X162666D03*
X170166Y1565121D03*
X167666D03*
X165166D03*
X162666D03*
Y1562621D03*
X165166D03*
X167666D03*
X170166D03*
X162466Y1570121D03*
X164966D03*
X167466D03*
X169966D03*
X157511Y1663933D03*
X165491Y1665582D03*
Y1662182D03*
X165336Y1675077D03*
Y1678477D03*
X162740Y1713172D03*
Y1704885D03*
X166467Y1720973D03*
X171925Y1717984D03*
X171945Y1730693D03*
X162740Y1723886D03*
X183357Y75343D03*
X172361Y69340D03*
X186757Y75343D03*
X175761Y69340D03*
X184930Y125502D03*
X181025Y159123D03*
X183890Y388180D03*
X174320Y395040D03*
X189290Y396730D03*
X177675Y419260D03*
X185160Y419220D03*
X181550Y441290D03*
X182500Y672500D03*
X172500Y684799D03*
X183576Y766871D03*
X183565Y1310380D03*
Y1312880D03*
X186065D03*
Y1310380D03*
Y1307880D03*
X172765D03*
Y1310380D03*
Y1312880D03*
X183565Y1307880D03*
Y1305380D03*
X186065D03*
X183565Y1300380D03*
Y1302880D03*
X186065D03*
Y1300380D03*
X172765Y1305380D03*
Y1300380D03*
Y1302880D03*
Y1315380D03*
X183565D03*
X186065D03*
X183565Y1317880D03*
X186065D03*
X172765D03*
X185481Y1372872D03*
X183051D03*
X180621D03*
X186481Y1370147D03*
Y1367247D03*
X177605Y1382130D03*
X174117Y1380530D03*
X176855Y1379562D03*
X185558Y1418560D03*
Y1416060D03*
X183058Y1418560D03*
Y1416060D03*
X173164Y1406397D03*
Y1408897D03*
X172976Y1411460D03*
X173202Y1414249D03*
X185558Y1421060D03*
Y1423560D03*
Y1426060D03*
X183058Y1421060D03*
Y1426060D03*
Y1423560D03*
Y1428560D03*
X185558D03*
X172751Y1462595D03*
X179451Y1452895D03*
X176051D03*
X173490Y1542540D03*
X173050Y1555751D03*
Y1553251D03*
X178582Y1575390D03*
X181087Y1576135D03*
X178582Y1572490D03*
Y1569590D03*
X180292Y1582589D03*
X177792D03*
X177509Y1653825D03*
X177666Y1649223D03*
X183974Y1656804D03*
X183920Y1653973D03*
X184139Y1651088D03*
X180103Y1668921D03*
X177672Y1657538D03*
X183986Y1659548D03*
X182533Y1676854D03*
X185124Y1701851D03*
X185084Y1691988D03*
X179999Y1699156D03*
X185173Y1695138D03*
X178385Y1715441D03*
X183813Y1705404D03*
X178376Y1720559D03*
X185760Y1731666D03*
X194361Y69340D03*
X197761D03*
X204088Y138912D03*
X200577Y125502D03*
X190000Y143000D03*
X191264Y147768D03*
X193610Y153951D03*
X192592Y353072D03*
X188055Y731734D03*
X199718Y767400D03*
X197651Y769241D03*
X200365Y1312880D03*
Y1310380D03*
Y1307880D03*
Y1305380D03*
Y1300380D03*
Y1302880D03*
X188565Y1312880D03*
Y1310380D03*
Y1307880D03*
Y1305380D03*
Y1300380D03*
Y1302880D03*
X200365Y1315380D03*
Y1317880D03*
X188565Y1315380D03*
Y1317880D03*
X196301Y1369018D03*
Y1371559D03*
X192511Y1373177D03*
X197794Y1379933D03*
X200074Y1376408D03*
X188245Y1379207D03*
X190411Y1377577D03*
X192511Y1378977D03*
X190311Y1374577D03*
X188245Y1376307D03*
X192511Y1376077D03*
X200408Y1416249D03*
Y1418749D03*
X192983Y1417568D03*
X188058Y1416060D03*
Y1418560D03*
X190483Y1417568D03*
X197983D03*
X195483D03*
X188695Y1404813D03*
Y1407313D03*
X191995Y1404813D03*
Y1407313D03*
X194495Y1404813D03*
Y1407313D03*
X196995Y1404813D03*
Y1407313D03*
X199495Y1404813D03*
Y1407313D03*
X188507Y1409876D03*
X191807D03*
X194307D03*
X196807D03*
X199307D03*
X200558Y1421551D03*
X195483Y1420068D03*
X192983D03*
X195483Y1422568D03*
X197983D03*
X192983D03*
X188058Y1421060D03*
Y1423560D03*
X190483Y1420068D03*
Y1422568D03*
X197983Y1420068D03*
X188058Y1426060D03*
X199551Y1462595D03*
X196151D03*
X192851Y1472295D03*
X189451D03*
X193679Y1640052D03*
Y1643452D03*
X198698Y1662215D03*
X199747Y1675603D03*
X200424Y1686870D03*
X197780Y1696973D03*
X200478Y1701758D03*
X200448Y1690771D03*
X202076Y1717845D03*
X189760Y1713061D03*
X193274Y1709769D03*
X199843Y1709837D03*
X203510Y1712441D03*
X196763Y1710444D03*
X189760Y1723041D03*
Y1731564D03*
X194000Y1720551D03*
X203655Y1723000D03*
X198760Y1719991D03*
X216491Y69343D03*
X205495Y75340D03*
X208895D03*
X217687Y522453D03*
X214999Y585668D03*
X211254Y595145D03*
X208254D03*
X211009Y610001D03*
X208009D03*
X214202Y606943D03*
X208254Y603245D03*
X211254D03*
X214202Y609681D03*
X208326Y606918D03*
X211326D03*
X210199Y714074D03*
X206199D03*
X206254Y732537D03*
X206933Y737277D03*
X208818Y766871D03*
X205365Y1307880D03*
Y1310380D03*
Y1312880D03*
X202865D03*
Y1310380D03*
Y1307880D03*
X216165D03*
Y1310380D03*
Y1312880D03*
Y1305380D03*
Y1300380D03*
Y1302880D03*
X205365Y1305380D03*
X202865D03*
X205365Y1300380D03*
Y1302880D03*
X202865D03*
Y1300380D03*
X205365Y1315380D03*
X202865D03*
X216165D03*
Y1317880D03*
X205365D03*
X202865D03*
X213521Y1372872D03*
X215951D03*
X203063Y1382593D03*
Y1380085D03*
X210505Y1382130D03*
X207017Y1380530D03*
X209755Y1379562D03*
X205558Y1418560D03*
Y1416060D03*
X202945Y1415910D03*
Y1418410D03*
X208058Y1416060D03*
X208061Y1418605D03*
X206251Y1452895D03*
X202851D03*
X216251Y1472295D03*
X205479Y1652130D03*
Y1648730D03*
X206788Y1660960D03*
X210833Y1660867D03*
X210217Y1668603D03*
X207807Y1681302D03*
Y1696409D03*
X211862Y1701100D03*
X212365Y1705403D03*
X211000Y1717675D03*
X229131Y26477D03*
X225731D03*
X229127Y50649D03*
X225727D03*
X227495Y75340D03*
X230895D03*
X219891Y69343D03*
X233284Y137195D03*
X221051Y153167D03*
X223687Y522453D03*
X229687D03*
X226599Y570970D03*
X217999Y585668D03*
X223999D03*
X220999D03*
X217202Y606943D03*
X220202D03*
X223202D03*
X223111Y603782D03*
X225895Y609691D03*
X228895D03*
X220111Y603782D03*
X217202Y609681D03*
X220202D03*
X223202D03*
X218024Y622385D03*
X221024D03*
X224024D03*
X227024D03*
X221024Y632385D03*
X218024D03*
X224024D03*
X227024D03*
X224157Y715915D03*
Y712915D03*
X229263Y765863D03*
X229275Y769292D03*
X218665Y1312880D03*
Y1310380D03*
Y1307880D03*
X221165Y1312880D03*
Y1310380D03*
Y1307880D03*
Y1305380D03*
X218665D03*
X221165Y1300380D03*
Y1302880D03*
X218665D03*
Y1300380D03*
Y1315380D03*
X221165D03*
Y1317880D03*
X218665D03*
X229101Y1369018D03*
Y1371559D03*
X218381Y1372872D03*
X219401Y1370067D03*
Y1367167D03*
X225411Y1373177D03*
X230594Y1379933D03*
X225411Y1378977D03*
Y1376077D03*
X221145Y1379207D03*
X223311Y1377577D03*
X223211Y1374577D03*
X221145Y1376307D03*
X226351Y1462595D03*
X222951D03*
X229651Y1452895D03*
X219651Y1472295D03*
X238059Y26235D03*
X233335Y17665D03*
X235697Y21585D03*
X241306Y20325D03*
X246356Y26855D03*
X246506Y20365D03*
X242216Y39365D03*
X246216D03*
X238059Y37165D03*
X235697Y39755D03*
X248816Y48965D03*
X239816Y54365D03*
X248487Y68690D03*
X242920Y67915D03*
X238846Y72977D03*
X235186Y98067D03*
X234331Y103286D03*
X232529Y114830D03*
X238297Y121555D03*
X244818Y111546D03*
Y115546D03*
X235460Y115790D03*
X235186Y112022D03*
X238600Y130400D03*
X235147Y124435D03*
X243813Y132383D03*
X241271Y130719D03*
X234000Y148000D03*
X239988Y141986D03*
X236104Y151996D03*
X245486Y159705D03*
X234628Y166735D03*
X240413Y360867D03*
X233413D03*
X235913D03*
X243845Y656940D03*
X246045Y655540D03*
X243845Y651140D03*
Y654040D03*
X245945Y652540D03*
X232981Y743983D03*
X240200Y766300D03*
X246371Y772388D03*
X232965Y1297880D03*
X237965D03*
X235465D03*
Y1300380D03*
Y1302880D03*
X237965D03*
Y1300380D03*
X235465Y1305380D03*
X237965D03*
X232965Y1302880D03*
Y1300380D03*
Y1305380D03*
Y1307880D03*
Y1310380D03*
Y1312880D03*
X237965Y1307880D03*
Y1310380D03*
Y1312880D03*
X235465D03*
Y1310380D03*
Y1307880D03*
X237965Y1315380D03*
X235465D03*
X232965D03*
X246321Y1372872D03*
X235863Y1380085D03*
X243305Y1382130D03*
X239817Y1380530D03*
X242555Y1379562D03*
X235863Y1382593D03*
X232874Y1376408D03*
X233051Y1452895D03*
X246451Y1472295D03*
X243051D03*
X255106Y16615D03*
X251106Y12615D03*
X250216Y39365D03*
X254046Y39425D03*
X259316Y48965D03*
X261016Y51565D03*
X252316Y48965D03*
X255816D03*
X254016Y51565D03*
X250516D03*
X257516D03*
X247893Y100546D03*
X248093Y92146D03*
X261416Y100665D03*
X253874Y111774D03*
X252800Y114800D03*
X256586Y138373D03*
X260596Y151065D03*
X248350Y165700D03*
X257252Y156730D03*
X258439Y214000D03*
X247859Y375389D03*
X250359D03*
X254859D03*
X247694Y378523D03*
X250194D03*
X254694D03*
X258751Y647987D03*
X262239Y649587D03*
X259501Y650555D03*
X255735Y657245D03*
X253305D03*
X250875D03*
X248111Y653810D03*
Y650910D03*
X250312Y663080D03*
Y660180D03*
X247587Y714760D03*
Y717260D03*
X252591Y714737D03*
Y717237D03*
X250091D03*
Y714737D03*
X247587Y712237D03*
X250087D03*
X252587D03*
X247587Y719760D03*
X252591Y719737D03*
X250091D03*
X247587Y724760D03*
X252587D03*
X250087D03*
X247587Y722260D03*
Y727260D03*
X250087Y729760D03*
X247587D03*
X250087Y727260D03*
X252587D03*
Y729760D03*
X252591Y722237D03*
X250091D03*
X254671Y776388D03*
X257071Y772770D03*
X260971Y777988D03*
X248765Y1297880D03*
X251265D03*
X248765Y1292880D03*
Y1295380D03*
X251265D03*
Y1292880D03*
X248765Y1307880D03*
Y1310380D03*
Y1312880D03*
X251265D03*
Y1310380D03*
Y1307880D03*
X248765Y1305380D03*
X251265D03*
X248765Y1300380D03*
Y1302880D03*
X251265D03*
Y1300380D03*
X248765Y1315380D03*
X251265D03*
Y1317880D03*
X248765D03*
X248751Y1372872D03*
X251181D03*
X252211Y1370232D03*
Y1367332D03*
X258211Y1373177D03*
X256111Y1377577D03*
X258211Y1378977D03*
X256011Y1374577D03*
X258211Y1376077D03*
X253945Y1379207D03*
Y1376307D03*
X253151Y1462595D03*
X259851Y1452895D03*
X249751Y1462595D03*
X256451Y1452895D03*
X261530Y1550300D03*
X275116Y28565D03*
X275896Y48875D03*
X266420Y39120D03*
X265365Y49171D03*
X263516Y51565D03*
X261816Y48965D03*
X263182Y73396D03*
X269860Y72741D03*
X262893Y77529D03*
Y80029D03*
X263316Y87665D03*
X275238Y83024D03*
X264916Y100665D03*
X268416D03*
X262916Y97965D03*
X266416D03*
X269916D03*
X273616Y96665D03*
X264293Y120972D03*
X269487Y121095D03*
X275793Y120248D03*
X266000Y125800D03*
X275793Y129595D03*
X266971Y140110D03*
X264574Y151206D03*
X276821Y140465D03*
X270178Y140322D03*
X262500Y161100D03*
X273500Y207500D03*
X266360Y203070D03*
X269925Y217700D03*
X274993Y522052D03*
X269568Y522366D03*
X266327Y522456D03*
X274096Y574698D03*
X273208Y588237D03*
X267601Y608378D03*
X271462Y650184D03*
X266193Y650032D03*
X272955Y658558D03*
X266193Y647524D03*
X269182Y653709D03*
X272955Y661099D03*
X276575Y685381D03*
Y688281D03*
Y691181D03*
X265891Y714737D03*
Y717237D03*
X263391D03*
Y714737D03*
X263387Y712237D03*
X265887D03*
X265891Y719737D03*
X263391D03*
X265787Y724760D03*
X263287D03*
X265787Y727260D03*
X263287D03*
X265787Y729760D03*
X263287D03*
X265787Y732260D03*
X263287D03*
X265891Y722237D03*
X263391D03*
X265787Y737260D03*
X263287D03*
X265787Y734760D03*
X263287D03*
X271161Y780588D03*
X268991Y783248D03*
X271245Y785474D03*
X274282Y786741D03*
X272054Y801112D03*
X270850Y797605D03*
X272165Y1256716D03*
X269665Y1259216D03*
X272165D03*
X269765Y1269234D03*
X272265D03*
X269765Y1261734D03*
Y1264234D03*
Y1266734D03*
X272265D03*
Y1264234D03*
Y1261734D03*
X267179Y1269273D03*
Y1266773D03*
Y1264273D03*
Y1261773D03*
Y1271773D03*
X269679D03*
X272179D03*
X262701Y1322872D03*
Y1325413D03*
X264194Y1333787D03*
X269463Y1333939D03*
X273417Y1334384D03*
X276155Y1333416D03*
X269463Y1336447D03*
X266474Y1330262D03*
X269851Y1452895D03*
X273251D03*
X269829Y1521436D03*
X273597Y1519845D03*
X269144Y1511953D03*
X273474Y1516120D03*
Y1512220D03*
X269144Y1514453D03*
Y1516953D03*
X267322Y1519250D03*
X276624Y1516120D03*
Y1512220D03*
X276637Y1521436D03*
X274546Y1549295D03*
Y1546795D03*
X267297Y1546119D03*
X286996Y20365D03*
X290795Y28365D03*
X284228Y25935D03*
X280828D03*
X282716Y40020D03*
X290716D03*
X287988Y54893D03*
X291379Y55746D03*
X293157Y50525D03*
X284226Y50649D03*
X280826D03*
X278638Y83024D03*
X288553Y105006D03*
X285353D03*
X280853Y109906D03*
X282853Y115606D03*
X285853D03*
X280853Y107306D03*
X286996Y139865D03*
X283049Y139731D03*
X288000Y209000D03*
X290000Y222575D03*
X289163Y212503D03*
X278425Y230925D03*
X289393Y498960D03*
X278547Y523041D03*
X284018Y522300D03*
X287723Y548499D03*
X289421Y575098D03*
X291481Y682228D03*
X280841Y688051D03*
X278675Y686781D03*
X280841Y685151D03*
X288465Y691493D03*
X283605D03*
X286035D03*
X278775Y689781D03*
X283042Y697280D03*
Y694380D03*
X285317Y746478D03*
X282817D03*
X280317D03*
Y759110D03*
X285317D03*
X282817D03*
X285317Y761610D03*
X285321Y748978D03*
Y751478D03*
Y753978D03*
X282821D03*
Y751478D03*
Y748978D03*
X285321Y756478D03*
X282821D03*
X280317Y756610D03*
Y751610D03*
Y754110D03*
Y749110D03*
Y761610D03*
X282817D03*
X284035Y796850D03*
X285258Y799314D03*
X282323Y794867D03*
X281449Y809609D03*
X283987Y811342D03*
X285565Y1246716D03*
X288065D03*
X283065D03*
X288065Y1251716D03*
X285565D03*
X283065D03*
X288065Y1249216D03*
X285565D03*
X283065D03*
Y1254216D03*
X288065D03*
X285565D03*
X283065Y1269234D03*
X285565D03*
X283065Y1261734D03*
Y1264234D03*
Y1266734D03*
X285565D03*
Y1264234D03*
Y1261734D03*
X283065Y1256716D03*
X285565D03*
X288065D03*
X283065Y1259216D03*
X285565D03*
X288065D03*
Y1266716D03*
Y1264216D03*
Y1261716D03*
Y1269216D03*
X285479Y1271773D03*
X282979D03*
X287979D03*
X284781Y1326726D03*
X282351D03*
X279921D03*
X285891Y1320942D03*
Y1323842D03*
X289611Y1328431D03*
X276905Y1335984D03*
X289711Y1331431D03*
X287545Y1330161D03*
Y1333061D03*
X280621Y1484082D03*
Y1480682D03*
Y1497482D03*
Y1494082D03*
X280088Y1509469D03*
X282588D03*
X279774Y1512220D03*
Y1516120D03*
X284024Y1514576D03*
X279499Y1519845D03*
X284024Y1512076D03*
X290593Y1523331D03*
Y1526731D03*
X291416Y1541795D03*
Y1549295D03*
Y1546795D03*
Y1544295D03*
X285586Y1551844D03*
X288004Y1551099D03*
X290509Y1551844D03*
X288004Y1548199D03*
X284014Y1538682D03*
X286514D03*
X284546Y1549295D03*
Y1546795D03*
Y1541795D03*
Y1544295D03*
X287046D03*
Y1541795D03*
X277046Y1546795D03*
Y1549295D03*
X282046D03*
Y1546795D03*
Y1544295D03*
X279546Y1549295D03*
Y1546795D03*
X282046Y1541795D03*
X300230Y14820D03*
X302606Y26365D03*
X292056Y24475D03*
X295516Y26365D03*
X300244Y28365D03*
X299496Y22865D03*
X304923Y24657D03*
X304968Y28365D03*
X303252Y38199D03*
X298716Y40020D03*
X296337Y55855D03*
X301306Y52485D03*
X298542Y51088D03*
X303711Y50860D03*
X295755Y72800D03*
X301107Y75676D03*
X305820Y73693D03*
X303852Y65042D03*
X306470Y65160D03*
X301780Y82900D03*
X299002Y88700D03*
X307816Y95727D03*
X301179Y112806D03*
Y110006D03*
Y107106D03*
X296478Y149203D03*
X296474Y158706D03*
X292811Y213242D03*
X296283Y242391D03*
X306528Y256528D03*
X297815Y580384D03*
X294299Y577188D03*
X302130Y584160D03*
X304192Y684425D03*
X298923Y684273D03*
X294969Y683828D03*
X292231Y684796D03*
X298923Y681765D03*
X301912Y687950D03*
X305685Y695340D03*
Y692799D03*
X298617Y746478D03*
X296117D03*
X301117D03*
X298621Y753978D03*
X296121D03*
Y751478D03*
Y748978D03*
X298621Y756478D03*
X296121D03*
X301121Y748996D03*
Y751496D03*
Y753996D03*
Y756496D03*
X296117Y759110D03*
Y761610D03*
X301117Y759110D03*
X298617D03*
X301117Y761610D03*
X298617D03*
X298621Y748978D03*
Y751478D03*
X301117Y766610D03*
X296117D03*
Y764110D03*
X301117Y771610D03*
X298617D03*
Y769110D03*
X301117D03*
X296117Y771610D03*
Y769110D03*
X298617Y766610D03*
Y764110D03*
X301117D03*
X305061Y1254131D03*
X300061D03*
X302561D03*
X305061Y1249131D03*
Y1251631D03*
X300061D03*
X302561D03*
X300061Y1249131D03*
X302561D03*
X305061Y1246631D03*
X300061D03*
X302561D03*
X302661Y1269149D03*
X305161D03*
X302661Y1261649D03*
Y1264149D03*
Y1266649D03*
X305161D03*
Y1264149D03*
Y1261649D03*
X300061Y1269131D03*
Y1266631D03*
X305061Y1259131D03*
Y1256631D03*
X300061D03*
Y1259131D03*
Y1261631D03*
Y1264131D03*
X302561Y1256631D03*
Y1259131D03*
X305075Y1271688D03*
X302575D03*
X300075D03*
X295597Y1322844D03*
Y1325385D03*
X291811Y1327031D03*
X297090Y1333759D03*
X302359Y1333911D03*
X306313Y1334356D03*
X302359Y1336419D03*
X299370Y1330234D03*
X291811Y1332831D03*
Y1329931D03*
X294725Y1381612D03*
X294533Y1384401D03*
X305204Y1381461D03*
X305012Y1384250D03*
X294684Y1387040D03*
X305163Y1386889D03*
X294683Y1390281D03*
X305163Y1389678D03*
X295042Y1530596D03*
X296416Y1549295D03*
X293916D03*
Y1546795D03*
X296416D03*
Y1544295D03*
X293916D03*
X296416Y1541795D03*
X293916D03*
X298916D03*
Y1549295D03*
Y1546795D03*
Y1544295D03*
X303041Y1544299D03*
X297323Y1657172D03*
Y1653772D03*
X310396Y50365D03*
X306566Y50225D03*
X323036Y73125D03*
X310455Y75895D03*
X320190Y77648D03*
X314653Y71806D03*
Y68906D03*
X312410Y89060D03*
X322871Y84321D03*
X316982Y89003D03*
X311053Y112806D03*
Y110006D03*
Y107106D03*
X323646Y147120D03*
Y152120D03*
X308240Y148100D03*
X317472Y222262D03*
Y225217D03*
X319970Y228167D03*
X320095Y231810D03*
X319075Y260075D03*
X311749Y440921D03*
X314780Y545716D03*
X322955Y556148D03*
X310445Y700931D03*
X312611Y702301D03*
X321235Y711636D03*
X316375D03*
X318805D03*
X311545Y709931D03*
X310445Y703931D03*
X311445Y706931D03*
X313611Y708201D03*
Y705301D03*
X315912Y717400D03*
Y714500D03*
X313087Y769160D03*
Y771660D03*
Y774160D03*
Y776660D03*
X318091Y769128D03*
Y771628D03*
Y774128D03*
X315591D03*
Y771628D03*
Y769128D03*
X318091Y776628D03*
X315591D03*
X313087Y766628D03*
X315587D03*
X318087D03*
Y791660D03*
X313087D03*
X315587D03*
X318087Y789160D03*
X313087D03*
X315587D03*
Y779160D03*
X313087Y784160D03*
X315587D03*
X313087Y786660D03*
X315587D03*
X313087Y781660D03*
X315587D03*
X313087Y779160D03*
X318087Y786660D03*
Y784160D03*
Y779160D03*
Y781660D03*
X313284Y1218522D03*
Y1215122D03*
X318461Y1254131D03*
X320961D03*
X315961D03*
Y1249131D03*
X318461D03*
X320961D03*
X315961Y1251631D03*
X318461D03*
X320961D03*
X315961Y1246631D03*
X318461D03*
X320961D03*
X315961Y1269149D03*
X318461D03*
X315961Y1261649D03*
Y1264149D03*
Y1266649D03*
X318461D03*
Y1264149D03*
Y1261649D03*
X320961Y1269131D03*
Y1256631D03*
Y1259131D03*
Y1261631D03*
X318461Y1256631D03*
Y1259131D03*
X320961Y1264131D03*
Y1266631D03*
X315961Y1256631D03*
Y1259131D03*
X320875Y1271688D03*
X315875D03*
X318375D03*
X312817Y1326698D03*
X315247D03*
X317677D03*
X318811Y1320902D03*
Y1323802D03*
X309801Y1335956D03*
X309051Y1333388D03*
X320441Y1330133D03*
Y1333033D03*
X307255Y1643750D03*
Y1647150D03*
X323113Y76941D03*
X334339Y162580D03*
X323646Y160120D03*
Y156120D03*
X331780Y182900D03*
X336000Y284000D03*
X324406Y367744D03*
X325816Y543012D03*
X324647Y566086D03*
X334031Y613498D03*
Y610498D03*
X331391D03*
Y613498D03*
X333502Y600019D03*
Y603019D03*
X330109Y602883D03*
Y605883D03*
X334031Y619398D03*
Y616498D03*
X331391D03*
Y619398D03*
X324251Y702378D03*
X331693Y701915D03*
Y704423D03*
X327739Y703978D03*
X325001Y704946D03*
X334682Y708100D03*
X331391Y769128D03*
Y771628D03*
Y774128D03*
X328891D03*
Y771628D03*
Y769128D03*
X331391Y776628D03*
X328891D03*
X333887Y766628D03*
X328887D03*
X331387D03*
X333891Y776646D03*
Y774146D03*
Y771646D03*
Y769146D03*
X333887Y791660D03*
X328887D03*
X331387D03*
X333887Y789160D03*
X328887D03*
X331387D03*
X333887Y779160D03*
Y781660D03*
X331387Y779160D03*
X328887D03*
Y781660D03*
X331387D03*
X333887Y786660D03*
X328887D03*
X331387D03*
X333887Y784160D03*
X328887D03*
X331387D03*
X335465Y1246631D03*
X332965D03*
X335465Y1249131D03*
X332965D03*
X335465Y1251631D03*
X332965D03*
X335465Y1254131D03*
X332965D03*
X335465Y1259131D03*
Y1256631D03*
X332965Y1259131D03*
Y1256631D03*
X335565Y1269149D03*
Y1261649D03*
Y1264149D03*
Y1266649D03*
X332961Y1269188D03*
Y1266688D03*
Y1261688D03*
Y1264188D03*
Y1271688D03*
X335461D03*
X328501Y1322787D03*
Y1325328D03*
X324707Y1327003D03*
X322507Y1328403D03*
X329994Y1333702D03*
X335263Y1333854D03*
Y1336362D03*
X332274Y1330177D03*
X324707Y1332803D03*
X322607Y1331403D03*
X324707Y1329903D03*
X334038Y1373469D03*
X334230Y1370680D03*
X323559Y1373620D03*
X323751Y1370831D03*
X334189Y1376108D03*
X323710Y1376259D03*
X334189Y1378897D03*
X323709Y1379500D03*
X341082Y56308D03*
X340436Y120555D03*
X343446Y131170D03*
X338244Y192264D03*
X344984Y199299D03*
X344106Y222659D03*
X348107Y220420D03*
X341895Y233980D03*
X348645Y229180D03*
X352000Y230643D03*
Y235643D03*
X344034Y282609D03*
X348890Y409120D03*
Y411620D03*
X340337Y496462D03*
X346751Y515376D03*
X351157Y550415D03*
X350566Y541882D03*
X351018Y554896D03*
X351157Y566936D03*
X345521Y564388D03*
X349397Y564459D03*
X351157Y570415D03*
X341500Y574500D03*
X342500Y582500D03*
Y578500D03*
X338420Y574500D03*
X351157Y590415D03*
Y586415D03*
X337031Y607498D03*
Y613498D03*
Y610498D03*
X346031Y607498D03*
X343031D03*
X349031D03*
X346031Y610498D03*
X343031D03*
X349031D03*
X340031Y607498D03*
Y610498D03*
Y613498D03*
X346031Y604498D03*
X343031D03*
X349031D03*
X340031D03*
X343691Y614018D03*
X346191D03*
X348691D03*
X343721Y618348D03*
X346221D03*
X348721D03*
X351191Y614018D03*
X351221Y618348D03*
X340031Y619398D03*
Y616498D03*
X337031Y619398D03*
Y616498D03*
X342675Y640994D03*
X345175D03*
X347675D03*
X350175D03*
X342675Y643494D03*
X345175D03*
X347675D03*
X350175D03*
X342595Y646054D03*
X345095D03*
X347595D03*
X350095D03*
X336962Y704575D03*
X338455Y715490D03*
Y712949D03*
X349435Y711368D03*
X346671Y705033D03*
X344505Y706663D03*
X346671Y707933D03*
X344605Y709663D03*
X342405Y705263D03*
Y708163D03*
Y711063D03*
X348395Y717060D03*
Y714160D03*
X346051Y769058D03*
Y771558D03*
Y774058D03*
Y776558D03*
X351151Y769040D03*
Y771540D03*
Y774040D03*
X348651D03*
Y771540D03*
Y769040D03*
X351151Y776540D03*
X348651D03*
X351147Y766540D03*
X348647D03*
X346147D03*
X346051Y791558D03*
X348551D03*
X351051D03*
X346051Y789058D03*
X348551D03*
X346051Y784058D03*
X348551D03*
X346051Y786558D03*
X348551D03*
X346051Y779058D03*
X348551D03*
X346051Y781558D03*
X348551D03*
X351051Y789058D03*
Y784058D03*
Y786558D03*
Y779058D03*
Y781558D03*
X347107Y1174343D03*
X339278Y1192112D03*
X336778D03*
X347885Y1206426D03*
X339532Y1218605D03*
X349938Y1214563D03*
X337965Y1251631D03*
Y1249131D03*
Y1254131D03*
X348865Y1246631D03*
Y1251631D03*
Y1249131D03*
Y1254131D03*
X337965Y1246631D03*
X348865Y1269149D03*
Y1261649D03*
Y1264149D03*
Y1266649D03*
X338065Y1269149D03*
Y1266649D03*
Y1264149D03*
Y1261649D03*
X337965Y1256631D03*
Y1259131D03*
X348865D03*
Y1256631D03*
X337961Y1271688D03*
X348861D03*
X348151Y1326641D03*
X350581D03*
X345721D03*
X342705Y1335899D03*
X339217Y1334299D03*
X341955Y1333331D03*
X346464Y1380102D03*
X343964D03*
X348964D03*
Y1387602D03*
Y1385102D03*
Y1382602D03*
X343964Y1385102D03*
Y1387602D03*
X346464Y1385102D03*
Y1387602D03*
X343964Y1382602D03*
X346464D03*
X348964Y1390102D03*
X343964D03*
Y1392602D03*
X346464D03*
Y1390102D03*
X343777Y1395166D03*
X346302Y1395242D03*
X348828Y1395392D03*
X349032Y1392675D03*
X361744Y120713D03*
X363621Y127665D03*
X361171Y223114D03*
X358618Y223129D03*
X361171Y220614D03*
X358671D03*
X355910Y223847D03*
X365739Y221871D03*
X365559Y238896D03*
X357925Y304082D03*
X351390Y409120D03*
X353890D03*
Y411620D03*
X351390D03*
X365852Y516466D03*
X365071Y551038D03*
X355100Y544390D03*
X362200Y566750D03*
X364047Y556773D03*
X359200Y566990D03*
X360261Y561044D03*
X359657Y570702D03*
X359157Y574415D03*
X365158Y597546D03*
Y593580D03*
X352031Y607498D03*
Y610498D03*
X355031Y607498D03*
Y613498D03*
Y610498D03*
X352031Y604498D03*
X355031D03*
X361031Y607498D03*
Y613498D03*
Y610498D03*
X358031Y607498D03*
Y613498D03*
Y610498D03*
Y604498D03*
Y619398D03*
Y616498D03*
X355031Y619398D03*
Y616498D03*
X361031Y619398D03*
Y616498D03*
X352675Y640994D03*
Y643494D03*
X355275Y641034D03*
Y643534D03*
X355195Y646094D03*
X352595Y646054D03*
X357311Y702110D03*
X364753Y701647D03*
Y704155D03*
X360799Y703710D03*
X358061Y704678D03*
X351865Y711368D03*
X354295D03*
X364451Y769040D03*
Y771540D03*
Y774040D03*
X361951D03*
Y771540D03*
Y769040D03*
X364451Y776540D03*
X361951D03*
X364447Y766540D03*
X361947D03*
X364451Y791558D03*
X361951D03*
X364451Y786558D03*
Y789058D03*
X361951D03*
Y786558D03*
X364451Y784058D03*
X361951Y781558D03*
X364451Y779058D03*
Y781558D03*
X361951Y779058D03*
Y784058D03*
X361671Y803588D03*
X356671D03*
X351671D03*
X363313Y812088D03*
X359813Y812188D03*
X356313D03*
X352813D03*
X356535Y849708D03*
X364897Y852564D03*
X364821Y861852D03*
X357400Y855982D03*
X356895Y859791D03*
X353281Y859620D03*
X363236Y1199632D03*
X361922Y1206891D03*
X357271Y1208988D03*
X351413Y1210052D03*
X365461Y1254188D03*
Y1251688D03*
Y1249188D03*
Y1246688D03*
X351365Y1246631D03*
X353865D03*
Y1251631D03*
X351365D03*
X353865Y1249131D03*
X351365D03*
X353865Y1254131D03*
X351365D03*
Y1269149D03*
Y1266649D03*
Y1264149D03*
Y1261649D03*
X365461Y1256688D03*
Y1259188D03*
X353865Y1266631D03*
Y1264131D03*
Y1261631D03*
Y1269131D03*
X351365Y1259131D03*
Y1256631D03*
X353865Y1259131D03*
Y1256631D03*
X365561Y1269288D03*
Y1264288D03*
Y1266788D03*
Y1261788D03*
Y1271788D03*
X351361Y1271688D03*
X353861D03*
X361301Y1322987D03*
Y1325528D03*
X351651Y1320942D03*
Y1323842D03*
X357611Y1326946D03*
X355411Y1328346D03*
X362794Y1333902D03*
X365074Y1330377D03*
X353345Y1332976D03*
X357611Y1329846D03*
X353345Y1330076D03*
X355511Y1331346D03*
X357611Y1332746D03*
X356764Y1359296D03*
X354264D03*
X364764D03*
X362264D03*
X359764D03*
X351632Y1359203D03*
X351923Y1364724D03*
X354423D03*
X356923D03*
X359423D03*
X362223D03*
X364723D03*
X351772Y1362085D03*
X354272D03*
X356772D03*
X359272D03*
X362072D03*
X364572D03*
X363964Y1385102D03*
X356464Y1380102D03*
X358964D03*
X361464D03*
X353964D03*
X351464D03*
X363964D03*
Y1382602D03*
X351464Y1385102D03*
X353964D03*
X361464D03*
X356464D03*
X358964D03*
X351464Y1382602D03*
X361464D03*
X358964D03*
X356464D03*
X353964D03*
X352067Y1387665D03*
X354567D03*
X357067D03*
X359567D03*
X363190Y1387527D03*
X365979Y1387641D03*
X352332Y1391886D03*
X354832D03*
X357332D03*
X359832D03*
X363191Y1390292D03*
Y1392792D03*
X365980Y1392906D03*
Y1390406D03*
X363003Y1395393D03*
X365792Y1395507D03*
X352313Y1395223D03*
X359859D03*
X357208D03*
X365493Y1655107D03*
X370888Y155250D03*
X377118Y222229D03*
X380012Y239615D03*
X370327Y228951D03*
X370352Y235455D03*
X366671Y297114D03*
X369171D03*
X369671Y292114D03*
Y294614D03*
X380935Y443386D03*
X375935D03*
X378435D03*
X382184Y466351D03*
X378976Y479226D03*
X379633Y493942D03*
X371962Y524954D03*
X368371Y553038D03*
X371971Y553138D03*
X375410Y552254D03*
X377502Y554193D03*
X380157Y553090D03*
X375271Y542191D03*
X379114Y544866D03*
X368647Y550422D03*
X370271Y555038D03*
X379689Y586040D03*
X368798Y587938D03*
X369271Y600138D03*
X373477Y593338D03*
X378577Y593026D03*
X377577Y590126D03*
X370022Y704307D03*
X371515Y715222D03*
Y712681D03*
X367742Y707832D03*
X379711Y708001D03*
Y705101D03*
X375445Y708231D03*
X377545Y706731D03*
X375445Y705331D03*
X377645Y709731D03*
X375445Y711131D03*
X366951Y769058D03*
Y771558D03*
Y774058D03*
Y776558D03*
X379187Y766428D03*
Y768960D03*
Y771460D03*
Y773960D03*
Y776460D03*
X366947Y766540D03*
X366951Y781558D03*
Y786558D03*
Y789058D03*
Y784058D03*
X379187Y786460D03*
Y783960D03*
Y788960D03*
Y778960D03*
Y781460D03*
X366951Y791558D03*
X379187Y791460D03*
X366951Y779058D03*
X376671Y803588D03*
X371671D03*
X366671D03*
X371999Y819527D03*
X372000Y831797D03*
Y835197D03*
X371999Y822927D03*
X372000Y846427D03*
Y843027D03*
X366864Y857274D03*
X369626Y860717D03*
X370316Y1204673D03*
X367931Y1196981D03*
X376271Y1207488D03*
X380718Y1221906D03*
X379223Y1219527D03*
X372126Y1214455D03*
X368726D03*
X367961Y1254188D03*
Y1251688D03*
Y1249188D03*
Y1246688D03*
X370461Y1254188D03*
Y1249188D03*
Y1251688D03*
Y1246688D03*
X367961Y1256688D03*
Y1259188D03*
X370461D03*
Y1256688D03*
X368061Y1269206D03*
X370561D03*
X368061Y1261706D03*
Y1264206D03*
Y1266706D03*
X370561D03*
Y1264206D03*
Y1261706D03*
Y1271788D03*
X368061D03*
X380951Y1326841D03*
X378521D03*
X368063Y1334054D03*
X375505Y1336099D03*
X372017Y1334499D03*
X374755Y1333531D03*
X368063Y1336562D03*
X368964Y1382602D03*
Y1385102D03*
X366464D03*
X368964Y1380102D03*
X366464D03*
Y1382602D03*
X368542Y1387639D03*
X368543Y1390404D03*
Y1392904D03*
X368355Y1395505D03*
X374432Y1582600D03*
X375050Y1639400D03*
X371823Y1644516D03*
X370533Y1658605D03*
X374962Y1648511D03*
X372953Y1653197D03*
X373330Y1668539D03*
X370369Y1661817D03*
X372449Y1680520D03*
X372395Y1677449D03*
X395048Y121178D03*
X384375Y147365D03*
X386350Y138980D03*
X395590Y147010D03*
X391310Y227871D03*
X389912Y280345D03*
X390881Y284156D03*
X395053Y318125D03*
X383525Y443386D03*
X389784Y476070D03*
X384827Y507057D03*
X397184Y507101D03*
X382184D03*
X388985Y554870D03*
X383071Y553738D03*
X382705Y546433D03*
X395171Y559463D03*
X395669Y563328D03*
X385318Y555238D03*
X394168Y568482D03*
X395157Y573815D03*
X393481Y571239D03*
X387103Y584506D03*
X392471Y596988D03*
X391021Y588788D03*
X390351Y702178D03*
X393839Y703778D03*
X391101Y704746D03*
X382475Y711436D03*
X387335D03*
X384905D03*
X381812Y717060D03*
Y714160D03*
X394987Y766428D03*
X381687D03*
X384187D03*
X394991Y773928D03*
Y771428D03*
Y768928D03*
Y776428D03*
X384191Y768928D03*
Y771428D03*
Y773928D03*
X381691D03*
Y771428D03*
Y768928D03*
X384191Y776428D03*
X381691D03*
X381687Y791460D03*
X384187D03*
X394987Y784060D03*
Y779060D03*
Y781560D03*
Y789060D03*
Y786560D03*
X381687Y778960D03*
Y786460D03*
Y783960D03*
Y788960D03*
Y781460D03*
X384187Y788960D03*
Y786460D03*
Y783960D03*
Y778960D03*
Y781460D03*
X385001Y816927D03*
Y813527D03*
X386381Y1015474D03*
X393861D03*
X386381Y1022560D03*
Y1019017D03*
X393861Y1022560D03*
Y1019017D03*
X390974Y1222849D03*
Y1219449D03*
X388630Y1236747D03*
X381361Y1254188D03*
Y1249188D03*
Y1251688D03*
Y1246688D03*
X383861Y1254188D03*
X386361D03*
X383861Y1249188D03*
X386361D03*
X383861Y1251688D03*
X386361D03*
X383861Y1246688D03*
X386361D03*
X388630Y1240147D03*
X381361Y1269206D03*
X383861D03*
X381361Y1261706D03*
Y1264206D03*
Y1266706D03*
X383861D03*
Y1264206D03*
Y1261706D03*
X381361Y1256688D03*
Y1259188D03*
X386361Y1256688D03*
Y1259188D03*
X383861Y1256688D03*
Y1259188D03*
X386361Y1269288D03*
Y1261788D03*
Y1266788D03*
Y1264288D03*
X381361Y1271788D03*
X386361D03*
X383861D03*
X383381Y1326841D03*
X384481Y1321192D03*
Y1324092D03*
X388211Y1328546D03*
X393883Y1342318D03*
X388311Y1331546D03*
X386145Y1333176D03*
Y1330276D03*
X386611Y1336056D03*
X388771Y1337546D03*
Y1334546D03*
X395376Y1353233D03*
X393883Y1344859D03*
X395384Y1519250D03*
X395359Y1546519D03*
X389290Y1561250D03*
X387939Y1565534D03*
X389276Y1568413D03*
X391526Y1582373D03*
X394521Y1575891D03*
X388784Y1581801D03*
X393005Y1592304D03*
X381711Y1593842D03*
X381607Y1590393D03*
X388445Y1585898D03*
X389333Y1598816D03*
X387805Y1617302D03*
Y1614802D03*
X394824Y1629713D03*
X394000Y1621500D03*
X389824Y1629713D03*
X389000Y1621500D03*
X384824Y1629713D03*
X381350Y1649000D03*
Y1642900D03*
Y1645800D03*
X382115Y1661545D03*
X387324Y1680495D03*
X392324D03*
X382642Y1680979D03*
X385068Y1683502D03*
X410500Y104883D03*
X410400Y107383D03*
X399264Y121144D03*
X400426Y112815D03*
Y116215D03*
X405606Y125815D03*
Y129715D03*
X403141Y148300D03*
X410678Y159140D03*
X408603Y152278D03*
X411299Y212096D03*
X400000Y220300D03*
X411940Y240501D03*
X410000Y304000D03*
X402184Y466469D03*
X410984Y496649D03*
X406184Y507900D03*
X403657Y546915D03*
X408550Y557850D03*
X404871Y567338D03*
X403381Y573516D03*
X410111Y572608D03*
X407543Y577415D03*
Y580490D03*
X408445Y687531D03*
X397793Y701715D03*
X410645Y691931D03*
X410545Y688931D03*
X408445Y690431D03*
Y693331D03*
X403062Y704375D03*
X397793Y704223D03*
X404555Y715290D03*
Y712749D03*
X400782Y707900D03*
X399991Y776560D03*
X397491Y768928D03*
Y771428D03*
Y773928D03*
Y776428D03*
X397487Y766428D03*
X399991Y771560D03*
Y769060D03*
X399987Y766428D03*
X399991Y774060D03*
X397487Y779060D03*
Y781560D03*
Y786560D03*
Y784060D03*
X399991D03*
Y779060D03*
Y781560D03*
X401341Y1015474D03*
Y1019017D03*
Y1022560D03*
X403347Y1266162D03*
Y1268662D03*
X400847Y1266162D03*
X398347D03*
X400847Y1268662D03*
X398347D03*
X403347Y1271162D03*
Y1273662D03*
X400847Y1271162D03*
X398347D03*
X400847Y1273662D03*
X398347D03*
X403347Y1276162D03*
Y1278662D03*
X400847D03*
Y1276162D03*
X398347Y1278662D03*
Y1276162D03*
X398447Y1281262D03*
Y1283762D03*
X400947Y1281180D03*
Y1283680D03*
X403447D03*
Y1281180D03*
X400947Y1288680D03*
X403447D03*
X400947Y1286180D03*
X403447D03*
X398447Y1286262D03*
Y1288762D03*
X398461Y1291319D03*
X403461D03*
X400961D03*
X400645Y1353385D03*
X408087Y1355430D03*
X404599Y1353830D03*
X407337Y1352862D03*
X400645Y1355893D03*
X397656Y1349708D03*
X401536Y1516120D03*
Y1512220D03*
X397206Y1516953D03*
Y1511953D03*
Y1514453D03*
X397891Y1521436D03*
X401659Y1519845D03*
X404686Y1516120D03*
Y1512220D03*
X410650Y1509469D03*
X408150D03*
X407836Y1512220D03*
Y1516120D03*
X407561Y1519845D03*
X404699Y1521436D03*
X410108Y1535680D03*
X408895Y1553644D03*
X405331Y1548928D03*
X410851Y1557434D03*
X407198Y1564990D03*
X401249Y1564422D03*
X405758Y1557900D03*
X402912Y1558011D03*
X396452Y1577738D03*
X403163Y1579357D03*
X403004Y1582457D03*
X408925Y1573805D03*
Y1576805D03*
X404669Y1594317D03*
X403837Y1609056D03*
Y1612456D03*
X399447Y1612609D03*
X399801Y1606376D03*
X406697Y1604207D03*
X408856Y1623435D03*
X400380Y1621500D03*
X405436Y1620268D03*
X406343Y1613847D03*
X405747Y1623350D03*
X404640Y1637425D03*
X397822Y1629615D03*
X409552Y1633606D03*
X405342Y1628611D03*
X404661Y1634139D03*
X412000Y1647177D03*
X403844Y1665769D03*
X405000Y1675000D03*
X397324Y1680495D03*
X409000Y1683500D03*
X424975Y54762D03*
X417025D03*
X416549Y66365D03*
Y71665D03*
X427300Y71300D03*
X419900Y96620D03*
X414100D03*
X424084Y110839D03*
X417486Y124179D03*
Y127579D03*
X424086Y123023D03*
X422890Y136700D03*
X424086Y133265D03*
X412370Y188210D03*
X411610Y223140D03*
X424815Y217646D03*
X422936Y223501D03*
X419299Y212096D03*
X423299D03*
X420115Y230323D03*
Y240501D03*
Y235442D03*
Y226323D03*
X411940Y235442D03*
X412715Y251165D03*
Y258165D03*
Y266165D03*
X419617Y308000D03*
X424151Y453174D03*
X415984Y466392D03*
X424784Y496572D03*
X419984Y508000D03*
X411500Y510800D03*
X412771Y524820D03*
X414402Y544690D03*
X423351Y684378D03*
X424101Y686946D03*
X412711Y687301D03*
X420335Y693636D03*
X415475D03*
X417905D03*
X412711Y690201D03*
X414712Y699440D03*
Y696540D03*
X420158Y748643D03*
X415158Y756175D03*
Y751175D03*
Y753675D03*
X417658Y748643D03*
X415158D03*
Y761175D03*
X420158D03*
X417658D03*
X415158Y758675D03*
X420162Y751143D03*
Y753643D03*
Y756143D03*
X417662D03*
Y753643D03*
Y751143D03*
X420162Y758643D03*
X417662D03*
X415158Y771175D03*
X420158Y763675D03*
Y766175D03*
X417658Y768675D03*
X415158D03*
X417658Y763675D03*
Y766175D03*
X415158Y763675D03*
Y766175D03*
X415318Y1009765D03*
Y1006025D03*
X424873Y1014745D03*
X423811Y1005800D03*
X415318Y1013505D03*
X424873Y1023013D03*
Y1018879D03*
X415318Y1028466D03*
Y1020986D03*
Y1024726D03*
Y1017245D03*
X418918Y1032206D03*
X423811Y1032431D03*
X424024Y1267144D03*
X414247Y1268662D03*
X416747D03*
X419247D03*
X424024Y1269644D03*
Y1272144D03*
X414247Y1281180D03*
Y1283680D03*
X416747D03*
Y1281180D03*
Y1271162D03*
X414247D03*
X416747Y1278662D03*
Y1276162D03*
X419247Y1278662D03*
Y1276162D03*
Y1273662D03*
X416747D03*
X414247Y1278662D03*
Y1276162D03*
Y1273662D03*
X419361Y1283719D03*
Y1281219D03*
X419247Y1271162D03*
X424024Y1274644D03*
X414247Y1288680D03*
X416747D03*
X414247Y1286180D03*
X416747D03*
X419361Y1288719D03*
Y1291219D03*
X414361D03*
X416861D03*
X419361Y1286219D03*
X417063Y1340523D03*
Y1343423D03*
X415963Y1346172D03*
X413533D03*
X411103D03*
X421315Y1354276D03*
Y1351376D03*
X421205Y1348586D03*
Y1345686D03*
X418675Y1352166D03*
Y1349266D03*
X425631Y1517138D03*
X425087Y1510708D03*
X422587D03*
X423131Y1517138D03*
X412086Y1512076D03*
Y1514576D03*
X422557Y1537595D03*
X420057D03*
X417098Y1536411D03*
X418157Y1549295D03*
X423157Y1541795D03*
Y1544295D03*
X415657Y1541795D03*
X418157Y1546795D03*
Y1544295D03*
Y1541795D03*
X415657Y1549295D03*
Y1546795D03*
Y1544295D03*
X420657Y1541795D03*
Y1544295D03*
Y1546795D03*
Y1549295D03*
X417098Y1538911D03*
X424115Y1548199D03*
Y1551099D03*
X421697Y1551844D03*
X421683Y1565312D03*
X421108Y1560235D03*
X424488Y1565400D03*
X413540Y1556646D03*
X424616Y1560086D03*
X414202Y1559396D03*
X421294Y1557729D03*
X419254Y1566828D03*
X427081Y1581620D03*
X421277Y1571923D03*
X413396Y1594597D03*
X410991Y1597002D03*
X425469Y1595433D03*
X422069D03*
X419277Y1600725D03*
X414500Y1639075D03*
X417365Y1627695D03*
X420765D03*
X423500Y1652500D03*
X411448Y1650598D03*
X420000Y1664925D03*
X411500Y1657500D03*
X417000Y1675000D03*
X413000Y1683500D03*
X415500Y1672500D03*
X433673Y73960D03*
X428149Y65016D03*
X431359Y82589D03*
X433997Y166400D03*
X437997D03*
X436103Y158594D03*
X437997Y170701D03*
X433997D03*
X438200Y212096D03*
X431299Y212095D03*
X437440Y237270D03*
X442710Y237990D03*
X435710Y250340D03*
X440710D03*
X426947Y320749D03*
X433277Y471970D03*
X429784Y466315D03*
X426208Y468977D03*
X436226Y475526D03*
X437084Y501865D03*
X429784Y506947D03*
X442084Y511870D03*
X427500Y510553D03*
X426011Y524888D03*
X436062Y686575D03*
X430793Y686423D03*
X426839Y685978D03*
X430793Y683915D03*
X437555Y697490D03*
Y694949D03*
X433782Y690100D03*
X430958Y748643D03*
X433458D03*
X433462Y751143D03*
Y753643D03*
Y756143D03*
X430962D03*
Y753643D03*
Y751143D03*
Y758643D03*
X440159Y970341D03*
Y977841D03*
Y985341D03*
X438359Y993766D03*
X438434Y989766D03*
X438359Y997766D03*
X427551Y1005800D03*
X434716Y1014745D03*
X431291Y1005800D03*
X435031D03*
X438771D03*
X438359Y1001766D03*
X434716Y1018879D03*
Y1023013D03*
X431291Y1032431D03*
X435031D03*
X438771D03*
X427551D03*
X427615Y1282917D03*
Y1275417D03*
Y1280417D03*
Y1277917D03*
X436903Y1285694D03*
Y1289694D03*
X436924Y1462595D03*
X433524D03*
X440224Y1452895D03*
X427286Y1483590D03*
Y1480190D03*
Y1501990D03*
Y1505390D03*
X426704Y1523331D03*
Y1526731D03*
X439935Y1532600D03*
X430027Y1546795D03*
Y1544295D03*
X432527Y1541795D03*
Y1549295D03*
Y1546795D03*
Y1544295D03*
X430027Y1541795D03*
Y1549295D03*
X435027D03*
Y1546795D03*
Y1544295D03*
Y1541795D03*
X427527Y1549295D03*
Y1546795D03*
Y1544295D03*
Y1541795D03*
X426620Y1551844D03*
X437736Y1544392D03*
X431923Y1565790D03*
X432051Y1560635D03*
X437910Y1553910D03*
X433440Y1581700D03*
X429947Y1594398D03*
X436776Y1610394D03*
X430500Y1605835D03*
X431664Y1624342D03*
X436776Y1613794D03*
X433012Y1621612D03*
X430500Y1613709D03*
X434500Y1641500D03*
X431000Y1640500D03*
X432000Y1650000D03*
X436925Y1649500D03*
X441182Y77125D03*
X445267Y82124D03*
X448414Y94684D03*
X445014D03*
X452948Y104003D03*
X445997Y166400D03*
X453997D03*
X449997D03*
X448038Y158659D03*
X441997Y170701D03*
X449997D03*
X448499Y212036D03*
X443299Y212095D03*
X456231Y227764D03*
X443299Y220046D03*
X447299D03*
X456231Y232883D03*
X455422Y244103D03*
X444310Y243370D03*
X446710Y249340D03*
X454518Y280793D03*
X447840Y275970D03*
X441320Y295170D03*
Y301170D03*
Y307170D03*
Y313170D03*
Y316170D03*
X442297Y474442D03*
X453269Y478388D03*
X449496Y474009D03*
X446547Y480123D03*
X443683Y502256D03*
X448024Y505345D03*
X452084Y511870D03*
X447084D03*
X457084D03*
X453723Y526558D03*
X444441Y565549D03*
X450305Y669036D03*
X452735D03*
X447875D03*
X440845Y668731D03*
Y665831D03*
X445111Y662701D03*
X442945Y664331D03*
X440845Y662931D03*
X443045Y667331D03*
X445111Y665601D03*
X447212Y671640D03*
Y674540D03*
X446686Y726660D03*
Y729160D03*
Y731660D03*
X449190Y726528D03*
Y729028D03*
Y731528D03*
X451690D03*
Y729028D03*
Y726528D03*
X446686Y724028D03*
X449186D03*
X451686D03*
Y741660D03*
X449186D03*
Y739160D03*
Y736660D03*
X451686Y739160D03*
Y736660D03*
X446686Y741660D03*
Y736660D03*
Y739160D03*
Y734160D03*
X449190Y734028D03*
X451690D03*
X453810Y1014745D03*
X449992Y1005800D03*
X453732D03*
X443574Y1014745D03*
X446252Y1005800D03*
X442511D03*
X453810Y1023013D03*
X443574D03*
X453810Y1018879D03*
X443574D03*
X453732Y1032431D03*
X442884Y1038766D03*
X442511Y1032431D03*
X442884Y1042766D03*
X446252Y1032431D03*
X449992D03*
X441159Y1051541D03*
X443764Y1179395D03*
X443624Y1452895D03*
X453624Y1472295D03*
X446810Y1565020D03*
X446910Y1562098D03*
X446653Y1573264D03*
X441931Y1581662D03*
X443590Y1593880D03*
X441460Y1596020D03*
X450500Y1612450D03*
X446182Y1625555D03*
X450180Y1614950D03*
X445800Y1633200D03*
Y1636000D03*
X446000Y1650000D03*
X462653Y72525D03*
X462456Y95101D03*
X459056D03*
X470010Y141070D03*
X461997Y166400D03*
X471371Y227764D03*
X461931Y212703D03*
X468574Y213104D03*
X471371Y222764D03*
X464440Y218253D03*
X460567Y225205D03*
Y235442D03*
X460624Y240953D03*
Y230323D03*
X463240Y244980D03*
X456720Y285158D03*
X457248Y280143D03*
Y282643D03*
X470243Y285693D03*
X467545Y356864D03*
X460441Y499842D03*
X457424Y497978D03*
X468638Y514096D03*
X465766Y524991D03*
X458725Y524480D03*
X470331Y566632D03*
X465331D03*
X467831D03*
X462831D03*
X467831Y569132D03*
X470331D03*
X459931Y566632D03*
X457431D03*
X462831Y569132D03*
X457431D03*
X459931D03*
X465331D03*
X470331Y576132D03*
X467831Y571632D03*
X465331D03*
X467831Y576132D03*
X465331D03*
X470331Y571632D03*
X462831D03*
Y576132D03*
X457431Y571632D03*
Y574132D03*
X459931Y571632D03*
Y574132D03*
X457431Y576632D03*
X459931D03*
X462831Y598514D03*
X467831D03*
X470331D03*
X465331D03*
X457711D03*
X460211D03*
X462831Y601014D03*
X467831D03*
X470331D03*
X465331D03*
X457711D03*
X460211D03*
X469955Y672890D03*
X463193Y659315D03*
X468462Y661975D03*
X463193Y661823D03*
X455751Y659778D03*
X459239Y661378D03*
X469955Y670349D03*
X456501Y662346D03*
X466182Y665500D03*
X462490Y731528D03*
Y726528D03*
Y729028D03*
X464990D03*
Y726528D03*
X467486Y724028D03*
X464986D03*
X462486D03*
X467490Y726660D03*
X457472Y1005800D03*
X465965Y1009765D03*
Y1006025D03*
Y1013505D03*
Y1020986D03*
Y1024726D03*
Y1028466D03*
Y1017245D03*
Y1032206D03*
X457472Y1032431D03*
X463724Y1462595D03*
X470424Y1452895D03*
X460324Y1462595D03*
X467024Y1452895D03*
X457024Y1472295D03*
X462215Y1581510D03*
X462753Y1641289D03*
X459500Y1659000D03*
X467500Y1651500D03*
X457000Y1650000D03*
X468075Y1662500D03*
X470463Y1670038D03*
X464925Y1662500D03*
X467500Y1678500D03*
X468575Y1704000D03*
X462500Y1697000D03*
X466000Y1714575D03*
X468575Y1731000D03*
X479400Y90574D03*
Y94574D03*
Y97574D03*
Y110930D03*
X479465Y119644D03*
Y115644D03*
X482255Y133222D03*
Y129822D03*
X479465Y123644D03*
X482380Y141942D03*
X483800Y189400D03*
X480200Y191900D03*
X480700Y208200D03*
X480715Y211099D03*
X471371Y235764D03*
X483227Y233000D03*
X487620Y270400D03*
X479870D03*
X483823Y285893D03*
X474808Y291492D03*
X482893Y291293D03*
X479148Y315502D03*
X484063Y305669D03*
X480773Y307153D03*
X471015Y527283D03*
X475731Y566632D03*
X473231D03*
Y569132D03*
X475731D03*
Y574132D03*
Y571632D03*
X473231Y574132D03*
Y571632D03*
X475731Y576632D03*
X473231D03*
X485335Y642536D03*
X480475D03*
X482905D03*
X473445Y642231D03*
X477711Y639101D03*
X475645Y640831D03*
X473445Y639331D03*
X475545Y637831D03*
X473445Y636431D03*
X477711Y636201D03*
X479812Y645240D03*
Y648140D03*
X479058Y702660D03*
Y700160D03*
X484062Y700028D03*
Y702528D03*
X481562D03*
Y700028D03*
X479058Y697528D03*
X481558D03*
X484058D03*
X479058Y717660D03*
Y707660D03*
Y712660D03*
Y710160D03*
Y715160D03*
X484058Y710160D03*
Y712660D03*
X481558Y710160D03*
Y712660D03*
X484058Y715160D03*
X481558D03*
X484062Y707528D03*
X481562D03*
X479058Y705160D03*
X484062Y705028D03*
X481562D03*
X480803Y1015474D03*
Y1022560D03*
Y1019017D03*
X483824Y1472295D03*
X480424D03*
X483500Y1658500D03*
X479500Y1666500D03*
X473500Y1662500D03*
X477538Y1661463D03*
X474000Y1704000D03*
X478500Y1697000D03*
Y1710500D03*
Y1733500D03*
X491849Y55095D03*
Y60105D03*
X497885Y51315D03*
X491849Y64965D03*
X500674Y116261D03*
X490380Y131442D03*
X493780D03*
X485780Y141942D03*
X500136Y141058D03*
X495500Y161386D03*
X497700Y157200D03*
X492685Y160994D03*
X486682Y193516D03*
X495232D03*
Y185516D03*
X486682Y189516D03*
X496831Y205030D03*
X499380Y222510D03*
X491635Y225970D03*
X494144Y221370D03*
X487442Y223377D03*
X500209Y227881D03*
X491635Y215652D03*
X500209Y233000D03*
X491859D03*
X500119Y243173D03*
X500209Y238119D03*
X491577Y238120D03*
Y243240D03*
X485962Y290679D03*
X487827Y354017D03*
X490419Y362138D03*
X498500Y419425D03*
X495793Y632815D03*
X495839Y635323D03*
X488351Y633278D03*
X491839Y634878D03*
X489101Y635846D03*
X498782Y639000D03*
X497362Y700028D03*
Y702528D03*
X494862D03*
Y700028D03*
X499858Y697528D03*
X497358D03*
X494858D03*
X499862Y700160D03*
Y702660D03*
X494862Y705028D03*
X497362D03*
X499862Y705160D03*
X488384Y1015474D03*
X495884D03*
X488384Y1022560D03*
Y1019017D03*
X495884Y1022560D03*
Y1019017D03*
X490524Y1462595D03*
X497224Y1452895D03*
X487124Y1462595D03*
X493824Y1452895D03*
X512658Y46613D03*
X504796Y86320D03*
X516020Y105370D03*
Y109270D03*
X514240Y97146D03*
X513772Y121220D03*
X502750Y111276D03*
X503000Y135600D03*
X509346Y125842D03*
X507945Y160919D03*
X503161Y154620D03*
X500600Y157100D03*
X505315Y196944D03*
X503507Y185516D03*
X504351Y202776D03*
X508238Y199506D03*
X512076Y206404D03*
X511684Y221219D03*
X504351Y215901D03*
X508001Y220166D03*
X515223Y289035D03*
Y313200D03*
Y305145D03*
X513775Y608436D03*
X506745Y608131D03*
X508945Y606731D03*
X506745Y602331D03*
Y605231D03*
X508845Y603731D03*
X511011Y602101D03*
Y605001D03*
X513012Y611040D03*
Y613940D03*
X501062Y635475D03*
X502555Y646390D03*
Y643849D03*
X514162Y673428D03*
Y665928D03*
Y668428D03*
Y670928D03*
X514158Y663428D03*
Y678460D03*
Y683460D03*
Y680960D03*
Y675960D03*
X509572Y865327D03*
X513572D03*
X513924Y1462595D03*
X510624Y1472295D03*
X507224D03*
X524713Y33346D03*
X529713D03*
X516058Y46613D03*
X519765Y40328D03*
X523165D03*
X519743Y71436D03*
X523143D03*
X526460Y100895D03*
Y97495D03*
X517640Y97146D03*
X524993Y125914D03*
X521618Y165428D03*
X519268Y167428D03*
X519601Y196117D03*
X518691Y191846D03*
X517314Y200449D03*
X519248Y280721D03*
X516723D03*
X521773D03*
X520273Y289035D03*
X517748D03*
X522798D03*
X520273Y313200D03*
X517748D03*
X520273Y305145D03*
X517748D03*
X515523Y335613D03*
X529317Y403784D03*
X524680Y417602D03*
X529095Y452049D03*
X529153Y598735D03*
X529235Y601543D03*
X521651Y599178D03*
X525139Y600778D03*
X522401Y601746D03*
X516205Y608436D03*
X518635D03*
X529962Y673428D03*
Y670928D03*
Y668428D03*
Y665928D03*
X516662Y673428D03*
Y670928D03*
Y668428D03*
Y665928D03*
X527462Y673428D03*
Y665928D03*
Y668428D03*
Y670928D03*
X516658Y663428D03*
X527458D03*
X529958D03*
X516658Y678460D03*
Y683460D03*
Y680960D03*
X527458Y678460D03*
X516658Y675960D03*
X527458D03*
X529958D03*
Y678460D03*
X526474Y851934D03*
Y849434D03*
X517009Y856494D03*
X523074Y853439D03*
Y855939D03*
X528220Y1167366D03*
X517118D03*
X520818D03*
X517324Y1462595D03*
X524024Y1452895D03*
X520624D03*
X539120Y31340D03*
X535117D03*
X544721Y42892D03*
X539721Y42862D03*
X533918Y47067D03*
X537318D03*
X541003Y71436D03*
X544403D03*
X538210Y90618D03*
X540615Y88213D03*
X535170Y111230D03*
Y115130D03*
X530567Y125914D03*
X543408Y133912D03*
X538166Y130698D03*
X541675Y146874D03*
Y151470D03*
Y142021D03*
Y137169D03*
Y156195D03*
X533442Y164428D03*
X532222Y207849D03*
X540695Y217874D03*
X534277Y224930D03*
X538613Y227882D03*
X537051Y211959D03*
X538613Y238119D03*
X534277Y230441D03*
Y235560D03*
X538613Y233000D03*
X539217Y245270D03*
X543780Y294168D03*
X541808Y289743D03*
X544628Y291633D03*
Y289133D03*
X542983Y334531D03*
X533211Y350838D03*
X533543Y404130D03*
X530729Y398634D03*
X543170Y434737D03*
X534455Y428561D03*
X531753Y453232D03*
X540616Y463486D03*
X538067Y592652D03*
X542071Y593089D03*
X535855Y612290D03*
X539657Y607658D03*
X534362Y601375D03*
X535855Y609749D03*
X532082Y604900D03*
X534962Y670960D03*
Y665960D03*
Y668460D03*
X532462D03*
Y665960D03*
Y670960D03*
Y673460D03*
Y663460D03*
X534962D03*
Y673460D03*
Y675960D03*
X532462D03*
X531921Y1167366D03*
X537424Y1452895D03*
X534024D03*
X544794Y1480682D03*
Y1484082D03*
Y1497482D03*
Y1494082D03*
X543947Y1516120D03*
Y1512220D03*
X543672Y1519845D03*
X540810Y1521436D03*
X533317Y1511953D03*
Y1514453D03*
Y1516953D03*
X531495Y1519250D03*
X537770Y1519845D03*
X537647Y1516120D03*
Y1512220D03*
X534002Y1521436D03*
X540797Y1516120D03*
Y1512220D03*
X543719Y1549295D03*
Y1546795D03*
X541219D03*
Y1549295D03*
X538719D03*
Y1546795D03*
X531339Y1546481D03*
X553620Y31048D03*
X549919D03*
X554984Y45312D03*
X553651Y48842D03*
X546350Y39562D03*
X550972Y42902D03*
X561721Y41024D03*
X556351Y41538D03*
X548610Y48082D03*
X547821Y79372D03*
X551721D03*
X555176Y71436D03*
X558576D03*
X559069Y105385D03*
Y101985D03*
X552105Y112203D03*
X555505D03*
X553780Y121240D03*
Y124640D03*
X559484Y156667D03*
X553757Y160075D03*
X547196Y190256D03*
X550196D03*
X554196D03*
X553578Y193541D03*
X547196Y199256D03*
X550553Y200304D03*
Y197778D03*
X548963Y218441D03*
X549248Y237652D03*
Y230441D03*
X555567Y236970D03*
X549248Y234152D03*
X559774Y243176D03*
X557243Y294693D03*
X561808Y300492D03*
X562030Y372872D03*
X551044Y373085D03*
X562208Y383668D03*
Y404717D03*
X550573Y399586D03*
Y403586D03*
X562208Y397599D03*
X550573Y414274D03*
X549854Y406298D03*
X547529Y425411D03*
X551591Y443665D03*
X552510Y446490D03*
X547751Y472678D03*
X550925Y475178D03*
X553360Y477822D03*
X555727Y479968D03*
X558379Y482096D03*
X549957Y658478D03*
Y661478D03*
X558690Y1226149D03*
X558876Y1454905D03*
Y1458305D03*
X546253Y1454107D03*
Y1457507D03*
X555348Y1483590D03*
Y1480190D03*
Y1501990D03*
Y1505390D03*
X548197Y1514641D03*
X550471Y1513584D03*
Y1511031D03*
X548197Y1512088D03*
X554766Y1523331D03*
Y1526731D03*
X550939Y1536646D03*
X559215Y1530596D03*
X546219Y1549295D03*
Y1541795D03*
Y1546795D03*
Y1544295D03*
X548719Y1549295D03*
Y1546795D03*
Y1541795D03*
Y1544295D03*
X551219D03*
Y1541795D03*
X549674Y1538890D03*
X558089Y1541795D03*
Y1544295D03*
Y1546795D03*
Y1549295D03*
X555589Y1541795D03*
Y1549295D03*
Y1546795D03*
Y1544295D03*
X549759Y1551844D03*
X552177Y1551099D03*
X554682Y1551844D03*
X552177Y1548199D03*
X565185Y47982D03*
X575331Y47672D03*
X573191Y42912D03*
X570209Y47982D03*
X566771Y41133D03*
X564794Y58911D03*
X567997Y58992D03*
X573763Y58688D03*
X562331Y48438D03*
X570860Y121310D03*
Y124710D03*
X563951Y153640D03*
Y148640D03*
Y157494D03*
X572003Y164356D03*
Y169415D03*
X568804Y221926D03*
X571427Y217771D03*
X569004Y225496D03*
X568736Y235821D03*
X565093Y242640D03*
X570823Y294893D03*
X572447Y299470D03*
X569893Y300293D03*
X571063Y314669D03*
X566148Y324502D03*
X567773Y316153D03*
X575913Y413287D03*
X570863Y410728D03*
X572121Y437038D03*
X564407Y431638D03*
X568709Y434227D03*
X563763Y486350D03*
X567297Y487551D03*
X560890Y484664D03*
X569923Y490726D03*
X561346Y1228547D03*
X564669Y1238907D03*
X564283Y1231192D03*
X565537Y1235456D03*
X574200Y1229900D03*
X567127Y1249536D03*
X570775Y1263008D03*
X564986Y1462595D03*
X571686Y1452895D03*
X561586Y1462595D03*
X568286Y1452895D03*
X560589Y1541795D03*
Y1544295D03*
Y1546795D03*
Y1549295D03*
X563089Y1541795D03*
Y1549295D03*
Y1546795D03*
Y1544295D03*
X567214Y1544299D03*
X591938Y46308D03*
X576478Y58563D03*
X591070Y60201D03*
X586953Y63441D03*
X583685Y70678D03*
X586390Y69291D03*
X579561Y73090D03*
X585000Y82500D03*
X584752Y86248D03*
X590501Y86909D03*
X578454Y88926D03*
X586394Y95948D03*
X591811Y97421D03*
X580485Y133056D03*
Y130530D03*
X583485D03*
Y133056D03*
X589203Y164356D03*
X581203D03*
X589203Y169415D03*
X585685Y174975D03*
X581203Y169415D03*
X575425Y189835D03*
X582124Y194150D03*
X588244Y208991D03*
X575440Y200785D03*
X582002Y197481D03*
X582766Y225496D03*
Y221421D03*
X588554Y217277D03*
Y225277D03*
X580343Y217771D03*
X588215Y214079D03*
X588968Y240112D03*
X582816Y228696D03*
X581099Y263680D03*
X586157Y366827D03*
X585585Y372052D03*
X577482Y383668D03*
X581985Y387227D03*
Y376427D03*
X587710Y399287D03*
X581985Y401158D03*
X587710Y404287D03*
X588723Y415846D03*
X588798Y435949D03*
X588723Y427949D03*
X588742Y431976D03*
X577845Y437151D03*
X587829Y445138D03*
X575345Y437151D03*
X580523Y435949D03*
X575075Y451263D03*
X582390Y464701D03*
X589507Y462559D03*
X583116Y476745D03*
X587500Y470308D03*
X587795Y479631D03*
X581335Y472100D03*
X581421Y813078D03*
X588500Y812093D03*
X584271Y1263988D03*
X588386Y1462595D03*
X585086Y1472295D03*
X581686D03*
X602837Y32910D03*
X603064Y48023D03*
X599284Y42481D03*
X597956Y48047D03*
X606585Y43529D03*
X601073Y60301D03*
X603350Y73642D03*
X599295Y100747D03*
X606183Y95873D03*
X597275Y94922D03*
X596068Y106798D03*
X591385Y109165D03*
X602328Y109062D03*
X597769Y153640D03*
Y148640D03*
X603344Y139131D03*
X598552Y159066D03*
X600161Y188776D03*
X593661D03*
X604293Y193185D03*
X597293Y193186D03*
X602294Y203786D03*
X598968Y238878D03*
X603526Y229995D03*
X597050Y281950D03*
X602223Y298035D03*
X603723Y289721D03*
X602223Y314145D03*
Y322200D03*
X598414Y372357D03*
X598208Y383668D03*
X599884Y412000D03*
X593758Y415850D03*
X603326Y429530D03*
X590326Y445015D03*
X592529Y461563D03*
X598496Y451421D03*
X597500Y483500D03*
X602833Y791746D03*
X590710Y804192D03*
X603743Y794963D03*
X595619Y806084D03*
X600337Y800649D03*
X596821Y802688D03*
X592572Y809088D03*
X596621Y1240366D03*
X595253Y1266668D03*
X596944Y1270115D03*
X595532Y1262668D03*
X605771Y1263098D03*
X598112Y1264365D03*
X594991Y1285582D03*
Y1289582D03*
X591786Y1462595D03*
X598486Y1452895D03*
X595086D03*
X613025Y42725D03*
X612608Y35961D03*
X618732Y39913D03*
X619563Y49193D03*
X615587Y45611D03*
X606263Y60301D03*
X616815Y60277D03*
X611579D03*
X615190Y74533D03*
X615772Y106645D03*
X618182Y100786D03*
X610009Y100748D03*
X614282Y95873D03*
X617420Y119640D03*
X619240Y123232D03*
X605853Y149640D03*
Y145640D03*
Y152140D03*
Y155131D03*
X618801Y165356D03*
Y175534D03*
Y170415D03*
X616357Y182229D03*
X608794Y203786D03*
X607868Y257562D03*
X618705Y285305D03*
X608773Y289721D03*
X609798Y298035D03*
X607273D03*
X606248Y289721D03*
X604748Y298035D03*
X609798Y314145D03*
X607273D03*
X604748D03*
X621585Y331358D03*
X609798Y322200D03*
X607273D03*
X604748D03*
X611118Y359462D03*
X613565Y350819D03*
X619035Y369542D03*
X613482Y383668D03*
X617985Y387227D03*
Y376427D03*
Y401728D03*
X606032Y418968D03*
X617985Y407346D03*
X617998Y415546D03*
X606811Y429528D03*
X611925Y437000D03*
X605769Y442593D03*
X615903Y493474D03*
X608886Y494400D03*
X618680Y511302D03*
X618957Y502306D03*
X616457D03*
X611896Y535178D03*
Y538178D03*
X607091Y528168D03*
X618645Y783582D03*
X609402Y788678D03*
X615571Y788448D03*
X608940Y1265991D03*
X610551Y1262988D03*
X618761Y1266988D03*
X615591Y1282038D03*
X618761Y1278668D03*
X606619Y1278302D03*
X610551Y1269888D03*
X616037Y1367166D03*
X608148Y1373890D03*
X616615Y1386232D03*
X616629Y1375082D03*
X618586Y1462595D03*
X615186D03*
X611886Y1472295D03*
X608486D03*
X613948Y1641600D03*
X624634Y48104D03*
X628410Y45381D03*
X624689Y58262D03*
X627881Y57120D03*
X622207Y60573D03*
X627496Y74977D03*
X626642Y71365D03*
X622156Y95948D03*
X626208Y100861D03*
X628885Y127057D03*
X630810Y122089D03*
X625532Y146982D03*
X625553Y152683D03*
X625755Y168917D03*
X626372Y193431D03*
X626824Y182080D03*
X620455Y219277D03*
Y228777D03*
X631505Y284355D03*
X626705Y285305D03*
X622705D03*
X626473Y305338D03*
X626388Y330536D03*
X631694Y341300D03*
X626555Y343929D03*
X624133Y346520D03*
X626596Y360196D03*
X636500Y360362D03*
X634105Y404652D03*
X635058Y399700D03*
X627925Y421966D03*
X631075Y429888D03*
X632281Y441904D03*
X622174Y438925D03*
X622197Y436116D03*
X622800Y461348D03*
X627880Y455310D03*
X620800Y474700D03*
X627364Y478823D03*
X632984Y471462D03*
X630758Y505874D03*
X633406Y497964D03*
X624381Y503765D03*
X631510Y510613D03*
X624718Y553428D03*
X634794Y590504D03*
X635567Y671774D03*
X631557Y773359D03*
X631741Y770318D03*
X633406Y1358576D03*
X634776Y1353739D03*
X630477Y1350109D03*
Y1353109D03*
X624795Y1373257D03*
X624976Y1378313D03*
X630195Y1384263D03*
X625195Y1383457D03*
X622352Y1393285D03*
X630523Y1392554D03*
X635849Y1393376D03*
X625286Y1452895D03*
X621886D03*
X629808Y1668863D03*
X633422Y1673488D03*
X631643Y1670946D03*
X635491Y1696845D03*
X635472Y1711808D03*
X644963Y29143D03*
X638490Y33340D03*
X642157Y44695D03*
X639876Y49193D03*
X651042Y41545D03*
X647987Y47606D03*
X646042Y41545D03*
X640653Y58274D03*
X640670Y74369D03*
X650846Y74074D03*
X647938Y83795D03*
X644202Y84604D03*
X642607Y94116D03*
X645752Y134988D03*
X643800Y166053D03*
X641111Y158300D03*
X641006Y161829D03*
X643800Y161862D03*
X640923Y169388D03*
X649871Y181942D03*
X641276Y187557D03*
X637804Y235371D03*
X640804D03*
X637804Y239371D03*
X640804D03*
X640084Y227113D03*
X637804Y243371D03*
X640804D03*
X642171Y311280D03*
X641013Y324459D03*
X640922Y360342D03*
X639000Y364862D03*
X642128Y363279D03*
X636579Y366941D03*
X642617Y389299D03*
X637314Y393680D03*
X640784Y395957D03*
X651279Y404458D03*
X637160Y405449D03*
X635243Y433518D03*
X637432Y428935D03*
X642406Y427614D03*
X639211Y433862D03*
Y438191D03*
X635449Y449797D03*
X639002Y449862D03*
X639500Y442362D03*
X639313Y452361D03*
X635690Y461441D03*
X648500Y453862D03*
X635640Y464257D03*
X644849Y495582D03*
X647576Y497964D03*
X643053Y502891D03*
X640076Y497964D03*
X635906D03*
X642310Y535773D03*
X649592Y540078D03*
X639757Y533440D03*
X636055Y528605D03*
X646151Y535227D03*
X648314Y571169D03*
X644414D03*
X638694Y590504D03*
X650258Y590316D03*
X646358D03*
X650228Y674761D03*
X638967Y671774D03*
X646446Y674643D03*
X640271Y763488D03*
X636551Y767900D03*
X642804Y766871D03*
X636247Y771179D03*
X635092Y1277102D03*
X634995Y1384457D03*
X638053Y1384491D03*
X647401Y1384160D03*
X645386Y1462595D03*
X641986D03*
X648686Y1452895D03*
X638686Y1472295D03*
X635286D03*
X639907Y1570443D03*
X639132Y1573127D03*
X645180Y1597800D03*
X645190Y1595050D03*
X649153Y1625726D03*
X649297Y1623185D03*
X640242Y1639951D03*
X647630Y1641522D03*
X643128Y1639803D03*
X642716Y1653939D03*
X637218Y1654131D03*
X644905Y1646491D03*
X639800Y1646650D03*
X643074Y1668505D03*
X647574D03*
X647460Y1662952D03*
X640846Y1665189D03*
X650158Y1687189D03*
X643041Y1682883D03*
X647500Y1674805D03*
X640600D03*
X643300D03*
X639391Y1700695D03*
X640690Y1703547D03*
X651143Y1706162D03*
X644975Y1725236D03*
X635210Y1718395D03*
X641825Y1730516D03*
X640865Y1719684D03*
X657921Y30864D03*
X654117Y29099D03*
X654582Y45448D03*
X660928Y60707D03*
X651014Y60820D03*
X656600Y60537D03*
X661601Y75562D03*
X656501Y69662D03*
X657166Y79131D03*
X656427Y75431D03*
X661588Y69662D03*
X658228Y88447D03*
X666200Y84862D03*
X654037Y93241D03*
Y96041D03*
X651950Y99890D03*
X658949Y139840D03*
X662881Y149912D03*
Y146912D03*
X654326Y174437D03*
X653700Y179962D03*
X659881Y208262D03*
Y205762D03*
Y210762D03*
X662781Y207862D03*
Y205362D03*
Y210362D03*
X663915Y234476D03*
X659918Y326503D03*
X658905Y341885D03*
X661019Y344831D03*
X663551Y346035D03*
X649500Y373500D03*
X652425Y385924D03*
X659095Y381020D03*
X649495Y385118D03*
X659354Y393938D03*
X653523Y399987D03*
X652954Y394284D03*
X661297Y409857D03*
X662016Y417897D03*
X652027Y415930D03*
X654273Y419251D03*
X662000Y433862D03*
X654248Y422500D03*
X657535Y422694D03*
X666000Y429844D03*
X651432Y433532D03*
X662000Y429844D03*
X652763Y427866D03*
X651384Y445252D03*
X661546Y444497D03*
X662000Y449862D03*
X654441Y449618D03*
X662000Y437844D03*
X657622Y437819D03*
X651853Y439518D03*
X653449Y458542D03*
X662570Y461547D03*
Y457755D03*
X662000Y473862D03*
X666000Y473844D03*
X651072Y465939D03*
X654000Y465824D03*
X654014Y473862D03*
X662000Y465862D03*
X651114Y473884D03*
X662000Y469862D03*
X653266Y479106D03*
X663374Y484295D03*
X652380Y482390D03*
X657520Y486330D03*
X649500Y490260D03*
X660215Y483109D03*
X658758Y497964D03*
X655917D03*
X661718Y498056D03*
X651406Y501178D03*
X650404Y496102D03*
X652576Y497964D03*
X659425Y521075D03*
X665689Y550294D03*
X649922Y545610D03*
X655967Y544375D03*
X658642Y573893D03*
X661718Y579932D03*
X653368Y581468D03*
X655572Y572603D03*
X656832Y577205D03*
X662992Y598660D03*
X658613Y599534D03*
X662628Y674761D03*
X660175Y679517D03*
X657428Y674761D03*
X663580Y731509D03*
X658947Y767300D03*
Y771100D03*
X662600Y1311502D03*
Y1308502D03*
X653376Y1365793D03*
X661719Y1363394D03*
X651973Y1363038D03*
X653149Y1372500D03*
X653101Y1369862D03*
X652651Y1375308D03*
X661813Y1370081D03*
X653117Y1378037D03*
X651877Y1391074D03*
X652086Y1452895D03*
X662086D03*
X663160Y1511734D03*
Y1516734D03*
Y1519234D03*
Y1521734D03*
X660660Y1519234D03*
X661710Y1514148D03*
X663160Y1524234D03*
X666092Y1553650D03*
X660953Y1539998D03*
X663133Y1543744D03*
Y1541244D03*
Y1538744D03*
X660953Y1542498D03*
X657430Y1555228D03*
X659532Y1546519D03*
X664246Y1561009D03*
X661731Y1561083D03*
X661156Y1626532D03*
X650966Y1618934D03*
X651870Y1612986D03*
X650753Y1615912D03*
X653542Y1649059D03*
X660058Y1648889D03*
X660389Y1654481D03*
X663431Y1645780D03*
X654712Y1653813D03*
X664315Y1654484D03*
X650074Y1668505D03*
X658648Y1664169D03*
X655683Y1664212D03*
X653154Y1683265D03*
X664159Y1674844D03*
X661528Y1674865D03*
X650200Y1674805D03*
X658491Y1688965D03*
X649464Y1691180D03*
X659837Y1698400D03*
X659557Y1714672D03*
X658759Y1707147D03*
X659028Y1710047D03*
X660930Y1730277D03*
X662120Y1720404D03*
X670613Y42464D03*
X674013D03*
X677476Y33317D03*
X680864Y38190D03*
X666506Y32750D03*
X674647Y38190D03*
X677305Y57947D03*
X665469Y58525D03*
X674036Y74522D03*
X675509Y88173D03*
X667941Y80142D03*
X677561Y118409D03*
X677738Y115428D03*
X665651Y147692D03*
X673011Y169021D03*
X679035Y204181D03*
X678226Y215771D03*
X674348Y218580D03*
X666552Y346115D03*
X677111Y345662D03*
X672111D03*
X674611D03*
X676800Y369362D03*
X672800D03*
X680800Y380280D03*
X672800Y382362D03*
X676000Y378100D03*
X667090Y385150D03*
X671500Y390862D03*
X679940Y400933D03*
X675500Y398862D03*
Y390862D03*
X670018Y418690D03*
X669929Y407999D03*
X666000Y433862D03*
Y425862D03*
X670000Y429864D03*
Y433844D03*
Y425894D03*
X666000Y437844D03*
X670000Y442362D03*
Y437844D03*
X666000Y442362D03*
X670000Y446362D03*
X679062Y455140D03*
X666000Y453844D03*
Y457862D03*
X670000Y453844D03*
X666000Y461862D03*
X670000Y469824D03*
Y477862D03*
X678000D03*
X670000Y482862D03*
X678000D03*
X681213Y495658D03*
X672699Y506907D03*
X664741Y506865D03*
X680488Y504784D03*
X665425Y537000D03*
X664454Y574896D03*
X665774Y571762D03*
X666192Y598660D03*
X679047Y678733D03*
X673287Y733156D03*
X674123Y736083D03*
X667101Y736071D03*
X672505Y766871D03*
X674552Y1342488D03*
Y1344988D03*
X665167Y1380836D03*
Y1376836D03*
X673671Y1431922D03*
X675272Y1434525D03*
X665486Y1452895D03*
X672856Y1484082D03*
Y1480682D03*
Y1497482D03*
Y1494082D03*
X678386Y1507965D03*
X677871Y1522079D03*
X678345Y1516994D03*
X677871Y1519579D03*
X673174Y1515806D03*
X675505Y1512606D03*
X678339Y1510960D03*
X677871Y1524579D03*
X678121Y1528516D03*
X665832Y1527425D03*
X672715Y1526626D03*
Y1530526D03*
X678350Y1567400D03*
X669524Y1560850D03*
X672163Y1560899D03*
X673729Y1556768D03*
X666978Y1560945D03*
X672810Y1571560D03*
X666610Y1571580D03*
X668133Y1625828D03*
X670839Y1620863D03*
X673960Y1633042D03*
X669648Y1640917D03*
X670803Y1654606D03*
X671068Y1650818D03*
X674908Y1644481D03*
X667971Y1654404D03*
X669178Y1646627D03*
X673548Y1669550D03*
X678117Y1662787D03*
X675497Y1687253D03*
X673359Y1674409D03*
X671001Y1696017D03*
X671798Y1704542D03*
X673113Y1716599D03*
X667701Y1705043D03*
X668058Y1720092D03*
X673113Y1727261D03*
X684611Y41857D03*
X682291Y46822D03*
X690476Y32684D03*
X692390Y46939D03*
X692466Y35950D03*
X687835Y37850D03*
X687345Y46940D03*
X687018Y58357D03*
X683369Y58157D03*
X692390Y72692D03*
X690028Y70142D03*
X687665Y73202D03*
X685781Y70022D03*
X680580Y79230D03*
X681054Y104668D03*
X686891Y115868D03*
X687000Y119500D03*
X685500Y124000D03*
X679316Y209861D03*
X680576Y207105D03*
X681333Y212326D03*
X679737Y217763D03*
X693621Y346169D03*
X680828Y363500D03*
X684800Y369362D03*
X680800D03*
X691484Y360643D03*
X691500Y382462D03*
X685200Y377820D03*
X690105Y401775D03*
X687500Y390680D03*
X684794Y402268D03*
X683500Y390862D03*
X679500D03*
X692996Y418358D03*
X694299Y413108D03*
X689269Y410420D03*
X687612Y471850D03*
X691572Y465214D03*
X684800Y477862D03*
X687472Y486994D03*
X684680Y485942D03*
X684800Y481862D03*
X680187Y491243D03*
X690452Y486984D03*
X687310Y500453D03*
X682915Y500568D03*
X683000Y521500D03*
X687310Y522141D03*
X694111Y537881D03*
X690718Y578913D03*
X694996Y575081D03*
X689574Y572866D03*
X681352Y681305D03*
X691417Y680382D03*
X685786Y680936D03*
X686509Y677440D03*
X688648Y767300D03*
Y771100D03*
X687961Y1314308D03*
Y1320308D03*
Y1323308D03*
Y1317308D03*
X684868Y1327117D03*
X682348D03*
Y1339617D03*
X683052Y1342548D03*
X684868Y1329617D03*
X682348D03*
X684868Y1332117D03*
X682348D03*
X684868Y1334617D03*
X682348D03*
X684868Y1337117D03*
Y1339617D03*
X682348Y1337117D03*
X683052Y1345048D03*
X681289Y1418291D03*
X683391Y1420531D03*
X685448Y1423137D03*
X691587Y1429515D03*
X689538Y1427467D03*
X684350Y1448911D03*
X692376Y1438326D03*
X691943Y1441626D03*
X687040Y1452300D03*
X684280Y1452260D03*
X684603Y1507851D03*
X681517Y1508034D03*
X687529Y1508173D03*
X690683Y1508058D03*
X693395D03*
X693532Y1510755D03*
X690820D03*
X687666Y1510870D03*
X687711Y1513612D03*
X690751Y1513750D03*
X693655Y1513818D03*
X693587Y1516470D03*
X690752Y1516516D03*
X683666Y1515189D03*
X680717Y1513292D03*
X684557Y1510685D03*
X681563Y1510708D03*
X693495Y1519305D03*
X679854Y1551492D03*
X679413Y1548843D03*
X680107Y1554330D03*
X681780Y1574280D03*
X684080Y1576500D03*
X686949Y1625144D03*
X689897Y1621781D03*
X692209Y1620037D03*
X691036Y1625508D03*
X686994Y1629077D03*
X693451Y1628733D03*
X686808Y1643500D03*
X685578Y1637479D03*
X683067Y1641758D03*
X686075Y1657082D03*
X679413Y1653251D03*
X685719Y1672391D03*
X685747Y1669303D03*
X693608Y1671081D03*
X685635Y1675310D03*
X691560Y1682047D03*
X693480Y1673940D03*
X692390Y1687594D03*
X705666Y48010D03*
X697678Y47132D03*
X697893Y35950D03*
X702481Y48327D03*
X698462Y60683D03*
X695220Y60455D03*
X704201Y72112D03*
X699476Y69982D03*
X701081Y72450D03*
X694752Y70212D03*
X696701Y72462D03*
X698711Y86035D03*
X696371Y78512D03*
X696728Y81552D03*
Y84052D03*
X706721Y100462D03*
X702721Y102162D03*
X701221Y104862D03*
X697721D03*
X695721Y102162D03*
X694221Y104862D03*
X699221Y102162D03*
X699398Y123668D03*
X704709Y125586D03*
X704771Y171188D03*
Y167788D03*
X703486Y345507D03*
X699813Y344798D03*
X706139Y345597D03*
X695500Y374362D03*
X699500D03*
X703500D03*
X707500D03*
X707943Y360643D03*
X707500Y368862D03*
X696391Y368617D03*
X703477Y369409D03*
X695500Y382362D03*
X700300Y382502D03*
X707500Y382362D03*
X700000Y386790D03*
X707500Y386862D03*
X703700Y386832D03*
X695500Y386862D03*
X699500Y390862D03*
X695500D03*
X707500D03*
X703500Y401290D03*
Y390862D03*
X708584Y404868D03*
X699431Y513344D03*
X703774Y513463D03*
X707664Y513375D03*
X703788Y521817D03*
X696020Y521844D03*
X699800Y521760D03*
X708500Y517362D03*
X708210Y537816D03*
X708500Y529862D03*
X704500D03*
X700790Y537732D03*
X704500Y537862D03*
X708500Y533862D03*
X696829Y533604D03*
X702657Y533695D03*
X697018Y537577D03*
X704500Y545862D03*
X696283Y546530D03*
X710429Y545752D03*
X708500Y555451D03*
X698996Y575081D03*
X704056D03*
X708056D03*
X704056Y583081D03*
X698996D03*
X702806Y613264D03*
X696928Y613207D03*
X706387Y621686D03*
X705158Y645357D03*
X703781Y641805D03*
X704965Y638767D03*
X707833Y655325D03*
X704549Y655238D03*
X701233Y655355D03*
X708418Y650389D03*
X694812Y680188D03*
X698756Y676388D03*
X694837Y676412D03*
X701386Y679683D03*
X703584Y676544D03*
X708012Y676836D03*
X705697Y679533D03*
X697571Y730453D03*
X704598Y732288D03*
X700205Y733211D03*
X702553Y735811D03*
X702206Y766871D03*
X697461Y1314008D03*
Y1320008D03*
Y1323008D03*
X702388Y1327127D03*
X699868D03*
X697461Y1317008D03*
X701771Y1342488D03*
X702388Y1337127D03*
Y1339627D03*
X699868Y1337127D03*
Y1339627D03*
X702388Y1329627D03*
X699868D03*
X702388Y1332127D03*
X699868D03*
X702388Y1334627D03*
X699868D03*
X701771Y1344988D03*
X705657Y1387027D03*
X701689Y1399545D03*
X697731Y1397513D03*
X706351Y1397588D03*
X705657Y1389568D03*
X695162Y1441350D03*
X696237Y1508149D03*
X699247Y1508062D03*
X699049Y1510892D03*
X696374Y1510846D03*
X696329Y1513818D03*
X696330Y1516584D03*
X699140Y1513772D03*
X707050Y1531700D03*
X709150Y1536250D03*
X703290Y1551700D03*
X707050Y1548400D03*
Y1541800D03*
X703290Y1545100D03*
X708500Y1560500D03*
X708994Y1568507D03*
X699500Y1559000D03*
X699610Y1568523D03*
Y1572523D03*
Y1576523D03*
X708600Y1572523D03*
X710420Y1585173D03*
X710550Y1576523D03*
X710080Y1581683D03*
X699610Y1584523D03*
X699500Y1596500D03*
Y1588500D03*
X709836Y1594721D03*
X710360Y1589296D03*
X699000Y1604500D03*
X699500Y1599500D03*
X709382Y1601210D03*
X699500Y1608500D03*
X709020Y1609101D03*
X699424Y1616627D03*
X695933Y1623460D03*
X709260Y1617903D03*
X701114Y1640345D03*
X702683Y1633715D03*
X703563Y1644116D03*
X702402Y1650469D03*
X700528Y1661468D03*
X697503Y1661331D03*
X703102Y1665554D03*
X714471Y46670D03*
X724621Y40062D03*
X719821Y45862D03*
X714322Y56286D03*
X721163Y58588D03*
X714096Y73686D03*
X712717Y68541D03*
X719416Y68738D03*
Y74036D03*
X725016Y86952D03*
X720016D03*
X715745Y86300D03*
X712725Y84714D03*
X712291Y106722D03*
X715934Y117488D03*
Y114588D03*
X712734Y117488D03*
Y114588D03*
X720434Y135088D03*
X717434D03*
X719934Y124488D03*
X723134D03*
X712341Y128093D03*
X710284Y169826D03*
X716699Y177087D03*
Y173687D03*
Y189087D03*
Y185687D03*
Y200587D03*
Y197187D03*
Y209021D03*
X717021Y220862D03*
X716699Y212421D03*
X714867Y344943D03*
X717712Y346103D03*
X715500Y374362D03*
X719500D03*
X723531Y368862D03*
X723500Y360862D03*
X711500Y374362D03*
X715500Y360862D03*
X719500Y368862D03*
X715500D03*
X711363Y369274D03*
X711500Y382362D03*
X719640Y386862D03*
X723632D03*
X711500D03*
X715500D03*
X722500Y383162D03*
X723500Y390862D03*
X719500D03*
X715500D03*
X711500D03*
X716500Y521862D03*
X711617Y513531D03*
X724500Y517362D03*
X716500D03*
X720400Y517440D03*
X720452Y513362D03*
X716716Y513368D03*
X720499Y533474D03*
X719841Y537348D03*
X712113Y537797D03*
X720500Y555862D03*
Y546211D03*
X712115Y541872D03*
X712409Y555413D03*
X710464Y557036D03*
X722201Y579306D03*
X723483Y574890D03*
X714583Y590792D03*
X716181Y585562D03*
X715037Y606428D03*
X716313Y610134D03*
X719710Y612831D03*
X720787Y627907D03*
X716721D03*
X713343Y633842D03*
X724000Y633906D03*
X725812Y654713D03*
X715371Y654726D03*
X711702Y646533D03*
X711295Y665117D03*
X718129Y666725D03*
X722129D03*
X712164Y676912D03*
X712120Y680287D03*
X717515Y679833D03*
X720563Y679886D03*
X720613Y677040D03*
X723814Y736782D03*
X718349Y767300D03*
Y771100D03*
X721339Y1314048D03*
X711839Y1314348D03*
X721339Y1323048D03*
Y1320048D03*
Y1317048D03*
X715828Y1327277D03*
X710488Y1327177D03*
X713008D03*
X711839Y1323348D03*
Y1320348D03*
Y1317348D03*
X713008Y1329877D03*
Y1332377D03*
Y1334877D03*
X715828Y1332877D03*
Y1330377D03*
X713008Y1337377D03*
Y1339877D03*
X715828Y1335377D03*
X710288Y1339677D03*
Y1337177D03*
X710221Y1342488D03*
X710288Y1334677D03*
Y1332177D03*
Y1329677D03*
X710221Y1344988D03*
X712419Y1398094D03*
X719861Y1400139D03*
X716373Y1398539D03*
X719111Y1397571D03*
X712419Y1400602D03*
X709430Y1394417D03*
X722877Y1390881D03*
X712099Y1416973D03*
X714599D03*
X717099D03*
X712099Y1414473D03*
X714599D03*
X717099D03*
X709599Y1416973D03*
Y1414473D03*
X717099Y1432773D03*
X712099D03*
X714599D03*
X717099Y1430273D03*
X712099D03*
X714599D03*
X709599Y1432773D03*
Y1427373D03*
Y1424873D03*
Y1430273D03*
Y1419873D03*
Y1422373D03*
X714259Y1447483D03*
X719471Y1467422D03*
X711671D03*
X714271D03*
X716871D03*
X720217Y1472287D03*
X717617D03*
X715017D03*
X720926Y1469814D03*
X718326D03*
X715726D03*
X713126D03*
X716067Y1474792D03*
X718667D03*
X721267D03*
X717358Y1477038D03*
X719958D03*
X714474Y1566333D03*
X724110Y1561825D03*
X714110Y1581475D03*
X714900Y1571273D03*
X721963Y1576932D03*
X719963Y1578932D03*
X721440Y1570963D03*
X719963Y1585790D03*
X721963Y1587790D03*
X723590Y1595323D03*
X718892Y1597152D03*
X714372Y1594679D03*
X723408Y1608740D03*
X720106Y1609542D03*
X717798Y1607335D03*
X713718Y1610235D03*
X717229Y1612376D03*
X718129Y1624330D03*
X722104Y1626253D03*
X715744Y1622842D03*
X722889Y1622491D03*
X711298Y1632534D03*
X718122Y1636332D03*
X718116Y1639129D03*
X713771Y1654927D03*
X722480Y1657616D03*
X719117Y1682722D03*
X723181Y1688825D03*
X740101Y41162D03*
X736621Y45262D03*
X733315Y40862D03*
X728721Y43562D03*
X726789Y60562D03*
X738590Y59868D03*
X730785Y58068D03*
X728285Y58135D03*
X724645Y58362D03*
X734769Y60757D03*
X725769Y69737D03*
X736864Y74943D03*
X731864D03*
X727200Y73210D03*
X729918Y90998D03*
X739824Y91052D03*
X734380Y80518D03*
X729380D03*
X736650Y102350D03*
X735771Y94988D03*
X730660Y108484D03*
X728734Y132088D03*
Y129288D03*
Y126388D03*
X735500Y143000D03*
X724147Y345291D03*
X729211Y346379D03*
X726431Y346384D03*
X738773Y346716D03*
X734463Y346712D03*
X735500Y368862D03*
X734166Y360782D03*
X739500Y368862D03*
X727564D03*
X731500Y360862D03*
X731406Y374331D03*
X731500Y368862D03*
Y386862D03*
X739553Y388270D03*
X735500Y386862D03*
X727500D03*
X735500Y390862D03*
X727500D03*
X735500Y399330D03*
X738672Y494444D03*
X728938Y517520D03*
X724500Y513362D03*
X732500D03*
X739185Y521394D03*
X728500Y521862D03*
X724500D03*
X728500Y513362D03*
X736609Y518426D03*
X728500Y529862D03*
X728576Y537476D03*
X736500Y537862D03*
X724336Y537527D03*
X724433Y530870D03*
X732500Y529862D03*
X736647Y529772D03*
X732580Y537193D03*
X724697Y535053D03*
X728652Y545862D03*
X728695Y550943D03*
X736670Y545864D03*
X740500Y545862D03*
X724684Y545864D03*
X724281Y553438D03*
X728714Y554190D03*
X732520Y545988D03*
X736528Y576480D03*
Y579615D03*
X727253Y610689D03*
X724246Y627939D03*
X736362Y636854D03*
X730770Y644218D03*
X733382Y633574D03*
X729489Y666547D03*
X734442Y675695D03*
X730837Y678940D03*
X738486Y679139D03*
X724931Y678364D03*
X735316Y736742D03*
X725712Y734135D03*
X729391D03*
X727576Y736756D03*
X727448Y766871D03*
X735739Y1314048D03*
Y1320048D03*
Y1317048D03*
X724788Y1327277D03*
X727501Y1327230D03*
X730021D03*
X735739Y1323048D03*
X727401Y1332430D03*
Y1329930D03*
Y1334930D03*
X724788Y1330377D03*
Y1332877D03*
X727401Y1339930D03*
Y1337430D03*
X724788Y1335377D03*
X730021Y1337230D03*
Y1339730D03*
Y1334730D03*
Y1329730D03*
Y1332230D03*
X730795Y1342444D03*
Y1344944D03*
X738439Y1387127D03*
X728198Y1388026D03*
Y1385126D03*
X738439Y1389668D03*
X727737Y1390881D03*
X725307D03*
X734767Y1396986D03*
Y1394086D03*
X732567Y1392586D03*
X732667Y1395586D03*
X730501Y1397216D03*
Y1394316D03*
X734767Y1391186D03*
X735418Y1426122D03*
Y1423122D03*
Y1420122D03*
X732418Y1426122D03*
Y1423122D03*
Y1420122D03*
X735453Y1525368D03*
X737551Y1524008D03*
X727325Y1563400D03*
X727571Y1558353D03*
X736782Y1555496D03*
X730782D03*
X733782D03*
X727571Y1555353D03*
X733782Y1567496D03*
X736782D03*
X730782D03*
X733782Y1558496D03*
Y1561496D03*
X736782Y1558496D03*
Y1561496D03*
X733782Y1564496D03*
X736782D03*
X730782Y1558496D03*
Y1561496D03*
Y1564496D03*
X726475Y1571293D03*
X723963Y1578932D03*
X730782Y1570496D03*
X736782D03*
X733782D03*
X733380Y1577231D03*
X727780Y1582361D03*
Y1577231D03*
X723963Y1585790D03*
X726550Y1599358D03*
X733380Y1587491D03*
X727780D03*
X736998Y1597463D03*
X730998D03*
X733998D03*
X736998Y1594463D03*
X730998D03*
X733998D03*
X736998Y1600463D03*
X730998D03*
X733998D03*
Y1603663D03*
X736998D03*
X733998Y1606663D03*
X736998D03*
X730998Y1603663D03*
Y1606663D03*
X730647Y1623629D03*
X727320Y1623698D03*
X736723Y1623938D03*
X731119Y1647997D03*
X735642Y1648537D03*
X730347Y1682902D03*
X725638Y1682890D03*
X732852Y1695701D03*
X738030Y1723903D03*
Y1726903D03*
X738108Y1721157D03*
X738075Y1718082D03*
X746101Y46262D03*
X745901Y40362D03*
X749478Y59902D03*
X746588Y59754D03*
X740817Y58503D03*
X747488Y71429D03*
X740537Y73564D03*
X750034Y89988D03*
X750701Y106642D03*
X754783Y96553D03*
X750034Y92888D03*
X741309Y108742D03*
X748034Y116288D03*
X748261Y112552D03*
X743050Y139182D03*
X751221Y137864D03*
X743547Y147703D03*
X748915Y158608D03*
X745031Y161463D03*
X748125Y170618D03*
X751575Y184252D03*
X746522Y308804D03*
X750717Y319907D03*
X747594Y319106D03*
X747696Y332772D03*
X751337Y343849D03*
X748752Y343582D03*
X745132Y344964D03*
X752926Y361021D03*
X747500Y368862D03*
X751500D03*
X743500D03*
Y374362D03*
X749389Y360816D03*
X755135Y368907D03*
X754813Y374362D03*
X739500D03*
X747500D03*
X747454Y386817D03*
X751652Y386862D03*
X743500Y386962D03*
X739652Y390862D03*
X743500D03*
X747500D03*
X751500D03*
X747629Y406163D03*
X753252Y495234D03*
X748381Y495244D03*
X752652Y504106D03*
X752500Y517362D03*
X744500Y513362D03*
X748661Y517060D03*
X740500Y513362D03*
X752500D03*
X748500D03*
X753951Y521801D03*
X748077Y521789D03*
X740500Y537862D03*
X752965Y537678D03*
X748143Y530269D03*
X744916Y530268D03*
X752500Y529862D03*
X748000Y537862D03*
X741851Y553544D03*
X745645Y545880D03*
X752500Y545862D03*
X745091Y553563D03*
X748500Y545862D03*
X752195Y554761D03*
X748482Y557085D03*
X751731Y557714D03*
X739128Y566639D03*
X741624Y580707D03*
X741200Y577470D03*
X749131Y570340D03*
X750062Y655415D03*
X753309Y655515D03*
X750074Y648739D03*
X753483Y648749D03*
X751885Y666724D03*
X753231Y678679D03*
X742579Y676093D03*
X746665Y678879D03*
X750168Y675833D03*
X748049Y767300D03*
Y771100D03*
X745439Y1314048D03*
X748188Y1327317D03*
X745491Y1327124D03*
X742971D03*
X745439Y1323048D03*
Y1320048D03*
Y1317048D03*
X745691Y1332424D03*
Y1329924D03*
Y1334924D03*
X748188Y1333017D03*
Y1330517D03*
X745691Y1339924D03*
Y1337424D03*
X748188Y1335517D03*
X742971Y1337124D03*
Y1339624D03*
Y1334624D03*
Y1329624D03*
Y1332124D03*
X739501Y1342244D03*
Y1344744D03*
X739932Y1398042D03*
X745201Y1398194D03*
X752643Y1400239D03*
X749155Y1398639D03*
X751893Y1397671D03*
X745201Y1400702D03*
X742212Y1394517D03*
X739611Y1458211D03*
X750418Y1468893D03*
X750968Y1482349D03*
X746111Y1504125D03*
X745984Y1501052D03*
X745001Y1516471D03*
X750205Y1512307D03*
X750155Y1516451D03*
X739900Y1523152D03*
X748782Y1555496D03*
X742782D03*
X739782D03*
X745782D03*
X739782Y1558496D03*
Y1561496D03*
Y1564496D03*
X745782Y1558496D03*
X742782D03*
X745782Y1561496D03*
X742782D03*
X745782Y1564496D03*
X742782D03*
X739782Y1567496D03*
X742782D03*
X748782Y1558496D03*
Y1561496D03*
Y1564496D03*
X747110Y1575863D03*
X747150Y1583247D03*
X747110Y1579863D03*
X739782Y1570496D03*
X742782D03*
X738880Y1582361D03*
Y1577231D03*
X747160Y1587773D03*
X749167Y1591967D03*
X754635Y1592571D03*
X738880Y1587491D03*
X745998Y1597463D03*
X742998D03*
X745998Y1594463D03*
X742998D03*
X739998Y1597463D03*
Y1594463D03*
X745998Y1600463D03*
X742998D03*
X739998D03*
X745998Y1603663D03*
X742998D03*
X739998D03*
X745998Y1606663D03*
X742998D03*
X739998D03*
X743664Y1626945D03*
X753770Y1636083D03*
X751521Y1656008D03*
X739880Y1648046D03*
X742792Y1647982D03*
X745075Y1665675D03*
X754030Y1669256D03*
X748254Y1674771D03*
X752187Y1682994D03*
X748413Y1679367D03*
X746766Y1696036D03*
X740328Y1698376D03*
X747289Y1693063D03*
X752187Y1691058D03*
X741030Y1723903D03*
Y1726903D03*
X741160Y1721150D03*
X741025Y1718195D03*
X757721Y62132D03*
X760221D03*
X762721D03*
X755621Y51602D03*
X758621D03*
X757721Y64632D03*
X760221D03*
X763221Y65132D03*
X757188Y91829D03*
X757694Y98108D03*
Y100653D03*
X760193Y106500D03*
X757576Y112575D03*
X756000Y145500D03*
X754825Y163397D03*
X756303Y158417D03*
X765950Y190669D03*
X765000Y186500D03*
X754737Y185469D03*
X757629Y239295D03*
X761067Y280355D03*
X763384Y279231D03*
X763508Y284404D03*
X763463Y281840D03*
X760614Y284100D03*
X754759Y281007D03*
X758510Y298620D03*
X760462Y295662D03*
X757937Y303908D03*
X768130Y335363D03*
X758245Y343763D03*
X764331Y374401D03*
X756347Y360851D03*
X764983Y368052D03*
X766304Y372862D03*
X768304Y374362D03*
X759652D03*
X755500Y386862D03*
X759500D03*
X763500D03*
X767500D03*
X759500Y390791D03*
X755500Y390862D03*
X759500Y402098D03*
X767500Y401470D03*
Y390862D03*
X763500D03*
X757258Y408763D03*
X765975Y414414D03*
X769648Y430511D03*
X770530Y423460D03*
X768301Y438223D03*
X770918Y442510D03*
X770042Y446829D03*
X770590Y470940D03*
X762800Y493654D03*
X764500Y521862D03*
X756500Y513340D03*
X764500D03*
X756800Y517050D03*
X760500Y521189D03*
X764600Y517022D03*
X756186Y529888D03*
X764500Y529862D03*
X760500Y529845D03*
X757860Y537859D03*
X760660Y537862D03*
X756500Y545862D03*
X764500D03*
X759568Y545867D03*
X768340Y563678D03*
X765809Y563410D03*
X758103Y556873D03*
X765041Y565867D03*
X762530Y565340D03*
X757745Y655353D03*
X755765Y666904D03*
X762656Y667835D03*
X756936Y676319D03*
X768565Y677573D03*
X760529Y677715D03*
X764401Y676968D03*
X762396Y732915D03*
X754532Y735859D03*
X760425Y736233D03*
X764568Y736183D03*
X761608Y766871D03*
X759839Y1313948D03*
Y1319948D03*
X760204Y1327314D03*
X762754D03*
X759839Y1316948D03*
X757638Y1327317D03*
X759839Y1322948D03*
X760204Y1332514D03*
Y1330014D03*
Y1335014D03*
X757638Y1333017D03*
Y1330517D03*
X760194Y1340024D03*
Y1337524D03*
X757638Y1335517D03*
X762844Y1337324D03*
Y1339824D03*
X762754Y1334814D03*
Y1329814D03*
Y1332314D03*
X762261Y1343424D03*
Y1345924D03*
X760980Y1385146D03*
Y1388046D03*
X758089Y1390981D03*
X760519D03*
X755659D03*
X767549Y1391286D03*
Y1397086D03*
Y1394186D03*
X765349Y1392686D03*
X765449Y1395686D03*
X763283Y1397316D03*
Y1394416D03*
X758163Y1490789D03*
Y1498663D03*
Y1494726D03*
Y1502600D03*
Y1506538D03*
Y1522286D03*
Y1510474D03*
X757826Y1514412D03*
X758056Y1518349D03*
X760650Y1570633D03*
Y1578733D03*
Y1574733D03*
X757610Y1576023D03*
X766212Y1568043D03*
X757650Y1580023D03*
X766950Y1581233D03*
X757610Y1584023D03*
X767750Y1584108D03*
X757610Y1589023D03*
X760650Y1587733D03*
X760521Y1595500D03*
X759723Y1626161D03*
X755261Y1628208D03*
X758030Y1668583D03*
X754839Y1678069D03*
X768463Y1687769D03*
X757161Y1696424D03*
X768733Y1694485D03*
X781441Y118637D03*
X782819Y149471D03*
X780159Y146961D03*
X772270Y153728D03*
X771427Y158026D03*
X782712Y260466D03*
X777408Y256648D03*
X777421Y277962D03*
X779884Y281705D03*
X769790Y296231D03*
X777468Y296315D03*
X769861Y302462D03*
X782641Y310888D03*
X779681Y313053D03*
X770190Y312563D03*
X779121Y303410D03*
Y308755D03*
X780046Y328268D03*
X772119Y333537D03*
X771964Y339716D03*
X781812Y341863D03*
X779118Y341749D03*
X769000Y364000D03*
X776500Y371000D03*
X784500Y367500D03*
X771512Y386862D03*
X775388Y390862D03*
X770000Y380787D03*
X777612Y403505D03*
X771512Y390862D03*
X780295Y403538D03*
X784498Y396353D03*
X782700Y415284D03*
X773181Y415197D03*
X773233Y409154D03*
X783256Y409340D03*
X770159Y410257D03*
X783770Y422454D03*
X772610Y434690D03*
X780877Y427344D03*
X771718Y426804D03*
X780877Y423344D03*
X783821Y431534D03*
X780877Y431368D03*
X772677Y451374D03*
X780577Y435564D03*
X780877Y443344D03*
Y447344D03*
X780977Y459524D03*
X780877Y463344D03*
Y455344D03*
X783377Y451344D03*
X780877Y475344D03*
X780759Y479344D03*
X783877Y475344D03*
X772427D03*
X783759Y479344D03*
X780877Y483344D03*
X772390Y491047D03*
X772427Y487344D03*
X783358Y495344D03*
X783351Y499221D03*
X771039Y511292D03*
X775100Y502504D03*
X772427Y495344D03*
X777166Y504477D03*
X774998Y511306D03*
X774964Y514204D03*
X772100Y532700D03*
X777200Y530250D03*
X772000Y529862D03*
X781699Y536425D03*
X772000Y545862D03*
X776345Y545733D03*
X777754Y558740D03*
X773463Y563455D03*
X778747Y572269D03*
X779448Y632498D03*
X772459Y655290D03*
X771553Y677963D03*
X777750Y767300D03*
Y771100D03*
X783280Y1296009D03*
X778030Y1296259D03*
X780530D03*
X783280Y1298509D03*
X785520Y1292160D03*
X769439Y1313948D03*
X783280Y1301009D03*
X769439Y1319948D03*
Y1322948D03*
Y1316948D03*
X770881Y1343344D03*
X782115Y1334173D03*
X770881Y1345844D03*
X774646Y1516441D03*
X772906Y1522901D03*
X774616Y1520361D03*
X778850Y1556133D03*
X781850D03*
Y1559133D03*
Y1562133D03*
Y1565133D03*
X778850Y1559133D03*
Y1562133D03*
Y1565133D03*
X771450Y1577333D03*
X781850Y1568133D03*
Y1571133D03*
X778850Y1568133D03*
Y1571133D03*
X779977Y1577233D03*
Y1582363D03*
X771550Y1587133D03*
X774420Y1587284D03*
X779977Y1587493D03*
X779550Y1594533D03*
X782550D03*
X776550Y1597533D03*
Y1594533D03*
X779550Y1597533D03*
X782550D03*
Y1600533D03*
X776550D03*
X779550D03*
Y1606533D03*
X782550Y1603533D03*
X779550D03*
X776550Y1606533D03*
Y1603533D03*
X782550Y1606533D03*
X785181Y120947D03*
X792681D03*
X790181D03*
X787681D03*
X783941Y118637D03*
X786441D03*
X788941D03*
X785529Y270459D03*
X798205Y279146D03*
X794058Y301569D03*
X793221Y296062D03*
X793897Y309026D03*
X793855Y305316D03*
X798493Y301377D03*
X795921Y312662D03*
X787500Y328362D03*
X799226Y328467D03*
X791726D03*
X783726D03*
X785674Y342279D03*
X788806Y342236D03*
X791403Y342262D03*
X793951Y342224D03*
X795685Y357498D03*
X792302Y357537D03*
X798312Y372571D03*
X796021Y395924D03*
X797000Y404000D03*
X786571Y403455D03*
X785923Y419194D03*
X787000Y407500D03*
X796283Y415344D03*
Y419344D03*
X786877Y427344D03*
X796283Y423344D03*
Y431344D03*
X783877Y427344D03*
X796283D03*
X786999Y435476D03*
X797252Y443344D03*
X786877D03*
X796333Y435344D03*
X786203Y447054D03*
X783877Y435444D03*
X797197Y447344D03*
X786887Y451344D03*
X797252D03*
X797322Y463344D03*
X786825Y459518D03*
X786755Y455524D03*
X797252Y455344D03*
X797326Y479344D03*
X786877Y471344D03*
X797463Y476159D03*
X786877Y475344D03*
X786440Y480769D03*
X797405Y487464D03*
X797326Y483344D03*
X787092Y490681D03*
X786358Y483566D03*
X786102Y507536D03*
X787446Y495344D03*
X787279Y499238D03*
X790503Y501826D03*
X799450Y511801D03*
X800674Y504130D03*
X789125Y529425D03*
X800500Y540500D03*
X794357Y559996D03*
X785919Y559660D03*
X792782Y565323D03*
X791723Y574946D03*
X799742Y628983D03*
X789135Y617097D03*
X783653Y631671D03*
X787591Y631785D03*
X788537Y734410D03*
X793131Y734310D03*
X784543Y734510D03*
X791308Y766871D03*
X789020Y1292160D03*
X792520D03*
X796020D03*
X794273Y1354600D03*
Y1357600D03*
Y1364500D03*
Y1361500D03*
X784669Y1462178D03*
X796955Y1487468D03*
X788710Y1488821D03*
X784277Y1504569D03*
Y1500632D03*
Y1508506D03*
Y1512443D03*
X791867Y1524254D03*
X784850Y1556133D03*
X796850D03*
X790850D03*
X787850D03*
X793850D03*
X784850Y1559133D03*
Y1562133D03*
Y1565133D03*
X796850Y1559133D03*
Y1562133D03*
Y1565133D03*
X787850Y1559133D03*
Y1562133D03*
Y1565133D03*
X793850Y1559133D03*
X790850D03*
X793850Y1562133D03*
X790850D03*
X793850Y1565133D03*
X790850D03*
X799150Y1581379D03*
X784850Y1568133D03*
Y1571133D03*
X787850Y1568133D03*
Y1571133D03*
X793850Y1568133D03*
X790850D03*
X793850Y1571133D03*
X790850D03*
X791077Y1577233D03*
X785577D03*
X791077Y1582363D03*
X796650Y1583347D03*
X785577Y1587493D03*
X791077D03*
X791550Y1597533D03*
X785550Y1594533D03*
X788550D03*
X791550D03*
X785550Y1597533D03*
X788550D03*
X785550Y1600533D03*
X788550D03*
X791550D03*
Y1606533D03*
X788550D03*
X785550D03*
X791550Y1603533D03*
X788550D03*
X785550D03*
X803302Y265848D03*
X812867Y278860D03*
X810139Y274098D03*
X804330Y281380D03*
X801341Y279141D03*
X799935Y286823D03*
X799113Y297733D03*
X803893Y301969D03*
X805871Y304812D03*
X806461Y310610D03*
X808617Y330102D03*
X806117D03*
X812070Y341590D03*
X803410Y341572D03*
X803500Y366000D03*
X802660Y381020D03*
X802462Y387756D03*
X807564Y403805D03*
X811224Y395974D03*
X803412Y403978D03*
X813148Y403908D03*
X805425Y395502D03*
X813252Y427060D03*
X802270Y435372D03*
X802459Y443218D03*
X813208Y435344D03*
X812895Y449802D03*
X813114Y443344D03*
X802533Y449802D03*
X812983Y463578D03*
X813114Y459344D03*
X801552Y463318D03*
X802752Y459344D03*
X813114Y455344D03*
X812983Y471344D03*
Y476159D03*
X801874Y471344D03*
X802752Y480159D03*
X812983D03*
X813000Y484862D03*
X801762Y495344D03*
X802752Y487344D03*
X801753Y491344D03*
X813187Y498362D03*
X813114Y495344D03*
X802250Y500504D03*
X801857Y508031D03*
X805940Y534500D03*
X805341Y578059D03*
X805199Y620347D03*
X804863Y626789D03*
X805150Y623843D03*
X807451Y767299D03*
X807127Y770958D03*
X799280Y1296009D03*
X802030Y1296259D03*
X804530D03*
X807601Y1299241D03*
X799280Y1298509D03*
Y1301009D03*
X801614Y1339062D03*
X811771Y1355488D03*
X799071Y1350088D03*
X807866Y1369177D03*
X805366Y1367093D03*
X802866D03*
X807866Y1366677D03*
X808714Y1490376D03*
Y1487376D03*
Y1506784D03*
Y1519784D03*
Y1509784D03*
Y1516784D03*
X802150Y1570633D03*
Y1578633D03*
Y1582833D03*
X810150Y1574633D03*
X813150Y1579410D03*
Y1570633D03*
X810050Y1584033D03*
X802150Y1594633D03*
X810850Y1587733D03*
X810150Y1590633D03*
X813049D03*
X802700Y1587183D03*
X810150Y1602633D03*
Y1598633D03*
X802150Y1606633D03*
X819321Y56961D03*
X823115Y115223D03*
X820901Y147112D03*
X814571Y145952D03*
X814532Y139851D03*
X822635Y165468D03*
X825332Y166862D03*
X813676Y266065D03*
X823067Y273225D03*
X823038Y276301D03*
X819828Y288063D03*
X827621Y302962D03*
X822689Y305148D03*
X826915Y311842D03*
X822252Y309973D03*
X816232Y341584D03*
X818677Y356405D03*
X826765Y356334D03*
X817780Y366905D03*
X823778Y376378D03*
X818157Y381020D03*
X816991Y395337D03*
X820018Y403710D03*
X816281Y403814D03*
X828286Y401567D03*
X824653Y405347D03*
X817497Y415344D03*
X827341Y419344D03*
X817497D03*
X827341Y415344D03*
X817497Y427060D03*
X826474Y431344D03*
X816239Y435344D03*
X817497Y431060D03*
X826474Y435344D03*
X816117Y443552D03*
X816236Y439279D03*
X816109Y449802D03*
X822878Y446425D03*
X816109Y455344D03*
X816000Y463578D03*
X816170Y458524D03*
X826912Y475989D03*
X816109Y471344D03*
X816409Y467568D03*
X817393Y491594D03*
X830212Y483892D03*
X826472Y483896D03*
X827000Y489055D03*
X817996Y496219D03*
X828259Y501027D03*
X824380Y517595D03*
X827237Y550771D03*
X817849Y550871D03*
X820620Y550846D03*
X824366Y552444D03*
X827832Y554269D03*
X814489Y558082D03*
X825200Y580300D03*
X815287Y580401D03*
X820617Y641273D03*
X816732Y629198D03*
X815753Y644219D03*
X817900Y649012D03*
X822579Y760169D03*
X822218Y756979D03*
X822794Y767511D03*
X825390Y770020D03*
X822794Y777511D03*
X816550Y766871D03*
X822625Y763529D03*
X822794Y772511D03*
Y775011D03*
X825061Y764884D03*
X822864Y783262D03*
X822772Y788359D03*
X822790Y785838D03*
X822883Y780334D03*
X822982Y791245D03*
X822555Y807409D03*
X822794Y797511D03*
Y800011D03*
Y795011D03*
X822494Y802941D03*
X823927Y907676D03*
X823958Y936140D03*
X826958D03*
X823958Y939140D03*
X826958D03*
X827088Y933387D03*
X824036Y933394D03*
X826953Y930432D03*
X824003Y930319D03*
X828109Y1234504D03*
X826728Y1246315D03*
X824444Y1249420D03*
X828246Y1266501D03*
X824714Y1490376D03*
Y1487376D03*
X816690Y1490376D03*
Y1487376D03*
X824714Y1500376D03*
Y1497376D03*
Y1506784D03*
X816717Y1500388D03*
X816729Y1497364D03*
X816693Y1506784D03*
X824714Y1519784D03*
Y1509784D03*
Y1516784D03*
X816706Y1519820D03*
X816693Y1516784D03*
X816694Y1509796D03*
X824714Y1529784D03*
Y1526784D03*
X816714Y1529784D03*
Y1526784D03*
X823850Y1556133D03*
X820850D03*
X826850D03*
X820850Y1565133D03*
Y1562133D03*
Y1559133D03*
X826850Y1565133D03*
X823850D03*
X826850Y1562133D03*
Y1559133D03*
X823850Y1562133D03*
Y1559133D03*
X820850Y1571133D03*
Y1568133D03*
X826850Y1571133D03*
Y1568133D03*
X823850Y1571133D03*
Y1568133D03*
X821977Y1577233D03*
X827577D03*
X821977Y1582363D03*
X816150Y1587284D03*
X821977Y1587493D03*
X827577D03*
X821550Y1594533D03*
X827550Y1597533D03*
Y1594533D03*
X824550Y1597533D03*
Y1594533D03*
X821550Y1597533D03*
Y1600533D03*
X827550D03*
X824550D03*
X815550Y1606533D03*
X818550D03*
X821550Y1603533D03*
X818550D03*
X827550Y1606533D03*
X824550D03*
X821550D03*
X827550Y1603533D03*
X824550D03*
X842320Y-21711D03*
Y-18311D03*
X828601Y61752D03*
X836780Y68008D03*
X839899Y87248D03*
X841585Y94181D03*
X837251Y93221D03*
X839361Y114862D03*
X835115Y115223D03*
X845221Y135862D03*
Y129362D03*
X829115Y147123D03*
X838221Y163862D03*
X835221D03*
X842721Y181362D03*
X837161Y213207D03*
X844527Y204968D03*
X838821Y206872D03*
X837161Y218212D03*
X837501Y229642D03*
X836305Y268624D03*
X836181Y275686D03*
X830418Y311865D03*
X837754Y335345D03*
X829800Y331013D03*
X840457Y335368D03*
X842257Y350376D03*
X829344Y356224D03*
X833219Y375992D03*
X840357Y382813D03*
X833097Y393000D03*
X837912Y401545D03*
X834426Y401504D03*
X833000Y409500D03*
X838500D03*
X837847Y405347D03*
X833807Y423257D03*
X841809Y423219D03*
X838000Y423362D03*
X829106Y439279D03*
X842825Y448739D03*
X828979Y449802D03*
X834106Y439279D03*
X828714Y443552D03*
X833800Y444700D03*
X828751Y455344D03*
Y463578D03*
X834251Y455578D03*
X828751Y459344D03*
X832224Y450328D03*
X831381Y455167D03*
X833751Y463578D03*
X842825Y452739D03*
X828751Y471344D03*
Y467568D03*
X838575Y477554D03*
X839200Y467900D03*
X830046Y476031D03*
X838561Y484071D03*
X841854Y504972D03*
X833000Y503500D03*
X831798Y515314D03*
X838342Y514610D03*
X839061Y555808D03*
X841660Y558200D03*
X835519Y580056D03*
X831018Y583076D03*
X835059Y660940D03*
X837391Y659820D03*
X831505Y897291D03*
X831582Y905153D03*
X832347Y1251703D03*
X844250Y1266759D03*
X832274Y1277301D03*
X832342Y1274626D03*
X833756Y1330156D03*
X834017Y1336252D03*
X833963Y1339464D03*
X838963Y1345974D03*
X833853Y1345833D03*
X841039Y1358082D03*
X839244Y1352094D03*
X841472Y1365050D03*
X835850Y1556133D03*
X829850D03*
X832850D03*
X838850D03*
X832850Y1565133D03*
X835850D03*
X832850Y1562133D03*
X835850D03*
X832850Y1559133D03*
X835850D03*
X829850Y1565133D03*
Y1562133D03*
Y1559133D03*
X838850Y1565133D03*
Y1562133D03*
Y1559133D03*
X841150Y1581379D03*
X832850Y1571133D03*
X835850D03*
X832850Y1568133D03*
X835850D03*
X829850Y1571133D03*
Y1568133D03*
X833077Y1577233D03*
Y1582363D03*
X838650Y1583347D03*
X833077Y1587493D03*
X830550Y1597533D03*
X833550D03*
X830550Y1594533D03*
X833550D03*
X830550Y1600533D03*
X833550D03*
X830550Y1603533D03*
X836550Y1606533D03*
Y1603533D03*
X833550D03*
X830550Y1606533D03*
X833550D03*
X850016Y87341D03*
X843856Y87711D03*
X847473Y94754D03*
X854221Y135862D03*
Y129362D03*
X854201Y143062D03*
X848745Y160137D03*
X845721Y181362D03*
X856213Y191545D03*
X855859Y212425D03*
X855934Y215375D03*
X847581Y232222D03*
X853621Y269057D03*
X853829Y262057D03*
X846189Y281419D03*
X856244Y286447D03*
X843504Y287602D03*
X855481Y299692D03*
X860071Y304850D03*
X843308Y335550D03*
X857187Y342210D03*
X848030Y338461D03*
X850155Y335042D03*
X852303Y337488D03*
X852177Y341882D03*
X848425Y378089D03*
X854552Y381000D03*
X854190Y404035D03*
X855722Y416606D03*
X846000Y418862D03*
X854239Y412911D03*
X851517Y411745D03*
X846000Y423362D03*
X845986Y429413D03*
X857942Y448575D03*
X845100Y440100D03*
X857887Y459847D03*
X848500Y452128D03*
X847686Y475915D03*
X847303Y485788D03*
X846104Y494661D03*
X847518Y490905D03*
X846411Y482128D03*
X849772Y494585D03*
X852209Y507211D03*
X855497Y507205D03*
X849351Y499070D03*
X848097Y503315D03*
X855837Y519713D03*
X847941Y538325D03*
X845094Y535110D03*
X844741Y543864D03*
X843655Y555683D03*
X847435Y555496D03*
X856647Y616786D03*
X854484Y647436D03*
X848999Y644995D03*
X846931Y1291468D03*
X846895Y1295981D03*
X845801Y1287776D03*
X851500Y1302000D03*
X851400Y1305499D03*
X852811Y1313450D03*
X850684Y1310000D03*
X852955Y1320320D03*
X856500Y1321500D03*
X853100Y1331688D03*
X856500Y1330500D03*
X852780Y1338365D03*
X856500Y1339500D03*
Y1348500D03*
X844150Y1578633D03*
Y1570633D03*
Y1582833D03*
X852150Y1574633D03*
X855150Y1579410D03*
Y1570633D03*
X852050Y1584033D03*
X844150Y1594633D03*
X852850Y1587733D03*
X852150Y1590633D03*
X855049D03*
X844700Y1587183D03*
X852150Y1602633D03*
Y1598633D03*
X844150Y1606633D03*
X857550Y1606533D03*
X858630Y60293D03*
X863343Y90021D03*
X865912Y89252D03*
X870892Y131868D03*
X871145Y163862D03*
X875170Y185113D03*
X867529Y231788D03*
X863104Y273103D03*
X868104D03*
X867701Y267537D03*
X863230Y280001D03*
X866619Y286801D03*
X870672Y295485D03*
X870008Y302273D03*
X872508D03*
X871099Y323000D03*
X864342Y330858D03*
X860942D03*
X860587Y342210D03*
X860372Y375195D03*
X866168Y374774D03*
X871190Y382230D03*
X858925Y398537D03*
X864826Y411557D03*
X870220Y430424D03*
X870826Y423423D03*
X870064Y427703D03*
X859500Y429362D03*
X863420D03*
X859469Y425293D03*
X860541Y446089D03*
X860328Y475162D03*
X858288Y467048D03*
X860280Y488636D03*
X860299Y491620D03*
X864361Y493001D03*
X860508Y497772D03*
X862987Y507305D03*
X860341Y503154D03*
X860658Y515961D03*
X867356Y558714D03*
X867733Y575522D03*
X864590Y642420D03*
X870590D03*
X866727Y650739D03*
X866549Y748027D03*
X869275Y750472D03*
X873175D03*
X868496Y776516D03*
X868539Y790882D03*
X870591Y785437D03*
X865466Y790581D03*
Y785581D03*
Y788081D03*
Y783081D03*
X865394Y801244D03*
X865466Y793081D03*
Y795581D03*
Y798081D03*
X865569Y806045D03*
Y808545D03*
X863369Y827461D03*
X863344Y824713D03*
X863372Y833469D03*
Y830718D03*
X867651Y836820D03*
X867646Y833388D03*
X863671Y839062D03*
X865601Y841219D03*
X865109Y850795D03*
X864768Y844815D03*
X864140Y856052D03*
X864020Y859972D03*
X864106Y863534D03*
X864003Y866609D03*
X866005Y941554D03*
X863055Y941441D03*
X863010Y947262D03*
X866010D03*
X863010Y950262D03*
X866010D03*
X866140Y944509D03*
X863088Y944516D03*
X862044Y1249687D03*
X866294Y1255903D03*
X874989Y1410441D03*
X863745Y1444560D03*
X871214Y1466542D03*
X865850Y1556133D03*
X871850D03*
X862850D03*
X868850D03*
X865850Y1565133D03*
Y1562133D03*
Y1559133D03*
X862850Y1565133D03*
Y1562133D03*
Y1559133D03*
X868850Y1565133D03*
X871850D03*
X868850Y1562133D03*
X871850D03*
X868850Y1559133D03*
X871850D03*
X865850Y1571133D03*
Y1568133D03*
X862850Y1571133D03*
Y1568133D03*
X868850Y1571133D03*
X871850D03*
X868850Y1568133D03*
X871850D03*
X863977Y1577233D03*
Y1582363D03*
X869577Y1577233D03*
X858150Y1587284D03*
X863977Y1587493D03*
X869577D03*
X863550Y1597533D03*
X866550Y1594533D03*
Y1597533D03*
X869550Y1594533D03*
Y1597533D03*
X863550Y1594533D03*
X872550D03*
Y1597533D03*
X866550Y1600533D03*
X869550D03*
X863550D03*
X872550D03*
Y1606533D03*
Y1603533D03*
X863550Y1606533D03*
X866550D03*
X869550D03*
X860550D03*
X869550Y1603533D03*
X866550D03*
X863550D03*
X860550D03*
X876696Y176862D03*
Y171362D03*
X887521D03*
Y176862D03*
X889351Y195489D03*
X878328Y183169D03*
X878221Y187449D03*
X887130Y183169D03*
X884986Y198829D03*
X881354Y267407D03*
X884004Y278712D03*
Y274482D03*
X885764Y284361D03*
X877448Y284825D03*
X884004Y271332D03*
X874244Y287047D03*
X873172Y295485D03*
X888000Y293000D03*
X877640Y315789D03*
X873884Y447991D03*
Y450491D03*
X885916Y653912D03*
X883731Y651690D03*
X884410Y794332D03*
X883633Y790336D03*
X883776Y786814D03*
X877459Y802356D03*
X875412Y797350D03*
X882582Y1075083D03*
X879582D03*
X876582D03*
X873582D03*
X882582Y1061983D03*
X879582D03*
X876582D03*
Y1071533D03*
Y1068533D03*
Y1065533D03*
X873582D03*
Y1068533D03*
Y1071533D03*
Y1061983D03*
X886707Y1229920D03*
Y1232920D03*
X881807Y1238920D03*
X876923Y1239520D03*
X886707Y1235920D03*
X881694Y1229763D03*
Y1232763D03*
Y1235763D03*
X876907Y1235586D03*
Y1232586D03*
Y1229586D03*
X881807Y1241920D03*
X877936Y1312336D03*
X883379Y1417881D03*
X875039Y1407246D03*
X886362Y1428973D03*
X884399Y1431507D03*
X879424Y1425001D03*
X883279Y1421726D03*
X883562Y1440356D03*
X881987Y1449608D03*
X887519Y1444625D03*
X877226Y1441585D03*
X887117Y1436735D03*
X877850Y1556133D03*
X874850D03*
X880850D03*
X874850Y1565133D03*
X877850D03*
X880850D03*
X874850Y1562133D03*
X877850D03*
X880850D03*
X874850Y1559133D03*
X877850D03*
X880850D03*
X886150Y1578633D03*
Y1570633D03*
Y1582833D03*
X883150Y1581379D03*
X874850Y1571133D03*
X877850D03*
X874850Y1568133D03*
X877850D03*
X875077Y1577233D03*
Y1582363D03*
X886150Y1594633D03*
X880650Y1583347D03*
X886700Y1587183D03*
X875077Y1587493D03*
X875550Y1597533D03*
Y1594533D03*
X886150Y1606633D03*
X875550Y1600533D03*
Y1606533D03*
X878550D03*
Y1603533D03*
X875550D03*
X891621Y207162D03*
X888930Y206823D03*
X891621Y209662D03*
X888930Y209323D03*
X896621Y207162D03*
X894121D03*
Y209662D03*
X896621D03*
X892376Y466430D03*
X899000Y481038D03*
X888372Y547518D03*
X902376Y590172D03*
X900323Y604377D03*
X900301Y828248D03*
Y831221D03*
X899500Y853000D03*
X901000Y909000D03*
X901842Y936863D03*
X903925Y948500D03*
X889273Y1134470D03*
X902382Y1137558D03*
X891996Y1149707D03*
X900280Y1150769D03*
X902482Y1140558D03*
X888247Y1219520D03*
Y1222520D03*
X891247D03*
Y1219520D03*
X888247Y1225520D03*
X896974Y1232869D03*
Y1235869D03*
X896907Y1238920D03*
X896974Y1229869D03*
X891247Y1225520D03*
X896907Y1241920D03*
X892000Y1307500D03*
X888854Y1337936D03*
X890620Y1342990D03*
X900885Y1435041D03*
X900808Y1437798D03*
X902377Y1456465D03*
X904850Y1556133D03*
X894150Y1574633D03*
X897150Y1579410D03*
Y1570633D03*
X894050Y1584033D03*
X894150Y1590633D03*
X894850Y1587733D03*
X897049Y1590633D03*
X900150Y1587284D03*
X894150Y1602633D03*
Y1598633D03*
X899550Y1606533D03*
X902550Y1603533D03*
Y1606533D03*
X917387Y184114D03*
X908621Y188899D03*
X910267Y242658D03*
X910093Y246015D03*
X916268Y269859D03*
X909023Y294734D03*
X910752Y286141D03*
X913512Y486743D03*
X903340Y505105D03*
X917582Y549564D03*
X909747Y579695D03*
X911980Y585280D03*
X910731Y590251D03*
X905526Y594657D03*
X910535Y619251D03*
X906706Y614062D03*
X909747Y628426D03*
X915334Y639166D03*
X908823Y655116D03*
X906274Y654921D03*
X909320Y663930D03*
X907207Y667646D03*
X906345Y742414D03*
X904535Y744639D03*
X906387Y821221D03*
Y815721D03*
X906313Y825095D03*
X903149Y825094D03*
X917000Y853000D03*
X907000Y899777D03*
X913000Y909000D03*
X917000D03*
Y918500D03*
X905000D03*
X915575Y948500D03*
X910000Y954500D03*
X912425Y948500D03*
X907075D03*
X910000Y957500D03*
X912500Y963309D03*
X907500D03*
X909000Y974000D03*
Y982000D03*
X911041Y979459D03*
X909000Y977491D03*
X919779Y1155658D03*
X915053Y1219520D03*
Y1222520D03*
X912053D03*
Y1219520D03*
Y1225520D03*
X915053D03*
X910707Y1229920D03*
Y1232920D03*
X905007Y1238920D03*
X910707Y1235920D03*
X905008Y1229940D03*
Y1232940D03*
Y1235940D03*
X905007Y1241920D03*
X917112Y1266300D03*
X917127Y1275251D03*
X917396Y1271025D03*
X917158Y1279451D03*
X917341Y1283775D03*
X916895Y1292330D03*
X916945Y1296713D03*
X917034Y1288235D03*
X912500Y1310000D03*
X914333Y1322700D03*
X914462Y1329351D03*
X914355Y1340726D03*
X914276Y1347550D03*
X913270Y1440429D03*
X910041Y1440536D03*
X907031Y1457231D03*
X909473Y1448779D03*
X910850Y1556133D03*
X907850D03*
X916850D03*
X913850D03*
X907850Y1559133D03*
Y1562133D03*
X910850Y1559133D03*
Y1562133D03*
X907850Y1565133D03*
X910850D03*
X904850Y1559133D03*
Y1562133D03*
Y1565133D03*
X913850Y1559133D03*
Y1562133D03*
Y1565133D03*
X916850Y1559133D03*
Y1562133D03*
Y1565133D03*
X907850Y1568133D03*
Y1571133D03*
X910850Y1568133D03*
Y1571133D03*
X904850Y1568133D03*
Y1571133D03*
X913850Y1568133D03*
Y1571133D03*
X916850Y1568133D03*
Y1571133D03*
X905977Y1577233D03*
Y1582363D03*
X911577Y1577233D03*
X917077D03*
Y1582363D03*
X905977Y1587493D03*
X911577D03*
X917077D03*
X914550Y1597533D03*
Y1594533D03*
X905550D03*
X911550Y1597533D03*
Y1594533D03*
X908550Y1597533D03*
Y1594533D03*
X905550Y1597533D03*
X917550D03*
Y1594533D03*
X914550Y1600533D03*
X905550D03*
X911550D03*
X908550D03*
X917550D03*
X914550Y1603533D03*
Y1606533D03*
X905550Y1603533D03*
X908550D03*
X911550D03*
Y1606533D03*
X908550D03*
X905550D03*
X917550Y1603533D03*
Y1606533D03*
X915991Y1667328D03*
X922128Y182486D03*
X923386Y193563D03*
X932129Y244103D03*
X922341Y263875D03*
X923103Y362852D03*
X924724Y372211D03*
X919294Y374503D03*
X921318Y372475D03*
X920018Y362877D03*
X921430Y507156D03*
X921367Y503407D03*
X924430Y507156D03*
X924367Y503407D03*
X922591Y496671D03*
X926730Y540897D03*
X921318Y549357D03*
X920031Y577846D03*
X926449Y577806D03*
X930406Y577308D03*
X923747Y584945D03*
X920989Y614132D03*
X925643Y616620D03*
X920989Y617692D03*
X924987Y622523D03*
X932000Y850500D03*
X920234Y843349D03*
X927777Y843416D03*
X930575Y864075D03*
X918500Y860075D03*
X920897Y881879D03*
X929603Y879000D03*
X920000Y895500D03*
X923000D03*
X925500Y907500D03*
X921000Y921925D03*
X925500Y916500D03*
X929500D03*
X932500Y941500D03*
X919500D03*
X928500D03*
X923500D03*
X926000Y949500D03*
Y946500D03*
X919272Y986782D03*
X920107Y1235920D03*
Y1232920D03*
Y1238920D03*
Y1229920D03*
Y1241920D03*
X924500Y1306000D03*
Y1302000D03*
X918000Y1312500D03*
Y1321500D03*
X925459Y1315352D03*
X925500Y1319000D03*
X922000Y1324000D03*
Y1328000D03*
X931326Y1328467D03*
X931216Y1323050D03*
X918000Y1330500D03*
Y1339500D03*
X922000Y1342000D03*
X925500Y1333000D03*
Y1337000D03*
X922000Y1346000D03*
X922850Y1556133D03*
X919850D03*
X922850Y1559133D03*
Y1562133D03*
Y1565133D03*
X919850Y1559133D03*
Y1562133D03*
Y1565133D03*
X925650Y1581379D03*
X919850Y1568133D03*
Y1571133D03*
X922650Y1583347D03*
X920550Y1603533D03*
Y1606533D03*
X921289Y1666337D03*
X927798Y1660762D03*
X945721Y173389D03*
X943221D03*
Y176389D03*
X945721D03*
X935551Y173329D03*
X938161Y173389D03*
Y176389D03*
X935591Y176049D03*
X940721Y173389D03*
Y176389D03*
X939271Y191419D03*
X935771D03*
X944520Y182094D03*
X936454Y184015D03*
X937267Y189010D03*
X945120Y193264D03*
X938570Y233152D03*
X945380Y233962D03*
X949181Y280131D03*
X939938Y386423D03*
X933390Y386405D03*
X944112Y386593D03*
X941764Y420403D03*
X944264D03*
X933390Y559943D03*
X939613Y562031D03*
X937310Y580755D03*
X941764Y587884D03*
X944264D03*
X935766Y587692D03*
X939511Y597073D03*
X935746Y611573D03*
X935783Y631192D03*
X937580Y655946D03*
X945602Y664653D03*
X934539Y664648D03*
X934339Y668533D03*
X941478Y668648D03*
X939216Y664767D03*
X948644Y811190D03*
X938000Y862620D03*
X943000Y862823D03*
X934925Y891425D03*
X945075Y891500D03*
X938500Y907500D03*
X946500Y915988D03*
X938500Y916500D03*
X934500D03*
X942500Y916340D03*
X942631Y943162D03*
X936960Y942898D03*
X935368Y939182D03*
X944515Y939850D03*
X940000Y973500D03*
Y986500D03*
Y982500D03*
Y977500D03*
X937148Y1134343D03*
X933234Y1145058D03*
X936393Y1148087D03*
X947305Y1150769D03*
X943101Y1219520D03*
Y1222520D03*
X946101D03*
Y1219520D03*
X943101Y1225520D03*
X946101D03*
X945691Y1229920D03*
Y1232920D03*
X940791Y1238920D03*
X935907Y1239520D03*
X945691Y1235920D03*
X940678Y1229763D03*
Y1232763D03*
Y1235763D03*
X935891Y1235586D03*
Y1232586D03*
Y1229586D03*
X940791Y1241920D03*
X940994Y1265636D03*
X941011Y1269499D03*
X941500Y1278059D03*
X941033Y1282115D03*
X946730Y1293219D03*
Y1290719D03*
X940919Y1290152D03*
X940937Y1294191D03*
X941083Y1286156D03*
X947135Y1287403D03*
X945872Y1304541D03*
Y1301500D03*
X945617Y1309500D03*
X935028Y1313769D03*
X935300Y1317525D03*
X939071Y1448219D03*
X949216Y1448337D03*
X944105Y1448317D03*
X946402Y1491204D03*
X943902D03*
X936402D03*
X938902D03*
X941402D03*
X933778D03*
X946402Y1501204D03*
Y1498704D03*
Y1496204D03*
Y1493704D03*
X943902D03*
Y1496204D03*
Y1498704D03*
Y1501204D03*
X936402Y1493704D03*
Y1496204D03*
Y1498704D03*
Y1501204D03*
X938902Y1493704D03*
Y1496204D03*
Y1498704D03*
Y1501204D03*
X941402Y1493704D03*
Y1496204D03*
Y1498704D03*
Y1501204D03*
X933778Y1493704D03*
Y1496204D03*
Y1498704D03*
Y1501204D03*
X944406Y1532791D03*
X936150Y1582233D03*
Y1578233D03*
Y1590233D03*
Y1586233D03*
X943798Y1660762D03*
X948401Y176499D03*
X961407Y205125D03*
X950950Y284662D03*
X947821Y386567D03*
X958158Y449020D03*
X958049Y453912D03*
X958101Y457846D03*
X958255Y465811D03*
X959033Y487289D03*
X957380Y515233D03*
X960054Y516982D03*
X962035Y518988D03*
X954757Y593045D03*
X948156Y593912D03*
X952497Y614080D03*
X951102Y628662D03*
X954362Y633314D03*
Y630061D03*
X954259Y657371D03*
X958299Y659886D03*
X954361Y660215D03*
X957462Y668700D03*
X951886Y804495D03*
X951895Y808163D03*
X951466Y816400D03*
X961592Y821737D03*
X949000Y850500D03*
X951000Y855425D03*
X958000Y865500D03*
Y862000D03*
X949500Y870500D03*
Y886500D03*
X953925Y900500D03*
X951169Y910425D03*
X957075Y906500D03*
X960925D03*
X954500Y915988D03*
X950500Y916150D03*
X948500Y937000D03*
X949407Y1137558D03*
X949507Y1140558D03*
X955958Y1232869D03*
Y1235869D03*
X955891Y1238920D03*
X955958Y1229869D03*
X955891Y1241920D03*
X964669Y1271000D03*
X963500Y1275000D03*
X955000Y1283000D03*
Y1287000D03*
X947650Y1314500D03*
Y1319000D03*
Y1323500D03*
Y1328000D03*
Y1337000D03*
Y1332500D03*
Y1341500D03*
Y1346000D03*
X960313Y1362654D03*
X958306Y1448056D03*
X954541Y1448307D03*
X961566Y1448341D03*
X953902Y1491204D03*
X951402D03*
X948902D03*
X956402D03*
X958902D03*
X961402D03*
X953902Y1501204D03*
Y1498704D03*
Y1496204D03*
Y1493704D03*
X951402Y1501204D03*
Y1498704D03*
Y1496204D03*
Y1493704D03*
X948902Y1501204D03*
Y1498704D03*
Y1496204D03*
Y1493704D03*
X956402D03*
X958902D03*
X961402D03*
X963402Y1501204D03*
X958402D03*
X955350Y1532760D03*
X961350D03*
X958350D03*
X959584Y1550824D03*
X949195Y1655145D03*
X951798Y1660762D03*
X975691Y161220D03*
X962673Y170263D03*
Y167763D03*
X967943Y204813D03*
X971943D03*
X975749Y202049D03*
X977221Y205399D03*
X964807Y205125D03*
X973997Y320848D03*
X966278Y556736D03*
X964114Y554704D03*
X976528Y801041D03*
Y803541D03*
Y806041D03*
Y808541D03*
X963500Y854719D03*
X973562Y859767D03*
X964075Y900500D03*
X966804Y1155658D03*
X969907Y1219520D03*
Y1222520D03*
X966907D03*
Y1219520D03*
Y1225520D03*
X969907D03*
X969691Y1229920D03*
Y1232920D03*
X963991Y1238920D03*
X969691Y1235920D03*
X963992Y1229940D03*
Y1232940D03*
Y1235940D03*
X979091Y1229920D03*
X963991Y1241920D03*
X964000Y1267000D03*
X966441Y1278145D03*
X972408Y1312557D03*
X973650Y1431424D03*
X969785Y1447987D03*
X967002Y1448013D03*
X964503Y1448097D03*
X969519Y1452784D03*
X973255Y1456714D03*
X975703Y1451367D03*
X967268Y1491204D03*
X969768D03*
X972268D03*
X974768D03*
X977268D03*
X963902D03*
X967268Y1501204D03*
Y1498704D03*
Y1496204D03*
Y1493704D03*
X969768D03*
Y1496204D03*
Y1498704D03*
Y1501204D03*
X972268Y1493704D03*
Y1496204D03*
Y1498704D03*
Y1501204D03*
X974768Y1493704D03*
Y1496204D03*
Y1498704D03*
Y1501204D03*
X977268Y1493704D03*
Y1496204D03*
Y1498704D03*
Y1501204D03*
X963902Y1493704D03*
X963120Y1520080D03*
Y1523080D03*
X967350Y1532760D03*
X964350D03*
X963120Y1526080D03*
X962584Y1550824D03*
X990579Y155248D03*
X981112Y161204D03*
X988751Y167541D03*
X986447Y158209D03*
X989605Y175400D03*
X985922Y171861D03*
X985445Y185389D03*
X986021Y195099D03*
X979849Y202049D03*
X983879Y202162D03*
X990221Y199699D03*
X987321Y198599D03*
Y202099D03*
X990221Y206699D03*
Y203199D03*
X987321Y205599D03*
X980406Y218283D03*
X980377Y215740D03*
X978269Y264929D03*
X982455Y260781D03*
Y271443D03*
X978827Y303412D03*
X984509Y303623D03*
X989582Y303563D03*
X988460Y358405D03*
X993460D03*
X984272Y349293D03*
X980346Y353527D03*
X981019Y349387D03*
X992460Y370659D03*
X985668Y389311D03*
X980690Y387784D03*
X984605Y408480D03*
X987581Y408332D03*
X988190Y424626D03*
X983358Y449026D03*
X991664Y446372D03*
X993650Y465315D03*
X988650D03*
X991270Y470212D03*
X990292Y494420D03*
X988125Y485193D03*
X986790Y480140D03*
X987440Y504742D03*
X982806Y498606D03*
X986056Y516014D03*
X994056Y521014D03*
Y516014D03*
Y526074D03*
Y531074D03*
X992125Y1061434D03*
X989125D03*
X986125D03*
X983125D03*
X992125Y1064984D03*
Y1067984D03*
X989125D03*
Y1064984D03*
X992125Y1074534D03*
Y1070984D03*
X989125D03*
Y1074534D03*
X986125D03*
X983125D03*
X979091Y1235920D03*
Y1232920D03*
Y1238920D03*
Y1241920D03*
X985396Y1268154D03*
X982665Y1265474D03*
X978318Y1263128D03*
X988242Y1273193D03*
X979228Y1297918D03*
X982000Y1307500D03*
X978026Y1459998D03*
X980779Y1451545D03*
X990634Y1491204D03*
X979768D03*
X982268D03*
X984768D03*
X987268D03*
X990634Y1493704D03*
Y1496204D03*
Y1498704D03*
Y1501204D03*
X979768Y1493704D03*
X982268D03*
X984768D03*
X987268D03*
X986768Y1501204D03*
X981768D03*
X986486Y1523080D03*
Y1520080D03*
Y1526080D03*
X991280Y1532760D03*
X988280D03*
X991196Y1550840D03*
X1006221Y164799D03*
X1002721D03*
X1005307Y155043D03*
X995181Y157689D03*
X999580Y154895D03*
X994257D03*
X996416Y176579D03*
X1002921Y178799D03*
X1002827Y172479D03*
X999221Y189299D03*
X1002721D03*
X1006161Y189019D03*
X1008918Y192994D03*
X1008121Y203525D03*
X1000611Y215039D03*
X1005641Y214969D03*
X1001196Y223898D03*
X1008707Y230423D03*
X997300Y234876D03*
X1006468Y301857D03*
X1003460Y358405D03*
X998460D03*
X994409Y349813D03*
X1000460Y369535D03*
X996889Y374156D03*
X1007080Y367087D03*
X999320Y394480D03*
X1006763Y396206D03*
X1003651Y433426D03*
X998859Y437141D03*
X998359Y451675D03*
X994900Y446192D03*
X998359Y462675D03*
Y457175D03*
X1003909Y454662D03*
Y460162D03*
X998359Y479175D03*
Y468175D03*
Y473675D03*
X996320Y470364D03*
X998359Y484675D03*
X1007077Y484937D03*
X998326Y499675D03*
X995530Y500034D03*
X1006206Y510304D03*
X1002056Y521014D03*
Y516014D03*
Y526074D03*
Y531074D03*
X1004527Y541924D03*
Y553224D03*
X1005270Y625710D03*
X1003090Y1037329D03*
X999350Y1310500D03*
Y1315000D03*
Y1319420D03*
Y1323840D03*
Y1328260D03*
Y1332740D03*
Y1341580D03*
Y1337160D03*
Y1346000D03*
X995500Y1368000D03*
X998000Y1365500D03*
X995000Y1362000D03*
X1000634Y1491204D03*
X998134D03*
X995634D03*
X993134D03*
X1003134D03*
X1005634D03*
X993134Y1496204D03*
Y1493704D03*
X1003134D03*
X1005634D03*
X1000634Y1501204D03*
Y1498704D03*
Y1496204D03*
Y1493704D03*
X998134Y1501204D03*
Y1498704D03*
Y1496204D03*
Y1493704D03*
X995634Y1501204D03*
Y1498704D03*
Y1496204D03*
Y1493704D03*
X993134Y1501204D03*
Y1498704D03*
X1005134Y1501204D03*
X994280Y1532760D03*
X997280D03*
X1000280D03*
X994196Y1550840D03*
X1009721Y164799D03*
X1013221D03*
X1014301Y179699D03*
X1017201D03*
X1019901Y179799D03*
X1011991Y189019D03*
X1014901Y189299D03*
X1017701Y189059D03*
X1011120Y198114D03*
X1020521Y194499D03*
X1011068Y207667D03*
X1021440Y226423D03*
X1019356Y222423D03*
X1010909Y213708D03*
X1011721Y233699D03*
X1019531Y230423D03*
X1018220Y243638D03*
X1015220D03*
X1009220D03*
X1014828Y268427D03*
Y258970D03*
X1013396Y280806D03*
X1011423Y282889D03*
X1023110Y287311D03*
X1017835Y291236D03*
X1023000Y298311D03*
X1016764Y350082D03*
X1010252Y363440D03*
X1009815Y404896D03*
X1020748Y420902D03*
Y425902D03*
X1023420Y462921D03*
X1017220Y464155D03*
X1023515Y454397D03*
X1019205Y457687D03*
X1023420Y468039D03*
X1017350Y472155D03*
X1022874Y474545D03*
X1019210Y480155D03*
X1013306Y518146D03*
Y532501D03*
X1017718Y541201D03*
X1019161Y554757D03*
X1024161D03*
X1017961Y545074D03*
X1009611Y550074D03*
Y545074D03*
X1021425Y568614D03*
X1012925Y558000D03*
X1011602Y568473D03*
X1016000Y563107D03*
X1019261Y571324D03*
X1007587Y761546D03*
Y772480D03*
Y775880D03*
Y764946D03*
Y783482D03*
Y786882D03*
Y794484D03*
Y797884D03*
X1016000Y1303000D03*
X1009905Y1305500D03*
X1009896Y1301500D03*
X1013605Y1316050D03*
X1013529Y1318950D03*
X1012500Y1322500D03*
Y1328500D03*
Y1341580D03*
X1013500Y1332740D03*
Y1337160D03*
X1016000Y1361000D03*
X1012500Y1347500D03*
X1021500Y1491204D03*
X1019000D03*
X1016500D03*
X1014000D03*
X1008134D03*
X1010634D03*
X1021500Y1501204D03*
Y1498704D03*
Y1496204D03*
Y1493704D03*
X1019000Y1501204D03*
Y1498704D03*
Y1496204D03*
Y1493704D03*
X1016500Y1501204D03*
Y1498704D03*
Y1496204D03*
Y1493704D03*
X1014000D03*
Y1496204D03*
Y1498704D03*
Y1501204D03*
X1008134Y1493704D03*
X1010634D03*
X1010134Y1501204D03*
X1009852Y1523080D03*
Y1520080D03*
Y1526080D03*
X1019440Y1532930D03*
X1022796Y1550840D03*
X1022801Y179799D03*
X1027690Y237902D03*
X1024220Y243638D03*
X1033590Y298311D03*
Y287311D03*
X1029200Y351614D03*
X1022674Y357848D03*
X1028146Y355960D03*
X1034214Y351601D03*
X1029601Y394387D03*
X1034855Y411704D03*
X1034409Y429618D03*
X1024443Y424051D03*
X1039015Y444404D03*
X1034899D03*
X1025830Y449022D03*
X1023320Y451112D03*
X1035860Y485976D03*
X1027504Y485637D03*
X1024509Y500168D03*
X1024546Y511254D03*
X1037254Y521014D03*
X1036708Y514883D03*
X1037254Y526074D03*
X1025631Y540104D03*
X1036021Y534990D03*
X1030000Y554500D03*
X1034412Y567416D03*
X1031000Y568500D03*
X1028500Y563000D03*
X1024000D03*
X1029431Y587342D03*
X1032055Y587260D03*
X1028540Y621000D03*
X1035269Y735474D03*
X1032736Y735320D03*
X1030190Y735023D03*
X1025493Y761819D03*
X1035026Y756009D03*
X1036427Y770532D03*
X1038867Y774960D03*
X1025493Y765719D03*
X1033236Y1279287D03*
X1033184Y1275996D03*
X1036411Y1275658D03*
X1036463Y1278949D03*
X1024000Y1491204D03*
X1026500D03*
X1029000D03*
X1031500D03*
X1034000D03*
X1024000Y1501204D03*
Y1498704D03*
Y1496204D03*
Y1493704D03*
X1026500D03*
X1029000D03*
X1031500D03*
X1034000D03*
X1033500Y1501204D03*
X1028500D03*
X1033218Y1523080D03*
Y1520080D03*
X1025440Y1532930D03*
X1022440D03*
X1033218Y1526080D03*
X1031440Y1532930D03*
X1028440D03*
X1025796Y1550840D03*
X1046384Y269814D03*
X1049451Y266747D03*
X1040060Y313528D03*
X1051873Y305482D03*
X1049573Y406586D03*
X1042015Y444404D03*
X1047515D03*
X1043377Y452740D03*
X1040836Y510894D03*
X1045254Y516014D03*
Y534074D03*
Y526074D03*
X1043991Y540979D03*
X1047335Y549574D03*
X1047200Y543090D03*
X1037301Y539685D03*
X1039407Y547723D03*
X1039000Y555000D03*
X1039718Y563268D03*
X1042628Y556845D03*
X1050956Y591090D03*
X1040626Y668441D03*
X1042389Y733426D03*
X1044056Y736188D03*
X1040915Y766870D03*
X1037566Y1047135D03*
X1037895Y1251517D03*
X1039546Y1275474D03*
X1039598Y1278765D03*
X1042855Y1275552D03*
X1042649Y1279152D03*
X1047366Y1491204D03*
X1044866D03*
X1037366D03*
X1042366D03*
X1039866D03*
X1049866D03*
X1047366Y1498704D03*
Y1496204D03*
Y1493704D03*
X1044866Y1496204D03*
Y1493704D03*
X1037366D03*
Y1496204D03*
Y1498704D03*
X1047366Y1501204D03*
X1044866D03*
Y1498704D03*
X1042366Y1501204D03*
Y1498704D03*
Y1496204D03*
Y1493704D03*
X1039866Y1501204D03*
Y1498704D03*
Y1496204D03*
Y1493704D03*
X1037366Y1501204D03*
X1049866Y1493704D03*
X1051866Y1501204D03*
X1051110Y1532850D03*
X1053290Y1652082D03*
X1045545Y1663089D03*
X1066231Y165078D03*
Y167578D03*
X1062704Y270875D03*
X1056941Y259176D03*
X1054613Y261586D03*
X1062923Y295053D03*
X1063356Y318297D03*
X1055934Y388988D03*
X1068143Y380188D03*
X1055934Y381988D03*
X1052505Y406576D03*
X1057798Y427059D03*
Y429618D03*
X1062642Y444859D03*
X1062640Y449155D03*
X1062741Y457959D03*
X1057276Y458155D03*
X1062173Y479655D03*
X1062873Y490180D03*
X1055905Y492537D03*
X1062250Y484672D03*
X1056960Y482262D03*
X1057450Y509242D03*
X1058231Y523238D03*
X1060719Y512359D03*
Y516059D03*
X1061817Y736362D03*
X1065154Y736282D03*
X1057057Y767299D03*
Y771099D03*
X1055171Y1307203D03*
Y1311203D03*
X1058143Y1433809D03*
X1065732Y1491204D03*
X1063232D03*
X1060732D03*
X1052366D03*
X1054866D03*
X1057366D03*
X1065732Y1501204D03*
Y1498704D03*
Y1496204D03*
Y1493704D03*
X1063232Y1501204D03*
Y1498704D03*
Y1496204D03*
Y1493704D03*
X1060732D03*
Y1496204D03*
Y1498704D03*
Y1501204D03*
X1052366Y1493704D03*
X1054866D03*
X1057366D03*
X1056866Y1501204D03*
X1056584Y1523080D03*
Y1520080D03*
X1057110Y1532850D03*
X1054110D03*
X1056584Y1526080D03*
X1063110Y1532850D03*
X1060110D03*
X1057396Y1550840D03*
X1054396D03*
X1071698Y270702D03*
X1078823Y269400D03*
X1071656Y366726D03*
X1078400Y391226D03*
X1074654Y380188D03*
X1078400Y383226D03*
X1074249Y387795D03*
X1082866Y403068D03*
X1074736Y396929D03*
X1072135Y396908D03*
X1072738Y411322D03*
Y416763D03*
Y421922D03*
X1072673Y428791D03*
X1077873Y463444D03*
X1080453Y457959D03*
X1071470Y475525D03*
X1080640Y467000D03*
X1080574Y471500D03*
X1071667D03*
Y467000D03*
X1080416Y482772D03*
X1080420Y487782D03*
X1071710Y483655D03*
Y488782D03*
X1081730Y509172D03*
X1078499Y648202D03*
X1072232Y667749D03*
X1068378Y736795D03*
X1070616Y766870D03*
X1076903Y1300361D03*
Y1302861D03*
X1079403D03*
Y1300361D03*
X1074403Y1302861D03*
Y1300361D03*
X1076903Y1305361D03*
X1079403D03*
X1074403D03*
Y1307861D03*
Y1310361D03*
Y1312861D03*
X1079403Y1307861D03*
Y1310361D03*
Y1312861D03*
X1076903D03*
Y1310361D03*
Y1307861D03*
X1079403Y1315361D03*
X1076903D03*
Y1317861D03*
X1079403D03*
X1074403D03*
Y1315361D03*
X1069839Y1368999D03*
Y1371540D03*
X1076601Y1382574D03*
X1071332Y1379914D03*
X1076601Y1380066D03*
X1080555Y1380511D03*
X1073612Y1376389D03*
X1081005Y1425458D03*
X1071117Y1445005D03*
X1077031Y1451498D03*
X1070312Y1452028D03*
X1073307Y1451931D03*
X1070732Y1491204D03*
X1068232D03*
X1073232D03*
X1075732D03*
X1078232D03*
X1080732D03*
X1070732Y1501204D03*
Y1498704D03*
Y1496204D03*
Y1493704D03*
X1068232Y1501204D03*
Y1498704D03*
Y1496204D03*
Y1493704D03*
X1073232D03*
X1075732D03*
X1078232D03*
X1080732D03*
X1080232Y1501204D03*
X1075232D03*
X1072134Y1647920D03*
X1081011Y1685499D03*
X1078011D03*
X1081011Y1682499D03*
X1078011D03*
X1077172Y1676686D03*
X1077881Y1688252D03*
X1080933Y1688245D03*
X1078016Y1691207D03*
X1080966Y1691320D03*
X1087421Y149716D03*
X1086714Y353515D03*
X1090086Y370417D03*
X1090061Y428019D03*
X1087963Y440605D03*
Y446105D03*
X1084840Y438234D03*
Y443515D03*
X1087963Y462605D03*
Y457105D03*
X1087940Y452110D03*
X1084840Y460005D03*
X1085851Y465978D03*
X1087963Y468105D03*
X1095448Y479426D03*
X1084000Y477500D03*
X1090000D03*
X1087963Y484605D03*
Y494641D03*
Y489641D03*
X1083434Y481500D03*
X1085730Y509362D03*
X1091730D03*
X1095730D03*
X1082622Y520652D03*
X1082438Y524033D03*
X1085438D03*
X1085622Y520652D03*
X1083281Y651601D03*
X1091270Y668286D03*
X1086758Y767299D03*
Y771099D03*
X1090203Y1307861D03*
Y1310361D03*
Y1312861D03*
X1092703D03*
Y1310361D03*
Y1307861D03*
Y1300361D03*
Y1302861D03*
X1090203D03*
Y1300361D03*
X1095203Y1302861D03*
Y1300361D03*
X1092703Y1305361D03*
X1090203D03*
X1095203D03*
Y1307861D03*
Y1310361D03*
Y1312861D03*
X1090203Y1315361D03*
X1092703D03*
Y1317861D03*
X1090203D03*
X1095203D03*
Y1315361D03*
X1087059Y1372853D03*
X1089489D03*
X1091919D03*
X1092889Y1367278D03*
Y1370178D03*
X1084043Y1382111D03*
X1083293Y1379543D03*
X1094683Y1379188D03*
Y1376288D03*
X1091598Y1491204D03*
X1089098D03*
X1086598D03*
X1084098D03*
X1091598Y1501204D03*
Y1498704D03*
Y1496204D03*
Y1493704D03*
X1089098Y1501204D03*
Y1498704D03*
Y1496204D03*
Y1493704D03*
X1086598Y1501204D03*
Y1498704D03*
Y1496204D03*
Y1493704D03*
X1084098D03*
Y1498704D03*
Y1501204D03*
Y1496204D03*
X1090300Y1532660D03*
X1087300D03*
X1096300D03*
X1093300D03*
X1089934Y1550784D03*
X1092934D03*
X1097000Y1629500D03*
X1096500Y1639000D03*
X1096768Y1635080D03*
X1090958Y1646528D03*
Y1649928D03*
X1084629Y1673002D03*
X1087141Y1688914D03*
X1092980Y1699179D03*
X1089030Y1717841D03*
Y1722841D03*
X1099500Y318000D03*
X1111001Y361272D03*
X1107300Y456944D03*
X1111076Y464388D03*
X1108076Y646774D03*
X1104443Y646983D03*
X1100316Y766870D03*
X1109503Y1302861D03*
X1107003D03*
Y1300361D03*
X1109503Y1305361D03*
X1107003D03*
Y1307861D03*
Y1310361D03*
Y1312861D03*
X1109503Y1307861D03*
Y1310361D03*
Y1312861D03*
Y1300361D03*
Y1315361D03*
Y1317861D03*
X1107003D03*
Y1315361D03*
X1102439Y1368999D03*
Y1371540D03*
X1098949Y1373158D03*
X1109201Y1382574D03*
X1103932Y1379914D03*
X1109201Y1380066D03*
X1106212Y1376389D03*
X1098949Y1378958D03*
X1096849Y1377558D03*
X1098949Y1376058D03*
X1096749Y1374558D03*
X1099098Y1501204D03*
X1102248Y1496186D03*
X1106700Y1526591D03*
X1112529Y1547661D03*
X1111701Y1558640D03*
X1107181Y1615917D03*
X1109811D03*
X1098549Y1625749D03*
X1100961Y1622543D03*
X1109000Y1671107D03*
X1105148Y1696029D03*
X1099108Y1691229D03*
X1100998Y1715841D03*
Y1725991D03*
X1119676Y54132D03*
X1124834Y56805D03*
X1124270Y404640D03*
X1121628Y401915D03*
X1121077Y511498D03*
X1125077D03*
X1126387Y615658D03*
X1118435Y625307D03*
X1114467Y640802D03*
X1120321Y635832D03*
X1116540Y651070D03*
X1112190Y651962D03*
X1116459Y767299D03*
Y771099D03*
X1112003Y1302861D03*
Y1300361D03*
Y1305361D03*
X1122803Y1307861D03*
X1125303D03*
Y1310361D03*
Y1312861D03*
X1122803D03*
Y1310361D03*
X1112003Y1312861D03*
Y1310361D03*
Y1307861D03*
X1125303Y1300361D03*
Y1302861D03*
X1122803D03*
Y1300361D03*
X1125303Y1305361D03*
X1122803D03*
X1125303Y1315361D03*
X1122803D03*
X1112003D03*
Y1317861D03*
X1125303D03*
X1122803D03*
X1124519Y1372853D03*
X1119659D03*
X1122089D03*
X1125469Y1367108D03*
Y1370008D03*
X1116643Y1382111D03*
X1113155Y1380511D03*
X1115893Y1379543D03*
X1124375Y1423488D03*
X1124415Y1426168D03*
Y1428668D03*
Y1431168D03*
Y1433668D03*
X1115098Y1468871D03*
Y1472271D03*
X1124875Y1490042D03*
X1125498Y1487292D03*
X1116917Y1506823D03*
X1119912Y1506936D03*
X1116917Y1509898D03*
X1119912Y1509891D03*
Y1515644D03*
X1116917D03*
X1119912Y1512644D03*
X1116917D03*
X1114617Y1526318D03*
X1113887Y1543447D03*
X1119459Y1556343D03*
X1118133Y1587998D03*
Y1591398D03*
X1115027Y1598788D03*
X1117247Y1604554D03*
X1113847D03*
X1124532Y1634915D03*
X1114286Y1630507D03*
X1117136Y1630441D03*
X1113490Y1651862D03*
X1112500Y1671107D03*
X1125784Y1662705D03*
X1124394Y1658967D03*
X1120595D03*
X1126000Y1672419D03*
X1122610Y1677976D03*
X1124091Y1683983D03*
X1114414Y1698859D03*
X1114394Y1695936D03*
X1119361Y1713734D03*
X1113948Y1711244D03*
X1126902Y60805D03*
X1142144Y63186D03*
X1132340Y468202D03*
Y471702D03*
X1141267Y500296D03*
X1134567Y513870D03*
X1139360Y516031D03*
X1129387Y615658D03*
X1138387D03*
X1132855Y609373D03*
X1135387Y615658D03*
X1130017Y766870D03*
X1127803Y1302861D03*
Y1300361D03*
Y1305361D03*
Y1307861D03*
Y1310361D03*
Y1312861D03*
X1139703Y1302861D03*
Y1300361D03*
Y1305361D03*
Y1307861D03*
Y1310361D03*
Y1312861D03*
X1127803Y1317861D03*
Y1315361D03*
X1139703Y1317861D03*
Y1315361D03*
X1135139Y1368999D03*
Y1371540D03*
X1131549Y1373158D03*
X1136632Y1379914D03*
X1138912Y1376389D03*
X1127283Y1379188D03*
X1129449Y1377558D03*
X1127283Y1376288D03*
X1129349Y1374558D03*
X1131549Y1378958D03*
Y1376058D03*
X1129965Y1403877D03*
X1127465D03*
X1129965Y1401377D03*
X1127465D03*
X1132465Y1403877D03*
Y1401377D03*
X1129925Y1398737D03*
X1127425D03*
X1134925D03*
X1132425D03*
X1137425D03*
X1137465Y1401377D03*
X1134965D03*
Y1403877D03*
X1137465D03*
X1137275Y1424138D03*
X1134775D03*
X1132275D03*
X1126875Y1423488D03*
X1129775Y1424138D03*
X1140175Y1423488D03*
X1140215Y1428668D03*
Y1426168D03*
X1134815Y1433668D03*
X1137315D03*
X1140215D03*
Y1431168D03*
X1132315Y1433668D03*
X1137315Y1426818D03*
X1134815D03*
X1137345Y1431058D03*
X1134845D03*
X1132315Y1426818D03*
X1132345Y1431058D03*
X1126915Y1428668D03*
Y1426168D03*
X1129815Y1433668D03*
X1126915D03*
Y1431168D03*
X1129815Y1426818D03*
X1129845Y1431058D03*
X1131478Y1485427D03*
X1134183Y1483926D03*
X1126951Y1484646D03*
X1140960Y1489434D03*
Y1491934D03*
X1141045Y1534952D03*
Y1537452D03*
Y1544952D03*
Y1542452D03*
Y1539952D03*
X1135033Y1556112D03*
X1142639Y1562789D03*
X1133765Y1568952D03*
X1140655Y1569256D03*
X1137755Y1569543D03*
X1138480Y1576364D03*
X1140422Y1595455D03*
X1139037Y1611383D03*
X1131824Y1600593D03*
Y1603993D03*
X1140325Y1598697D03*
X1139037Y1614153D03*
X1139142Y1618859D03*
X1139188Y1621603D03*
X1132981Y1634531D03*
X1141084Y1646672D03*
Y1643272D03*
X1137542Y1647925D03*
X1134207Y1669230D03*
X1129184Y1662705D03*
X1132406Y1658967D03*
X1136575Y1676239D03*
X1141356Y1676542D03*
X1133206Y1675383D03*
X1132176Y1690038D03*
X1142643Y74738D03*
X1151679Y72258D03*
X1150118Y207344D03*
X1155268D03*
Y212344D03*
X1150118D03*
X1155890Y478812D03*
X1150577Y478840D03*
X1144663Y492319D03*
Y500319D03*
X1151036Y501627D03*
X1143060Y516476D03*
X1154145Y583339D03*
Y586339D03*
X1146160Y767299D03*
Y771099D03*
X1155282Y766806D03*
X1142203Y1300361D03*
Y1302861D03*
X1144703D03*
Y1300361D03*
X1142203Y1305361D03*
X1144703D03*
X1155503Y1312861D03*
Y1310361D03*
Y1307861D03*
X1142203D03*
Y1310361D03*
Y1312861D03*
X1144703D03*
Y1310361D03*
Y1307861D03*
X1155503Y1302861D03*
Y1300361D03*
Y1305361D03*
Y1315361D03*
X1142203D03*
X1144703D03*
X1142203Y1317861D03*
X1144703D03*
X1155503D03*
X1152359Y1372853D03*
X1154789D03*
X1141901Y1382574D03*
Y1380066D03*
X1149343Y1382111D03*
X1145855Y1380511D03*
X1148593Y1379543D03*
X1142675Y1423488D03*
X1145715Y1423555D03*
X1145755Y1426235D03*
Y1428735D03*
Y1431235D03*
Y1433735D03*
X1142715Y1426168D03*
Y1428668D03*
Y1431168D03*
Y1433668D03*
X1150718Y1462792D03*
X1153724Y1462695D03*
X1154824Y1471134D03*
X1145960Y1491934D03*
X1148460D03*
X1150960D03*
X1153460D03*
X1155960D03*
X1145960Y1489434D03*
X1148460D03*
X1150960D03*
X1153460D03*
X1155960D03*
X1143460D03*
Y1491934D03*
X1153545Y1534952D03*
X1151045D03*
X1148545D03*
X1146045D03*
X1143545D03*
X1153545Y1537452D03*
X1151045D03*
X1148545D03*
X1146045D03*
X1143545D03*
X1151045Y1544952D03*
X1148545D03*
X1146045D03*
X1143545D03*
X1153545D03*
X1143545Y1542452D03*
X1146045D03*
X1148545D03*
X1151045D03*
X1153545D03*
Y1539952D03*
X1151045D03*
X1148545D03*
X1146045D03*
X1143545D03*
X1155253Y1559176D03*
X1147814Y1562823D03*
X1154336Y1555979D03*
X1149467Y1568988D03*
X1142917Y1583314D03*
Y1586714D03*
X1155180Y1655534D03*
X1146501Y1655608D03*
Y1652208D03*
X1158343Y1658514D03*
X1152198Y1669629D03*
X1151985Y1666685D03*
X1151707Y1663655D03*
X1152114Y1672517D03*
X1154500Y1677000D03*
X1142033Y1682412D03*
X1152211Y1682373D03*
X1162086Y76509D03*
X1162144Y487630D03*
X1158764Y489516D03*
X1162067Y570050D03*
X1166131Y580602D03*
X1157038Y583298D03*
Y586298D03*
X1166026Y669006D03*
X1159718Y766870D03*
X1158003Y1307861D03*
Y1310361D03*
Y1312861D03*
Y1300361D03*
Y1302861D03*
Y1305361D03*
X1160503Y1302861D03*
Y1300361D03*
Y1305361D03*
Y1307861D03*
Y1310361D03*
Y1312861D03*
X1158003Y1315361D03*
Y1317861D03*
X1160503D03*
Y1315361D03*
X1168039Y1368999D03*
Y1371540D03*
X1157219Y1372853D03*
X1158059Y1367018D03*
Y1369918D03*
X1164249Y1373158D03*
X1169532Y1379914D03*
X1164249Y1376058D03*
X1159983Y1376288D03*
X1162049Y1374558D03*
X1164249Y1378958D03*
X1159983Y1379188D03*
X1162149Y1377558D03*
X1160163Y1445627D03*
X1163422Y1445000D03*
X1166350Y1454234D03*
X1160750Y1463250D03*
X1164300Y1463300D03*
X1159283Y1471132D03*
X1158460Y1491934D03*
Y1489434D03*
X1170986Y1516590D03*
Y1513190D03*
Y1534990D03*
Y1538390D03*
X1169061Y1543800D03*
X1170061Y1551040D03*
X1163485Y1546195D03*
X1161492Y1551175D03*
X1164528Y1565578D03*
X1170404Y1556331D03*
Y1559731D03*
X1166873Y1561431D03*
X1157255Y1556000D03*
X1170539Y1595621D03*
X1168023Y1586251D03*
X1170539Y1588751D03*
X1168023D03*
X1170539Y1586251D03*
Y1583751D03*
Y1600621D03*
Y1598121D03*
X1170339Y1603121D03*
X1165806Y1658934D03*
X1159688Y1665427D03*
X1169098Y1666278D03*
X1159703Y1673000D03*
X1159500Y1679000D03*
Y1682500D03*
X1177404Y-21711D03*
Y-18311D03*
X1184194Y57015D03*
Y61515D03*
X1185913Y93634D03*
X1174031Y403519D03*
X1181000Y402500D03*
X1175181Y447841D03*
Y442341D03*
X1185952Y444202D03*
Y436202D03*
X1178340Y447734D03*
Y442234D03*
X1176000Y436500D03*
X1180000Y436000D03*
X1175181Y458841D03*
Y464341D03*
Y453341D03*
X1185952Y452202D03*
X1178340Y458734D03*
X1178254Y453142D03*
X1178340Y461615D03*
X1175181Y469841D03*
X1186040Y481691D03*
X1178340Y467165D03*
X1175181Y481691D03*
X1182950Y577030D03*
X1178000Y572602D03*
X1182594Y587759D03*
X1178000Y592673D03*
X1183811Y640682D03*
X1182256Y632368D03*
X1182713Y733815D03*
X1175860Y767299D03*
Y771099D03*
X1184960Y766870D03*
X1172603Y1302861D03*
Y1300361D03*
Y1305361D03*
Y1307861D03*
Y1310361D03*
Y1312861D03*
X1175103Y1300361D03*
Y1302861D03*
X1177603D03*
Y1300361D03*
X1175103Y1305361D03*
X1177603D03*
X1175103Y1307861D03*
Y1310361D03*
Y1312861D03*
X1177603D03*
Y1310361D03*
Y1307861D03*
X1175103Y1315361D03*
X1177603D03*
X1172603Y1317861D03*
Y1315361D03*
X1175103Y1317861D03*
X1177603D03*
X1185259Y1372853D03*
X1174801Y1382574D03*
Y1380066D03*
X1182243Y1382111D03*
X1178755Y1380511D03*
X1181493Y1379543D03*
X1171812Y1376389D03*
X1184900Y1428500D03*
X1183000Y1422900D03*
X1184175Y1435600D03*
X1176500Y1457071D03*
X1180200Y1457100D03*
X1183924Y1485895D03*
X1180624Y1495595D03*
X1177224D03*
X1178039Y1595621D03*
X1175539D03*
X1173039D03*
X1180923Y1588751D03*
Y1586251D03*
X1173039Y1588751D03*
X1175539D03*
X1178039D03*
Y1586251D03*
X1175539D03*
X1173039D03*
X1178039Y1583751D03*
X1175539D03*
X1173039D03*
X1178039Y1600621D03*
X1175539D03*
X1173039D03*
X1178039Y1598121D03*
X1175539D03*
X1173039D03*
X1175339Y1603121D03*
X1172839D03*
X1177839D03*
X1184362Y1670254D03*
X1181385Y1670312D03*
X1175726Y1686726D03*
X1195488Y93550D03*
X1190587Y99694D03*
X1199756Y128748D03*
X1189727Y164987D03*
Y160987D03*
X1200037Y177187D03*
X1200012Y181187D03*
X1186821Y185430D03*
Y181930D03*
X1195767Y460202D03*
Y470392D03*
Y465272D03*
X1193040Y481691D03*
X1191087Y573809D03*
X1199370Y578154D03*
X1195236Y581407D03*
X1188267Y571807D03*
X1199392Y590500D03*
X1195336Y586606D03*
X1200923Y601734D03*
Y606134D03*
X1199539Y638492D03*
X1197039D03*
X1194539D03*
X1192039D03*
X1195108Y668148D03*
X1198456Y668138D03*
X1190903Y1307861D03*
Y1310361D03*
Y1312861D03*
X1188403D03*
Y1310361D03*
Y1307861D03*
Y1302861D03*
Y1300361D03*
Y1305361D03*
X1190903Y1300361D03*
Y1302861D03*
X1193403D03*
Y1300361D03*
X1190903Y1305361D03*
X1193403D03*
Y1307861D03*
Y1310361D03*
Y1312861D03*
X1190903Y1315361D03*
X1188403D03*
Y1317861D03*
X1190903D03*
X1193403D03*
Y1315361D03*
X1200839Y1368999D03*
Y1371540D03*
X1190119Y1372853D03*
X1191049Y1367188D03*
Y1370088D03*
X1187689Y1372853D03*
X1197149Y1373158D03*
X1192883Y1379188D03*
X1195049Y1377558D03*
X1197149Y1378958D03*
X1192883Y1376288D03*
X1194949Y1374558D03*
X1197149Y1376058D03*
X1194296Y1396500D03*
X1194000Y1401000D03*
Y1414500D03*
X1203242Y1417440D03*
X1194366Y1405500D03*
X1193929Y1410000D03*
X1202548Y1407453D03*
X1202857Y1412454D03*
X1191000Y1425900D03*
X1198800Y1421500D03*
X1202411Y1427410D03*
X1194000Y1424000D03*
X1203117Y1422452D03*
X1202475Y1432468D03*
X1188000Y1419800D03*
X1194000Y1437500D03*
X1203040D03*
X1194000Y1442500D03*
Y1447500D03*
X1187324Y1485895D03*
X1200724Y1505295D03*
X1197324D03*
X1188960Y1609135D03*
X1186455Y1608390D03*
Y1602590D03*
Y1605490D03*
X1190174Y1615418D03*
X1190616Y1670641D03*
X1190314Y1661630D03*
X1199299Y1675517D03*
X1197746Y1680914D03*
X1199272Y1683025D03*
X1189263Y1682551D03*
X1190830Y1675710D03*
X1197612Y1703334D03*
X1192612D03*
X1199612Y1691366D03*
X1189462Y1700334D03*
X1194478Y1699936D03*
X1189407Y1717518D03*
X1205929Y86872D03*
X1206580Y94846D03*
X1208431Y133866D03*
Y128748D03*
X1214094Y258633D03*
Y269008D03*
Y282948D03*
Y287948D03*
X1205625Y313758D03*
X1210698Y313671D03*
X1207447Y341381D03*
X1202508Y341424D03*
X1212700Y475712D03*
X1206590Y481403D03*
X1203269Y481237D03*
X1212051Y559827D03*
X1208733Y585986D03*
X1205900Y582443D03*
X1206191Y588400D03*
X1205679Y594148D03*
X1209796Y668115D03*
X1204334Y668138D03*
X1205630Y766600D03*
X1207903Y1300361D03*
Y1302861D03*
X1210403D03*
Y1300361D03*
X1207903Y1305361D03*
X1210403D03*
X1207903Y1307861D03*
Y1310361D03*
Y1312861D03*
X1210403D03*
Y1310361D03*
Y1307861D03*
X1205403Y1302861D03*
Y1300361D03*
Y1305361D03*
Y1307861D03*
Y1310361D03*
Y1312861D03*
X1207903Y1315361D03*
X1210403D03*
X1205403Y1317861D03*
Y1315361D03*
X1207903Y1317861D03*
X1210403D03*
X1202332Y1379914D03*
X1207601Y1380066D03*
X1215043Y1382111D03*
X1211555Y1380511D03*
X1214293Y1379543D03*
X1207601Y1382574D03*
X1204612Y1376389D03*
X1211000Y1392125D03*
X1211075Y1395200D03*
X1210100Y1436500D03*
X1213000Y1435000D03*
X1210400Y1440000D03*
X1214900Y1439800D03*
X1214124Y1485895D03*
X1210724D03*
X1207424Y1495595D03*
X1204024D03*
X1202697Y1673059D03*
X1205604Y1685400D03*
Y1682200D03*
Y1679000D03*
Y1675800D03*
X1212954Y1703343D03*
X1214954Y1691375D03*
X1204804Y1700343D03*
X1207954Y1703343D03*
X1207770Y1706861D03*
Y1720861D03*
X1205638Y1732766D03*
X1227803Y94210D03*
X1221411Y134230D03*
X1221512Y128239D03*
X1220931Y131307D03*
X1222094Y258633D03*
X1230094D03*
Y269008D03*
X1222094D03*
X1230094Y287948D03*
Y282948D03*
X1222094D03*
Y297066D03*
Y292066D03*
Y314216D03*
Y305216D03*
X1226094Y314216D03*
X1218430Y421012D03*
X1219325Y438151D03*
X1216300Y475682D03*
X1228372Y688501D03*
X1221203Y1312861D03*
Y1310361D03*
Y1307861D03*
X1223703D03*
Y1310361D03*
Y1312861D03*
Y1300361D03*
Y1302861D03*
Y1305361D03*
X1221203Y1302861D03*
Y1300361D03*
Y1305361D03*
Y1315361D03*
X1223703D03*
Y1317861D03*
X1221203D03*
X1222919Y1372853D03*
X1220489D03*
X1223889Y1367188D03*
Y1370088D03*
X1218059Y1372853D03*
X1229949Y1373158D03*
X1228800Y1391300D03*
X1225683Y1379188D03*
X1227849Y1377558D03*
X1225683Y1376288D03*
X1227749Y1374558D03*
X1229949Y1378958D03*
Y1376058D03*
X1227000Y1401300D03*
X1219650Y1392050D03*
X1219500Y1398900D03*
X1224200Y1393500D03*
X1227000Y1404500D03*
X1219500Y1436000D03*
X1221837Y1438800D03*
X1229661Y1442000D03*
X1226200Y1444300D03*
X1222700Y1446300D03*
X1220200Y1449100D03*
X1227524Y1505295D03*
X1224124D03*
X1230824Y1495595D03*
X1219738Y1713861D03*
Y1708861D03*
X1216738Y1717011D03*
X1219738Y1722861D03*
Y1727861D03*
X1216738Y1731011D03*
X1238769Y75320D03*
X1233668Y132739D03*
Y128239D03*
X1247834Y159844D03*
X1238094Y258633D03*
X1246094Y269008D03*
X1238094D03*
X1234000Y385500D03*
X1233468Y419742D03*
X1242429Y431255D03*
Y427255D03*
Y435255D03*
X1236879Y449755D03*
X1242429Y439255D03*
X1232081Y460580D03*
X1242692Y483435D03*
X1236100Y773844D03*
X1233084Y772582D03*
X1235215Y777213D03*
X1231397Y769667D03*
X1243207Y779428D03*
X1241057Y782278D03*
X1244986Y787578D03*
X1244127Y784598D03*
X1238257Y779728D03*
X1243294Y1269197D03*
Y1266697D03*
Y1261697D03*
Y1264197D03*
X1243308Y1271754D03*
X1238830Y1322853D03*
Y1325394D03*
X1240323Y1333768D03*
X1245592Y1333920D03*
Y1336428D03*
X1242603Y1330243D03*
X1239800Y1389500D03*
X1235400Y1391200D03*
X1238500Y1400900D03*
X1234900Y1404400D03*
X1233700Y1395600D03*
X1238200Y1395500D03*
X1244300Y1403500D03*
X1235679Y1418908D03*
X1239242Y1418462D03*
X1238731Y1422362D03*
X1239550Y1437050D03*
X1240924Y1485895D03*
X1237524D03*
X1234224Y1495595D03*
X1245840Y1689D03*
Y-1711D03*
X1249152Y72895D03*
X1253152Y84895D03*
X1255661Y90470D03*
X1253152Y95525D03*
X1259472Y92864D03*
X1252693Y124739D03*
X1249431Y137739D03*
X1249065Y241594D03*
Y236594D03*
Y251594D03*
Y246594D03*
X1246094Y258633D03*
X1254094D03*
X1262094Y269008D03*
X1254094D03*
X1262094Y282948D03*
X1254094D03*
X1262094Y287948D03*
X1250285Y303307D03*
X1259659Y389456D03*
X1260107Y399125D03*
X1260227Y415128D03*
X1256137Y459182D03*
Y453872D03*
X1245752Y470733D03*
X1250975Y474945D03*
X1248130Y783354D03*
X1251177Y784488D03*
X1254981Y787578D03*
X1256447Y798828D03*
X1259297Y798784D03*
X1251177Y794878D03*
X1257527Y808938D03*
X1260427Y809008D03*
X1259194Y1251697D03*
Y1246697D03*
Y1254197D03*
Y1249197D03*
X1248294Y1259197D03*
Y1256697D03*
X1245794Y1259197D03*
X1259194Y1269215D03*
Y1261715D03*
Y1264215D03*
Y1266715D03*
X1245894Y1269215D03*
X1248394D03*
X1245894Y1261715D03*
Y1264215D03*
Y1266715D03*
X1248394D03*
Y1264215D03*
Y1261715D03*
X1259194Y1256697D03*
Y1259197D03*
X1248308Y1271754D03*
X1245808D03*
X1259108D03*
X1256050Y1326707D03*
X1258480D03*
X1253034Y1335965D03*
X1249546Y1334365D03*
X1252284Y1333397D03*
X1249600Y1403425D03*
X1257594Y1417000D03*
X1253100Y1413500D03*
X1256224Y1430075D03*
X1256600Y1434500D03*
X1254324Y1505295D03*
X1250924D03*
X1257624Y1495595D03*
X1275981Y85114D03*
X1263472Y92864D03*
X1269146Y121022D03*
X1263146D03*
X1267037Y180565D03*
Y175030D03*
X1268941Y206017D03*
X1269360Y219632D03*
X1261969Y219505D03*
X1262094Y258633D03*
X1270094D03*
Y269008D03*
Y282948D03*
Y292066D03*
X1268174Y395125D03*
X1275585Y393597D03*
X1269840Y411128D03*
X1270483Y433148D03*
Y435648D03*
X1265227Y454372D03*
X1262457Y798814D03*
X1266677Y802988D03*
X1266568Y809078D03*
X1275177Y808963D03*
X1263647Y809118D03*
X1271177Y808963D03*
X1261694Y1251697D03*
X1264194D03*
Y1246697D03*
X1261694D03*
Y1254197D03*
X1264194D03*
X1261694Y1249197D03*
X1264194D03*
X1261694Y1269215D03*
Y1266715D03*
Y1264215D03*
Y1261715D03*
X1264194Y1269197D03*
Y1256697D03*
Y1259197D03*
Y1261697D03*
X1261694Y1256697D03*
Y1259197D03*
X1264194Y1264197D03*
Y1266697D03*
X1264108Y1271754D03*
X1261608D03*
X1271726Y1322825D03*
Y1325366D03*
X1260910Y1326707D03*
X1262050Y1320878D03*
Y1323778D03*
X1267940Y1327012D03*
X1265740Y1328412D03*
X1273219Y1333740D03*
X1275499Y1330215D03*
X1267940Y1332812D03*
Y1329912D03*
X1265840Y1331412D03*
X1263674Y1330142D03*
Y1333042D03*
X1271042Y1418748D03*
X1266996Y1423617D03*
X1262310Y1428303D03*
X1267724Y1485895D03*
X1264324D03*
X1261024Y1495595D03*
X1275195Y1552250D03*
X1275170Y1579519D03*
X1269310Y1583170D03*
X1287486Y134165D03*
X1278050Y152912D03*
X1278137Y166051D03*
X1278211Y161030D03*
Y156030D03*
X1278137Y180565D03*
Y176051D03*
Y171551D03*
Y184987D03*
X1279447Y213292D03*
X1286094Y258633D03*
X1278094D03*
Y269008D03*
X1286094D03*
X1278094Y282948D03*
X1286094D03*
X1278094Y287948D03*
X1286094Y292066D03*
X1290127Y401125D03*
Y410635D03*
X1289352Y418550D03*
Y421950D03*
X1281190Y1254112D03*
X1276190D03*
X1278690D03*
X1281190Y1249112D03*
Y1251612D03*
X1276190D03*
X1278690D03*
X1276190Y1249112D03*
X1278690D03*
X1281190Y1246612D03*
X1276190D03*
X1278690D03*
X1276190Y1269112D03*
Y1266612D03*
X1281190Y1259112D03*
Y1256612D03*
X1276190D03*
Y1259112D03*
Y1261612D03*
Y1264112D03*
X1278690Y1256612D03*
Y1259112D03*
X1278790Y1269130D03*
X1281290D03*
X1278790Y1261630D03*
Y1264130D03*
Y1266630D03*
X1281290D03*
Y1264130D03*
Y1261630D03*
X1281204Y1271669D03*
X1278704D03*
X1276204D03*
X1288946Y1326679D03*
X1278488Y1333892D03*
X1285930Y1335937D03*
X1282442Y1334337D03*
X1285180Y1333369D03*
X1278488Y1336400D03*
X1287600Y1423100D03*
Y1427600D03*
X1276500Y1432000D03*
X1279525D03*
X1287700Y1431700D03*
X1277724Y1485895D03*
X1281124D03*
X1288494Y1517082D03*
Y1513682D03*
Y1530482D03*
Y1527082D03*
X1287961Y1542469D03*
X1287372Y1552845D03*
X1287647Y1545220D03*
Y1549120D03*
X1277017Y1544953D03*
Y1547453D03*
Y1549953D03*
X1281470Y1552845D03*
X1281347Y1549120D03*
Y1545220D03*
X1284497Y1549120D03*
Y1545220D03*
X1284510Y1554436D03*
X1277702D03*
X1289919Y1582295D03*
Y1574795D03*
Y1579795D03*
Y1577295D03*
X1287419Y1582295D03*
Y1579795D03*
X1284919D03*
Y1582295D03*
X1282419D03*
Y1579795D03*
X1299196Y76209D03*
X1305685Y74748D03*
X1296200Y66911D03*
X1305091Y123680D03*
Y127830D03*
Y131750D03*
X1301582Y166051D03*
X1301743Y162055D03*
X1301582Y171551D03*
Y184051D03*
X1302094Y258633D03*
X1294094D03*
Y269008D03*
X1302094D03*
X1294094Y287948D03*
Y282948D03*
X1302094D03*
Y292066D03*
X1302069Y303184D03*
X1299026Y389355D03*
X1302226D03*
X1295519Y389561D03*
X1304347Y523237D03*
X1302160Y524916D03*
X1304566Y525743D03*
X1301642Y537299D03*
X1293581Y542716D03*
X1294938Y561331D03*
X1300400Y599413D03*
X1297400D03*
X1298000Y657500D03*
X1303250Y655149D03*
X1295000Y655200D03*
X1292297Y657206D03*
X1302500Y664500D03*
X1305100Y662100D03*
X1301900Y660699D03*
X1294590Y1254112D03*
X1297090D03*
X1292090D03*
Y1249112D03*
X1294590D03*
X1297090D03*
X1292090Y1251612D03*
X1294590D03*
X1297090D03*
X1292090Y1246612D03*
X1297090D03*
X1294590D03*
X1292090Y1269130D03*
X1294590D03*
X1292090Y1261630D03*
Y1264130D03*
Y1266630D03*
X1294590D03*
Y1264130D03*
Y1261630D03*
X1297090Y1269112D03*
Y1256612D03*
Y1259112D03*
Y1261612D03*
X1294590Y1256612D03*
Y1259112D03*
X1297090Y1264112D03*
Y1266612D03*
X1292090Y1256612D03*
Y1259112D03*
X1297004Y1271669D03*
X1292004D03*
X1294504D03*
X1304630Y1322768D03*
Y1325309D03*
X1293806Y1326679D03*
X1291376D03*
X1294956Y1320934D03*
Y1323834D03*
X1300836Y1326984D03*
X1298636Y1328384D03*
X1296570Y1330114D03*
Y1333014D03*
X1298736Y1331384D03*
X1300836Y1329884D03*
Y1332784D03*
X1296000Y1427700D03*
X1301900D03*
X1295700Y1421800D03*
X1300800D03*
X1291700Y1431700D03*
X1302390Y1530430D03*
X1297490Y1526910D03*
X1297620Y1529534D03*
X1291897Y1545076D03*
X1290461Y1542469D03*
X1291897Y1547576D03*
X1302915Y1563596D03*
X1298466Y1556331D03*
Y1559731D03*
X1292419Y1582295D03*
Y1579795D03*
Y1574795D03*
Y1577295D03*
X1294919D03*
Y1574795D03*
X1294387Y1571682D03*
X1291887D03*
X1301789Y1574795D03*
X1304289D03*
X1301789Y1577295D03*
X1304289D03*
Y1579795D03*
X1301789D03*
X1304289Y1582295D03*
X1301789D03*
X1299289Y1574795D03*
Y1582295D03*
Y1579795D03*
Y1577295D03*
X1295877Y1581199D03*
X1298382Y1584844D03*
X1295877Y1584099D03*
X1293459Y1584844D03*
X1320020Y66979D03*
X1308110Y66911D03*
X1307857Y103353D03*
X1313951Y104739D03*
X1311045D03*
X1313011Y135820D03*
Y139845D03*
X1306300Y203917D03*
X1318094Y258633D03*
X1310094D03*
Y269008D03*
X1318094D03*
X1310094Y287948D03*
Y282948D03*
X1318094D03*
X1305426Y389355D03*
X1308926Y524111D03*
X1306815Y522726D03*
X1307117Y525897D03*
X1309870Y552788D03*
X1309776Y559831D03*
X1317266Y597213D03*
X1310544Y613100D03*
X1313544Y610100D03*
X1310544D03*
X1313544Y607100D03*
X1310544D03*
X1313544Y604100D03*
X1310544D03*
X1307544Y610100D03*
Y613100D03*
Y604100D03*
Y607100D03*
X1317266Y600213D03*
X1309166Y601713D03*
X1308776Y599181D03*
X1313544Y613100D03*
X1310544Y616100D03*
X1313544D03*
X1307544D03*
X1308800Y619200D03*
Y622200D03*
Y625200D03*
X1318300D03*
Y622200D03*
Y619200D03*
X1307700Y664600D03*
X1309600Y667700D03*
X1315657Y1199532D03*
Y1196132D03*
X1311715Y1221042D03*
X1318776Y1219566D03*
X1311594Y1251612D03*
X1309094D03*
X1311594Y1254112D03*
X1309094D03*
X1311594Y1246612D03*
X1309094D03*
X1311594Y1249112D03*
X1309094D03*
X1314094Y1246612D03*
Y1251612D03*
Y1249112D03*
Y1254112D03*
X1309090Y1269169D03*
Y1266669D03*
Y1261669D03*
Y1264169D03*
X1314194Y1269130D03*
Y1266630D03*
Y1264130D03*
Y1261630D03*
X1311694Y1269130D03*
Y1261630D03*
Y1264130D03*
Y1266630D03*
X1311594Y1259112D03*
Y1256612D03*
X1309094Y1259112D03*
Y1256612D03*
X1314094D03*
Y1259112D03*
X1309090Y1271669D03*
X1311590D03*
X1314090D03*
X1306123Y1333683D03*
X1311392Y1333835D03*
X1318834Y1335880D03*
X1315346Y1334280D03*
X1318084Y1333312D03*
X1311392Y1336343D03*
X1308403Y1330158D03*
X1308900Y1525510D03*
X1306789Y1574795D03*
Y1582295D03*
Y1579795D03*
Y1577295D03*
X1310914Y1577299D03*
X1331930Y66945D03*
X1327541Y105227D03*
X1337399Y98084D03*
X1333399D03*
X1334094Y258633D03*
X1326094D03*
Y269008D03*
X1334094D03*
Y287948D03*
X1326094Y282948D03*
X1334094D03*
X1326094Y292066D03*
X1328427Y349452D03*
X1329585Y561806D03*
X1325366Y597213D03*
Y600213D03*
X1321300Y619200D03*
Y622200D03*
Y625200D03*
X1326636Y656800D03*
X1322420Y656867D03*
X1332812Y856383D03*
X1325543Y871161D03*
X1329244D03*
X1334301Y867765D03*
X1328992Y1209788D03*
X1327029Y1206788D03*
X1331202Y1206478D03*
X1323169Y1208995D03*
X1333977Y1222158D03*
X1325137Y1210653D03*
X1324901Y1216419D03*
X1322141Y1217365D03*
X1327494Y1246612D03*
Y1251612D03*
Y1249112D03*
Y1254112D03*
X1324994Y1246612D03*
Y1251612D03*
Y1249112D03*
Y1254112D03*
X1329994Y1246612D03*
Y1251612D03*
Y1249112D03*
Y1254112D03*
X1324994Y1269130D03*
Y1261630D03*
Y1264130D03*
Y1266630D03*
X1327494Y1269130D03*
Y1266630D03*
Y1264130D03*
Y1261630D03*
Y1259112D03*
Y1256612D03*
X1324994Y1259112D03*
Y1256612D03*
X1329994Y1259112D03*
Y1256612D03*
Y1266612D03*
Y1264112D03*
Y1261612D03*
Y1269112D03*
X1327490Y1271669D03*
X1324990D03*
X1329990D03*
X1326710Y1326622D03*
X1324280D03*
X1321850D03*
X1327876Y1320934D03*
Y1323834D03*
X1333740Y1326927D03*
X1331540Y1328327D03*
X1333740Y1329827D03*
Y1332727D03*
X1331640Y1331327D03*
X1329474Y1330057D03*
Y1332957D03*
X1322539Y1411278D03*
X1322499Y1413788D03*
X1325499D03*
X1325539Y1411278D03*
Y1416446D03*
X1322539D03*
X1328539Y1411278D03*
X1328499Y1413788D03*
X1328539Y1416446D03*
X1331509Y1416486D03*
X1334509D03*
X1331509Y1408818D03*
X1334509Y1411318D03*
X1334469Y1413828D03*
X1334509Y1408818D03*
X1331469Y1413828D03*
X1331509Y1411318D03*
X1325579Y1418976D03*
X1322579D03*
X1325609Y1421496D03*
X1322609D03*
X1328579Y1418976D03*
X1328609Y1421496D03*
X1331579Y1421536D03*
X1331549Y1419016D03*
X1334579Y1421536D03*
X1334549Y1419016D03*
X1343840Y66911D03*
X1341399Y98084D03*
X1348199D03*
X1342094Y258633D03*
Y269008D03*
X1350094D03*
Y287948D03*
X1342094Y282948D03*
X1350094D03*
X1342094Y292066D03*
X1340257Y677765D03*
Y675111D03*
X1336812Y856383D03*
X1341301Y867765D03*
X1337801D03*
X1341301Y871265D03*
X1344801D03*
X1348301D03*
X1340948Y1177681D03*
X1342507Y1187848D03*
X1340948Y1181681D03*
X1349012Y1204971D03*
X1342036Y1206429D03*
Y1203029D03*
X1346063Y1217729D03*
Y1214329D03*
X1341590Y1254169D03*
Y1251669D03*
Y1249169D03*
Y1246669D03*
X1344090Y1254169D03*
Y1251669D03*
Y1249169D03*
Y1246669D03*
X1346590Y1254169D03*
Y1249169D03*
Y1251669D03*
Y1246669D03*
X1341690Y1269269D03*
Y1264269D03*
Y1266769D03*
Y1261769D03*
X1341590Y1256669D03*
Y1259169D03*
X1344190Y1269187D03*
X1346690D03*
X1344190Y1261687D03*
Y1264187D03*
Y1266687D03*
X1346690D03*
Y1264187D03*
Y1261687D03*
X1344090Y1256669D03*
Y1259169D03*
X1346590D03*
Y1256669D03*
X1341690Y1271769D03*
X1346690D03*
X1344190D03*
X1337430Y1322968D03*
Y1325509D03*
X1338923Y1333883D03*
X1344192Y1334035D03*
X1348146Y1334480D03*
X1344192Y1336543D03*
X1341203Y1330358D03*
X1340556Y1383674D03*
Y1386674D03*
X1337556D03*
Y1383674D03*
X1346556Y1386674D03*
Y1383674D03*
X1343556Y1386674D03*
Y1383674D03*
X1349556D03*
Y1386674D03*
X1337555Y1389658D03*
X1343712Y1389804D03*
X1348712D03*
X1346212D03*
X1341212D03*
X1348823Y1409626D03*
X1348853Y1413866D03*
X1346323Y1409626D03*
X1346353Y1413866D03*
X1343823Y1409626D03*
X1343853Y1413866D03*
X1346509Y1416486D03*
X1349509D03*
X1343509D03*
X1341323Y1409626D03*
X1341353Y1413866D03*
X1337509Y1416486D03*
Y1411318D03*
X1337469Y1413828D03*
X1337509Y1408818D03*
X1340509Y1416486D03*
X1349579Y1421536D03*
X1349549Y1419016D03*
X1346579Y1421536D03*
X1346549Y1419016D03*
X1343549D03*
X1343579Y1421536D03*
X1337579D03*
X1337549Y1419016D03*
X1340579Y1421536D03*
X1340549Y1419016D03*
X1355750Y66886D03*
X1360109Y98050D03*
X1352199D03*
X1364369Y120380D03*
X1358094Y258633D03*
X1350094D03*
X1358094Y269008D03*
X1366094D03*
Y287948D03*
X1358094Y282948D03*
X1366094D03*
X1358094Y292066D03*
X1363857Y626579D03*
X1361427D03*
X1354397Y623374D03*
Y626274D03*
X1356597Y624874D03*
X1358663Y623144D03*
X1356497Y621874D03*
X1354397Y620474D03*
X1358663Y620244D03*
X1360964Y629514D03*
Y632414D03*
X1358461Y684151D03*
Y686651D03*
X1360961Y684073D03*
Y686573D03*
X1363461D03*
Y684073D03*
X1363435Y681573D03*
X1358435D03*
X1360935D03*
X1358461Y694151D03*
X1363461D03*
X1360961D03*
X1358461Y689151D03*
Y691651D03*
X1363461Y696651D03*
X1360961D03*
X1363461Y699151D03*
X1360961Y691573D03*
X1363461D03*
X1360961Y689073D03*
X1363461D03*
X1362523Y1015473D03*
Y1022559D03*
Y1019016D03*
X1355222Y1200561D03*
X1361285Y1206718D03*
X1355641Y1210674D03*
X1362810Y1211071D03*
X1357490Y1254169D03*
Y1249169D03*
Y1251669D03*
Y1246669D03*
X1359990Y1254169D03*
X1362490D03*
X1359990Y1249169D03*
X1362490D03*
X1359990Y1251669D03*
X1362490D03*
Y1246669D03*
X1359990D03*
Y1269187D03*
Y1266687D03*
Y1264187D03*
Y1261687D03*
X1357490Y1269187D03*
Y1261687D03*
Y1264187D03*
Y1266687D03*
Y1256669D03*
Y1259169D03*
X1362490Y1269269D03*
Y1261769D03*
Y1266769D03*
Y1264269D03*
Y1256669D03*
Y1259169D03*
X1359990Y1256669D03*
Y1259169D03*
X1357490Y1271769D03*
X1362490D03*
X1359990D03*
X1359510Y1326822D03*
X1360724Y1321184D03*
Y1324084D03*
X1357080Y1326822D03*
X1354650D03*
X1364340Y1328527D03*
X1351634Y1336080D03*
X1350884Y1333512D03*
X1364440Y1337527D03*
Y1331527D03*
Y1334527D03*
X1362274Y1330257D03*
Y1333157D03*
Y1336057D03*
X1352226Y1386804D03*
Y1383804D03*
X1352225Y1389788D03*
X1358509Y1416486D03*
Y1413818D03*
Y1411318D03*
Y1408818D03*
X1352509Y1416486D03*
Y1411318D03*
Y1413818D03*
Y1408818D03*
X1355509Y1416486D03*
Y1411318D03*
Y1413818D03*
Y1408818D03*
X1352579Y1421536D03*
X1352549Y1419016D03*
X1355549D03*
X1367950Y66886D03*
X1377682Y87587D03*
X1368109Y98000D03*
X1366094Y258633D03*
X1373862Y485552D03*
Y511052D03*
X1381457Y511050D03*
X1376757Y619497D03*
X1369303Y617321D03*
X1372791Y618921D03*
X1370053Y619889D03*
X1376745Y616858D03*
X1379734Y623043D03*
X1366287Y626579D03*
X1376761Y686573D03*
Y684073D03*
X1374261D03*
Y686573D03*
X1374245Y681573D03*
X1376745D03*
X1376761Y694151D03*
X1374261D03*
X1376761Y696651D03*
X1374261D03*
X1376761Y699151D03*
X1374261D03*
X1376761Y701651D03*
X1374261D03*
X1376761Y691573D03*
Y689073D03*
X1374261Y691573D03*
Y689073D03*
X1376761Y706651D03*
Y704151D03*
X1374261Y706651D03*
Y704151D03*
X1377483Y1015473D03*
X1370003D03*
X1377483Y1022559D03*
Y1019016D03*
X1370003Y1022559D03*
Y1019016D03*
X1370685Y1223032D03*
Y1226432D03*
X1374476Y1266143D03*
X1376976D03*
X1379476D03*
X1374476Y1268643D03*
X1376976D03*
X1379476D03*
X1374476Y1273643D03*
Y1271143D03*
X1374576Y1283743D03*
Y1281243D03*
X1374476Y1276143D03*
Y1278643D03*
X1376976Y1273643D03*
Y1271143D03*
X1379476Y1273643D03*
Y1271143D03*
X1377076Y1281161D03*
Y1283661D03*
X1379576D03*
Y1281161D03*
X1376976Y1276143D03*
Y1278643D03*
X1379476D03*
Y1276143D03*
X1379576Y1288661D03*
X1377076Y1286161D03*
X1379576D03*
X1377076Y1288661D03*
X1379576Y1291243D03*
X1377076D03*
X1374576Y1288743D03*
Y1286243D03*
Y1291243D03*
X1370012Y1342299D03*
X1371505Y1353214D03*
X1376774Y1353366D03*
X1370012Y1344840D03*
X1376774Y1355874D03*
X1373785Y1349689D03*
X1382045Y1700038D03*
X1379804Y1733118D03*
X1383715Y236594D03*
Y241594D03*
X1381457Y485550D03*
X1382014Y619518D03*
X1383507Y627892D03*
Y630433D03*
X1387097Y656274D03*
X1389297Y657774D03*
X1391363Y656044D03*
X1387097Y653374D03*
X1389197Y654774D03*
X1391363Y653144D03*
X1394127Y659479D03*
X1387097Y659174D03*
X1393664Y662384D03*
Y665284D03*
X1393343Y716971D03*
X1390807Y717053D03*
X1390817Y714471D03*
X1393317D03*
X1393343Y719471D03*
X1390807Y719553D03*
X1393367Y727023D03*
Y729523D03*
X1393343Y724471D03*
Y721971D03*
X1390807Y722053D03*
Y724553D03*
X1390853Y727053D03*
X1391460Y1009764D03*
Y1006024D03*
Y1013504D03*
Y1020985D03*
Y1024725D03*
Y1028465D03*
Y1017244D03*
X1390376Y1268643D03*
X1392876D03*
Y1283661D03*
Y1281161D03*
X1390376D03*
Y1283661D03*
Y1273643D03*
Y1271143D03*
Y1276143D03*
Y1278643D03*
X1392876Y1273643D03*
Y1271143D03*
Y1276143D03*
Y1278643D03*
Y1288661D03*
Y1286161D03*
X1390376Y1288661D03*
Y1286161D03*
Y1291243D03*
X1392876D03*
X1393306Y1340515D03*
Y1343415D03*
X1384216Y1355411D03*
X1380728Y1353811D03*
X1383466Y1352843D03*
X1392092Y1346153D03*
X1389662D03*
X1387232D03*
X1385068Y1664907D03*
X1390738Y1664938D03*
X1392068Y1676875D03*
X1381918D03*
X1391750Y1697747D03*
X1382045Y1704038D03*
X1390045Y1712038D03*
X1390179Y1733118D03*
X1404917Y116911D03*
X1395302Y251136D03*
Y256136D03*
X1411000Y460362D03*
X1406500Y458362D03*
X1400500Y458377D03*
X1409445Y652266D03*
X1402003Y650221D03*
X1405491Y651821D03*
X1402753Y652789D03*
X1409445Y649758D03*
X1398987Y659479D03*
X1396557D03*
X1409143Y716971D03*
X1395843D03*
X1406643D03*
X1409127Y714471D03*
X1395817D03*
X1406627D03*
X1409143Y719471D03*
X1395843D03*
X1406643D03*
X1395867Y732023D03*
Y727023D03*
Y729523D03*
X1406667Y727023D03*
X1409167Y732023D03*
Y729523D03*
X1406667Y732023D03*
Y729523D03*
X1409167Y727023D03*
X1409143Y724471D03*
Y721971D03*
X1395843Y724471D03*
Y721971D03*
X1406643Y724471D03*
Y721971D03*
X1409167Y739523D03*
Y734523D03*
Y737023D03*
X1406667Y734523D03*
Y737023D03*
Y739523D03*
X1401015Y1014744D03*
X1399953Y1005799D03*
X1403693D03*
X1407433D03*
X1401015Y1023012D03*
Y1018878D03*
X1407433Y1032430D03*
X1403693D03*
X1395060Y1032205D03*
X1399953Y1032430D03*
X1395376Y1268643D03*
Y1273643D03*
Y1271143D03*
Y1281243D03*
Y1283743D03*
Y1276143D03*
Y1278643D03*
Y1288743D03*
Y1286243D03*
Y1291243D03*
X1399122Y1352258D03*
X1394856Y1352488D03*
X1399122Y1346458D03*
Y1349358D03*
X1396922Y1347858D03*
X1394856Y1349588D03*
X1397022Y1350858D03*
X1405811Y1430021D03*
X1409532Y1552845D03*
X1409409Y1549120D03*
Y1545220D03*
X1403257Y1552250D03*
X1405079Y1549953D03*
Y1544953D03*
Y1547453D03*
X1405764Y1554436D03*
X1403232Y1579519D03*
X1397030Y1594060D03*
X1409286Y1605796D03*
X1406666Y1616332D03*
X1400029Y1615796D03*
X1406447Y1619572D03*
X1396783Y1617170D03*
X1408023Y1638705D03*
X1398058Y1628651D03*
X1408208D03*
X1406814Y1652439D03*
X1399599Y1657583D03*
X1398883Y1680341D03*
X1410750Y244583D03*
X1417000Y460362D03*
X1419335Y533958D03*
X1414714Y653008D03*
X1412434Y655943D03*
X1416207Y663333D03*
Y660792D03*
X1421797Y687354D03*
X1423963Y685724D03*
X1419697Y685954D03*
X1421897Y690354D03*
X1423963Y688624D03*
X1419697Y688854D03*
Y691754D03*
X1423417Y747051D03*
X1423407Y757133D03*
Y749633D03*
Y752133D03*
Y754633D03*
X1416301Y970340D03*
Y977840D03*
Y985340D03*
X1414576Y989765D03*
X1414501Y993765D03*
Y997765D03*
X1410858Y1014744D03*
X1418653Y1005799D03*
X1414913D03*
X1411173D03*
X1414501Y1001765D03*
X1419716Y1014744D03*
X1422394Y1005799D03*
X1410858Y1023012D03*
X1419716D03*
X1410858Y1018878D03*
X1419716D03*
X1422394Y1032430D03*
X1419026Y1038765D03*
Y1042765D03*
X1414913Y1032430D03*
X1418653D03*
X1411173D03*
X1417301Y1051540D03*
X1418982Y1175144D03*
X1414165Y1289564D03*
X1414172Y1286188D03*
X1415434Y1552845D03*
X1415709Y1545220D03*
Y1549120D03*
X1418523Y1542469D03*
X1419959Y1545076D03*
Y1547576D03*
X1416023Y1542469D03*
X1412559Y1549120D03*
Y1545220D03*
X1412572Y1554436D03*
X1417981Y1568680D03*
X1423531Y1574795D03*
Y1582295D03*
Y1579795D03*
Y1577295D03*
X1424621Y1571911D03*
Y1569411D03*
X1416862Y1582871D03*
X1419811Y1599084D03*
X1416709Y1592819D03*
X1413836Y1586944D03*
X1412467Y1602234D03*
X1419914Y1602777D03*
X1418000Y1607500D03*
X1422154Y1626270D03*
X1423722Y1616780D03*
X1419622Y1616000D03*
X1422266Y1628947D03*
X1411113Y1637767D03*
X1421890Y1635500D03*
X1418755Y1654999D03*
X1410315Y1646967D03*
X1424315D03*
X1436263Y1689D03*
Y-1711D03*
X1434262Y52892D03*
X1438262D03*
X1431262Y61392D03*
X1439049Y107443D03*
X1429169Y107313D03*
X1431300Y538800D03*
X1435400Y536200D03*
X1431400Y533400D03*
X1435400Y530800D03*
X1434603Y682801D03*
X1438091Y684401D03*
X1435353Y685369D03*
X1431617Y692359D03*
X1429187D03*
X1426757D03*
X1426264Y694954D03*
Y697854D03*
X1439227Y747051D03*
X1425917D03*
X1428417D03*
X1428407Y762133D03*
Y759633D03*
X1425907D03*
X1439257Y762133D03*
Y759633D03*
X1425943Y757051D03*
X1428443D03*
X1425943Y749551D03*
Y752051D03*
Y754551D03*
X1428443D03*
Y752051D03*
Y749551D03*
X1439243Y757051D03*
Y749551D03*
Y752051D03*
Y754551D03*
X1439257Y764633D03*
Y769633D03*
Y767133D03*
X1429952Y1014744D03*
X1433614Y1005799D03*
X1426134D03*
X1429874D03*
X1429952Y1023012D03*
Y1018878D03*
X1426134Y1032430D03*
X1433614D03*
X1429874D03*
X1435160Y1516590D03*
Y1513190D03*
Y1534990D03*
Y1538390D03*
X1434235Y1550240D03*
X1433235Y1543800D03*
X1430735D03*
X1431735Y1550240D03*
X1434578Y1556331D03*
Y1559731D03*
X1430213Y1553652D03*
X1427713D03*
X1426031Y1582295D03*
X1431031Y1574795D03*
Y1577295D03*
X1426031Y1579795D03*
Y1577295D03*
Y1574795D03*
X1428531D03*
Y1577295D03*
Y1579795D03*
Y1582295D03*
X1430431Y1570595D03*
X1427931D03*
X1437901Y1579795D03*
Y1577295D03*
Y1574795D03*
Y1582295D03*
X1435401D03*
Y1579795D03*
Y1577295D03*
Y1574795D03*
X1431989Y1581199D03*
X1434494Y1584844D03*
X1431989Y1584099D03*
X1429571Y1584844D03*
X1430244Y1609966D03*
X1438565Y1612583D03*
X1434316Y1616909D03*
X1430238Y1617137D03*
X1437594Y1616845D03*
X1426899Y1616990D03*
X1429072Y1643655D03*
X1433911Y1649037D03*
X1433618Y1659331D03*
X1433157Y1651977D03*
X1436311Y1665948D03*
X1438078Y1669992D03*
X1439316Y1675080D03*
X1435904Y1694335D03*
X1443049Y107443D03*
X1448549Y114643D03*
X1446040Y120218D03*
X1452040Y113018D03*
X1440871Y152166D03*
X1454769Y163842D03*
X1444769D03*
Y174217D03*
X1453974Y174414D03*
X1449769Y174217D03*
X1439769D03*
Y182217D03*
X1449769D03*
X1456500Y457000D03*
X1441053Y560535D03*
X1441898Y576755D03*
X1452708Y610954D03*
Y607954D03*
X1449708Y610954D03*
X1446708D03*
Y607954D03*
X1449708D03*
X1440708Y610954D03*
X1443708D03*
X1440708Y607954D03*
X1443708D03*
X1452708Y613954D03*
X1446708Y616954D03*
Y619954D03*
X1440708D03*
Y616954D03*
X1443708D03*
Y619954D03*
X1449708Y613954D03*
X1446708D03*
X1440708D03*
X1443708D03*
X1446708Y622954D03*
X1440708D03*
X1443708D03*
X1452938Y617364D03*
X1450438D03*
X1452898Y621844D03*
X1450398D03*
X1448996Y645270D03*
Y647770D03*
X1451496Y645270D03*
X1453996D03*
Y647770D03*
X1451496D03*
X1449046Y650370D03*
X1454046D03*
X1451546D03*
X1446426D03*
X1443926D03*
X1443876Y645270D03*
Y647770D03*
X1446376Y645270D03*
Y647770D03*
X1447314Y684998D03*
X1442091Y684846D03*
X1442045Y682338D03*
X1448807Y695913D03*
Y693372D03*
X1445034Y688523D03*
X1452615Y705531D03*
X1441727Y747051D03*
X1444257Y757133D03*
Y759633D03*
Y762133D03*
X1441757Y759633D03*
Y762133D03*
X1441743Y757051D03*
Y754551D03*
Y752051D03*
Y749551D03*
X1444257Y772133D03*
Y764633D03*
Y769633D03*
Y767133D03*
X1441757Y772133D03*
Y764633D03*
Y769633D03*
Y767133D03*
X1442107Y1013504D03*
Y1009764D03*
Y1006024D03*
Y1020985D03*
Y1024725D03*
Y1028465D03*
Y1017244D03*
Y1032205D03*
X1451498Y1485895D03*
X1448098D03*
X1444798Y1495595D03*
X1441398D03*
X1439850Y1541470D03*
X1440401Y1574795D03*
Y1582295D03*
Y1579795D03*
Y1577295D03*
X1442901Y1582295D03*
Y1579795D03*
Y1577295D03*
Y1574795D03*
X1447026Y1577299D03*
X1448061Y1593055D03*
X1451000Y1601000D03*
X1446000Y1600500D03*
X1450500Y1614500D03*
Y1624000D03*
X1445500Y1614500D03*
X1441000D03*
X1440027Y1667945D03*
X1455579Y1665701D03*
X1453553Y1686892D03*
X1445079Y1686678D03*
X1449070Y1686722D03*
X1448000Y1676000D03*
X1464830Y59054D03*
X1466681Y78590D03*
X1454549Y107443D03*
X1455667Y125733D03*
X1463017Y139518D03*
X1456226Y152166D03*
X1462682Y450372D03*
X1456982Y437362D03*
X1466609Y458608D03*
X1465395Y487582D03*
X1465832Y530656D03*
X1463647Y544977D03*
X1464257Y560977D03*
Y557498D03*
X1462497Y555021D03*
X1464257Y568977D03*
Y572977D03*
Y580977D03*
Y576977D03*
X1467708Y610954D03*
Y607954D03*
X1464708Y610954D03*
Y607954D03*
X1458708Y610954D03*
X1455708D03*
X1461708D03*
Y607954D03*
X1455708D03*
X1458708D03*
X1467708Y616954D03*
Y619954D03*
Y613954D03*
X1461708Y616954D03*
Y619954D03*
X1464708Y616954D03*
Y619954D03*
Y613954D03*
X1458708D03*
X1455708D03*
X1461708D03*
X1467708Y622954D03*
X1461708D03*
X1464708D03*
X1455438Y617364D03*
X1457938D03*
X1455398Y621844D03*
X1457898D03*
X1456496Y645270D03*
X1459396D03*
X1456496Y647770D03*
X1459396D03*
X1456546Y650370D03*
X1459446D03*
X1467521Y702378D03*
X1454715Y700931D03*
X1468271Y704946D03*
X1462045Y711826D03*
X1464475D03*
X1459615D03*
X1456881Y708201D03*
Y705301D03*
X1454715Y706931D03*
Y703931D03*
X1454815Y709931D03*
X1458777Y714194D03*
Y717094D03*
X1456335Y771710D03*
Y766628D03*
X1458861Y776628D03*
X1461361D03*
X1458861Y769128D03*
Y771628D03*
Y774128D03*
X1461361D03*
Y771628D03*
Y769128D03*
X1461335Y766628D03*
X1458835D03*
X1456335Y776710D03*
Y774210D03*
Y769210D03*
X1461371Y791696D03*
Y789196D03*
X1458871Y779196D03*
X1461371D03*
X1458871Y784196D03*
Y781696D03*
Y786696D03*
X1461371Y784196D03*
Y786696D03*
Y781696D03*
X1456371Y779210D03*
Y781710D03*
Y784210D03*
X1456945Y1015473D03*
X1464526D03*
X1456945Y1019016D03*
Y1022559D03*
X1464526Y1019016D03*
Y1022559D03*
X1464898Y1505295D03*
X1461498D03*
X1468198Y1495595D03*
X1468102Y1670817D03*
X1458795Y1687083D03*
X1457940Y1675710D03*
X1463038Y1687060D03*
X1466111Y1685098D03*
X1472129Y56083D03*
X1483820Y132405D03*
X1471395Y487582D03*
X1473947Y492169D03*
X1472647Y539478D03*
X1475257Y530656D03*
X1473444Y555208D03*
X1473408Y547948D03*
X1478147Y547728D03*
X1478257Y543977D03*
X1481257Y544977D03*
X1482044Y542517D03*
X1472257Y551241D03*
X1472757Y561264D03*
X1473362Y558380D03*
X1472257Y564977D03*
X1481898Y585476D03*
X1484347Y580388D03*
X1478258Y588108D03*
Y584142D03*
X1474963Y701915D03*
X1480232Y704575D03*
X1475009Y704488D03*
X1481725Y715490D03*
X1471009Y703978D03*
X1481725Y712949D03*
X1477952Y708100D03*
X1477171Y774196D03*
Y771696D03*
Y769196D03*
Y776696D03*
X1474661Y776628D03*
Y774128D03*
Y771628D03*
Y769128D03*
X1472161Y776628D03*
Y769128D03*
Y771628D03*
Y774128D03*
X1472145Y766628D03*
X1474645D03*
X1477145D03*
X1477171Y791696D03*
X1474671D03*
X1472171D03*
X1477171Y786696D03*
X1474671D03*
X1477171Y781696D03*
X1474671D03*
X1472171Y789196D03*
Y779196D03*
Y784196D03*
Y786696D03*
Y781696D03*
X1477171Y789196D03*
X1474671D03*
X1477171Y779196D03*
X1474671D03*
X1477171Y784196D03*
X1474671D03*
X1481177Y803488D03*
X1469950Y813232D03*
X1473728Y813552D03*
X1480677Y813488D03*
X1484177Y812988D03*
X1474177Y816872D03*
X1471526Y1015473D03*
Y1019016D03*
Y1022559D03*
X1478298Y1485895D03*
X1474898D03*
X1471598Y1495595D03*
X1482798Y1685982D03*
X1469588Y1673342D03*
X1486000Y1686000D03*
X1470500Y1685500D03*
X1494891Y121171D03*
X1488647Y134562D03*
X1497386Y464980D03*
X1495682Y473302D03*
X1484395Y487582D03*
X1492514Y539657D03*
X1484416Y541658D03*
X1488510Y542816D03*
X1490602Y544755D03*
X1497310Y543960D03*
X1494967Y541898D03*
X1487660Y585748D03*
X1491677Y583588D03*
X1490677Y580688D03*
X1492789Y576602D03*
X1495236Y612838D03*
X1495486Y599938D03*
X1497986Y602438D03*
Y599938D03*
X1495236Y605338D03*
X1495486Y602438D03*
X1495236Y607838D03*
Y610338D03*
X1492636Y605258D03*
Y607758D03*
Y610258D03*
Y612758D03*
X1497986Y612838D03*
Y605338D03*
Y607838D03*
Y610338D03*
X1495486Y615988D03*
Y618488D03*
X1497986Y615988D03*
Y618488D03*
X1492886Y618408D03*
Y615908D03*
X1497587Y711636D03*
X1495157D03*
X1492727D03*
X1489963Y705301D03*
X1487797Y706931D03*
X1487897Y709931D03*
X1489963Y708201D03*
X1485697Y708431D03*
Y705531D03*
Y711331D03*
X1492264Y714544D03*
Y717444D03*
X1491943Y776628D03*
X1494443D03*
X1491943Y769128D03*
Y771628D03*
Y774128D03*
X1494443D03*
Y771628D03*
Y769128D03*
X1494417Y766628D03*
X1491917D03*
X1489417Y776710D03*
Y774210D03*
Y769210D03*
Y771710D03*
Y766628D03*
X1494487Y779210D03*
Y784210D03*
Y786710D03*
Y781710D03*
X1491987Y779210D03*
Y784210D03*
Y786710D03*
Y781710D03*
X1489487Y779210D03*
Y784210D03*
Y786710D03*
Y781710D03*
X1500500Y809063D03*
X1496532Y803513D03*
X1485177Y803488D03*
X1489177Y812988D03*
X1487923Y816770D03*
X1490973Y825557D03*
X1498177Y829359D03*
X1495670Y826073D03*
X1486761Y826279D03*
X1493260Y1167390D03*
X1496960D03*
X1491698Y1505295D03*
X1488298D03*
X1498398Y1495595D03*
X1494998D03*
X1488875Y1677385D03*
X1503785Y464815D03*
X1505974Y470636D03*
X1511917Y483878D03*
X1499752Y488424D03*
X1502085Y545432D03*
X1507109Y550059D03*
X1507644Y554372D03*
X1507468Y564357D03*
X1506337Y561677D03*
X1502757Y570977D03*
X1508281Y559390D03*
X1509757Y575477D03*
X1501821Y577664D03*
X1502986Y602438D03*
Y599938D03*
X1500486Y602438D03*
Y599938D03*
X1502486Y605338D03*
Y607838D03*
Y610338D03*
Y612838D03*
X1500486Y615988D03*
Y618488D03*
X1502986Y615988D03*
Y618488D03*
X1500603Y702378D03*
X1508045Y701915D03*
X1513314Y704575D03*
X1508045Y704423D03*
X1504091Y703978D03*
X1501353Y704946D03*
X1511034Y708100D03*
X1510287Y771710D03*
Y769210D03*
Y774210D03*
Y776710D03*
X1507743Y776628D03*
Y774128D03*
Y771628D03*
Y769128D03*
X1505243Y776628D03*
Y769128D03*
Y771628D03*
Y774128D03*
X1505227Y766628D03*
X1507727D03*
X1510227D03*
X1507787Y786710D03*
Y781710D03*
X1505287Y779210D03*
Y784210D03*
Y786710D03*
Y781710D03*
X1510287Y779210D03*
Y784210D03*
Y786710D03*
Y781710D03*
X1507787Y779210D03*
Y784210D03*
X1508177Y803488D03*
X1501500Y799948D03*
X1510261Y814611D03*
X1500422Y814180D03*
X1512523Y809679D03*
X1502177Y817013D03*
X1512539Y812920D03*
X1505016Y817107D03*
X1501636Y828796D03*
X1499469Y860322D03*
Y863322D03*
X1504362Y1167390D03*
X1508063D03*
X1505098Y1485895D03*
X1501698D03*
X1515854Y119810D03*
X1517708Y216505D03*
X1527392Y238017D03*
X1519120Y479215D03*
X1515936Y484412D03*
X1516757Y537477D03*
X1516257Y547977D03*
X1516336Y551977D03*
X1519457Y556338D03*
X1519317Y561977D03*
X1527853Y560264D03*
X1524777Y605488D03*
Y607988D03*
X1527277Y605488D03*
Y607988D03*
X1524777Y610588D03*
X1527277D03*
X1524777Y613088D03*
X1527277D03*
X1524777Y615618D03*
X1527277D03*
X1524777Y618118D03*
X1527277D03*
X1514807Y715490D03*
Y712949D03*
X1525527Y711636D03*
X1527957D03*
X1522763Y708201D03*
Y705301D03*
X1518497Y705531D03*
X1520597Y706931D03*
X1518497Y708431D03*
X1520697Y709931D03*
X1518497Y711331D03*
X1525064Y714544D03*
Y717444D03*
X1522217Y771710D03*
X1527217Y766628D03*
X1522217Y769210D03*
X1524717Y766628D03*
X1522217D03*
Y774210D03*
Y776710D03*
X1524743Y776628D03*
X1527243D03*
X1524743Y769128D03*
Y771628D03*
Y774128D03*
X1527243D03*
Y771628D03*
Y769128D03*
X1527217Y779210D03*
Y784210D03*
Y786710D03*
Y781710D03*
X1524717Y779210D03*
X1522217D03*
X1524717Y784210D03*
Y786710D03*
X1522217Y784210D03*
Y786710D03*
X1524717Y781710D03*
X1522217D03*
X1517431Y811466D03*
X1521003Y1169488D03*
X1521217Y1190088D03*
X1524425Y1185241D03*
X1528498Y1485895D03*
X1518498Y1505295D03*
X1525198Y1495595D03*
X1515098Y1505295D03*
X1521798Y1495595D03*
X1538342Y28406D03*
X1540342Y48720D03*
X1537450Y226293D03*
X1533160Y231250D03*
X1536538Y296819D03*
X1536422Y292816D03*
X1536542Y308819D03*
X1534584Y467067D03*
X1539693Y543613D03*
X1532824Y555981D03*
X1539693Y558943D03*
X1532730Y562949D03*
X1534565Y564945D03*
X1533403Y702378D03*
X1540845Y701915D03*
Y704423D03*
X1536891Y703978D03*
X1534153Y704946D03*
X1543834Y708100D03*
X1530387Y711636D03*
X1538027Y766628D03*
X1540527D03*
X1540543Y776628D03*
Y774128D03*
Y771628D03*
Y769128D03*
X1538043Y776628D03*
Y769128D03*
Y771628D03*
Y774128D03*
X1538027Y784710D03*
Y779210D03*
X1540527D03*
X1538027Y781710D03*
X1540527D03*
X1539972Y807319D03*
X1529306Y1177468D03*
X1540801Y1178265D03*
X1537301D03*
X1539301Y1175765D03*
X1532896Y1234836D03*
X1542747Y1253602D03*
X1538587Y1245065D03*
X1543772Y1241016D03*
X1543519Y1248205D03*
X1536916Y1240844D03*
X1531898Y1485895D03*
X1541898D03*
X1543582Y1524562D03*
X1541191Y1544953D03*
Y1547453D03*
Y1549953D03*
X1539369Y1552250D03*
X1541876Y1554436D03*
X1539344Y1579519D03*
X1552674Y26477D03*
X1556379Y19541D03*
X1549274Y26477D03*
X1554360Y207251D03*
X1556960Y287478D03*
X1551900Y287288D03*
X1544489Y288816D03*
X1546789Y287116D03*
X1548772Y291916D03*
X1553154Y479063D03*
X1558198Y486791D03*
X1551779Y530698D03*
X1546149Y541169D03*
X1545987Y562012D03*
X1553657Y678965D03*
X1553827Y687991D03*
X1556027Y680391D03*
X1555893Y686261D03*
Y683361D03*
X1553657Y681965D03*
X1553727Y684991D03*
X1558657Y689696D03*
X1558194Y695501D03*
Y692501D03*
X1546114Y704575D03*
X1547607Y715490D03*
Y712949D03*
X1556708Y747282D03*
X1556688Y744688D03*
X1556708Y749782D03*
Y754782D03*
Y752282D03*
Y757282D03*
Y762282D03*
Y759782D03*
Y764782D03*
Y769782D03*
Y767282D03*
X1556121Y798542D03*
X1551124Y801289D03*
X1551961Y807269D03*
X1556361D03*
X1547561D03*
X1551113Y1238088D03*
X1548360Y1234750D03*
X1550517Y1232905D03*
X1545627Y1254068D03*
X1545480Y1245090D03*
X1544911Y1260654D03*
X1543980Y1258312D03*
X1554692Y1269688D03*
X1557559Y1269095D03*
X1557510Y1280291D03*
X1554377Y1278763D03*
X1560454Y1279004D03*
X1553226Y1288814D03*
X1553548Y1284991D03*
X1556515Y1292232D03*
X1555222Y1302757D03*
X1547195Y1478165D03*
X1547216Y1480812D03*
X1545298Y1485895D03*
X1545473Y1522117D03*
X1547548Y1520070D03*
X1552668Y1513682D03*
Y1517082D03*
Y1530482D03*
Y1527082D03*
X1551821Y1549120D03*
Y1545220D03*
X1551546Y1552845D03*
X1556071Y1547576D03*
X1554635Y1542469D03*
X1552135D03*
X1556071Y1545076D03*
X1545644Y1552845D03*
X1545521Y1549120D03*
Y1545220D03*
X1548671Y1549120D03*
Y1545220D03*
X1548684Y1554436D03*
X1554093Y1582295D03*
Y1574795D03*
Y1579795D03*
Y1577295D03*
X1551593Y1582295D03*
Y1579795D03*
X1556593Y1582295D03*
Y1579795D03*
Y1574795D03*
Y1577295D03*
X1549093Y1579795D03*
Y1582295D03*
X1546593D03*
Y1579795D03*
X1558560Y1571682D03*
X1556060D03*
X1557633Y1584844D03*
X1566847Y26477D03*
X1559779Y19541D03*
X1570552D03*
X1563447Y26477D03*
X1572502Y254250D03*
X1572549Y257491D03*
X1566442Y294816D03*
X1564506Y310334D03*
Y313734D03*
X1571516Y319099D03*
X1568070Y497847D03*
X1573070D03*
X1570570D03*
X1570068Y534095D03*
X1573326Y543351D03*
X1573487Y546996D03*
X1572436Y578933D03*
X1568446Y582733D03*
X1572436Y582433D03*
X1564946Y582733D03*
X1561246Y580393D03*
X1572436Y574022D03*
X1568936Y585933D03*
Y589433D03*
X1565436Y585933D03*
Y589433D03*
X1562016Y584283D03*
Y587783D03*
X1572436Y589433D03*
Y585933D03*
X1566533Y680438D03*
X1570021Y682038D03*
X1567283Y683006D03*
X1563517Y689696D03*
X1561087D03*
X1572514Y747188D03*
X1561714D03*
X1559214D03*
X1561688Y744688D03*
X1559188D03*
X1572498D03*
X1572588Y757282D03*
Y759782D03*
X1561708Y757282D03*
X1559208D03*
X1561708Y759782D03*
X1559208D03*
X1561708Y762282D03*
X1559208D03*
X1572514Y752188D03*
Y749688D03*
Y754688D03*
X1561714Y749688D03*
Y752188D03*
X1559214D03*
Y749688D03*
X1561714Y754688D03*
X1559214D03*
X1561708Y769782D03*
X1559208D03*
X1561708Y767282D03*
X1559208D03*
X1561708Y764782D03*
X1559208D03*
X1570583Y800104D03*
X1572668Y806778D03*
X1567737Y1271411D03*
X1561927Y1269901D03*
X1559181Y1287165D03*
X1568100Y1290418D03*
X1567000Y1293446D03*
X1562820Y1309360D03*
X1568456Y1311533D03*
X1572416Y1303160D03*
X1564268Y1338440D03*
X1562937Y1341609D03*
X1572331Y1348205D03*
X1566901Y1347726D03*
X1564758Y1367834D03*
X1572906Y1366759D03*
X1563967Y1363205D03*
X1572860Y1495595D03*
X1569460D03*
X1563222Y1516590D03*
Y1513190D03*
Y1534990D03*
Y1538390D03*
X1567089Y1563596D03*
X1562640Y1556331D03*
Y1559731D03*
X1559093Y1577295D03*
Y1574795D03*
X1565963D03*
X1568463D03*
X1565963Y1577295D03*
X1568463D03*
Y1579795D03*
X1565963D03*
X1568463Y1582295D03*
X1565963D03*
X1570963Y1574795D03*
Y1582295D03*
Y1579795D03*
Y1577295D03*
X1563463Y1574795D03*
Y1582295D03*
Y1579795D03*
Y1577295D03*
X1560051Y1581199D03*
X1574966Y1577038D03*
X1562556Y1584844D03*
X1560051Y1584099D03*
X1588125Y19541D03*
X1581020Y26477D03*
X1573952Y19541D03*
X1584725D03*
X1577620Y26477D03*
X1586291Y303596D03*
X1586621Y484304D03*
X1580519Y497650D03*
X1575570Y497847D03*
X1584397Y655622D03*
X1586497Y651222D03*
X1586597Y654222D03*
X1584397Y652722D03*
Y649822D03*
X1573975Y679975D03*
X1579244Y682635D03*
X1573975Y682483D03*
X1576964Y686160D03*
X1580737Y693550D03*
Y691009D03*
X1577588Y747282D03*
X1575014Y747188D03*
X1577498Y744688D03*
X1574998D03*
X1575088Y757282D03*
X1577588Y749782D03*
Y754782D03*
Y752282D03*
X1575014Y749688D03*
Y752188D03*
Y754688D03*
X1578690Y1283310D03*
X1585290Y1285098D03*
X1574168Y1283300D03*
X1577077Y1270937D03*
X1580577D03*
X1584068Y1271198D03*
X1580010Y1296100D03*
X1574560Y1296410D03*
X1580520Y1289900D03*
X1586167Y1295478D03*
X1575024Y1306373D03*
X1586557Y1304509D03*
X1578336Y1359253D03*
X1578411Y1348623D03*
X1578020Y1344773D03*
X1584156Y1381419D03*
X1586000Y1387641D03*
X1590723Y1381589D03*
X1579560Y1485895D03*
X1576160D03*
X1602299Y19541D03*
X1595194Y26477D03*
X1598899Y19541D03*
X1591794Y26477D03*
X1603970Y222956D03*
X1593303Y234250D03*
Y239250D03*
X1598303Y234250D03*
X1596462Y229790D03*
X1593658Y252010D03*
X1593303Y244250D03*
X1593349Y248160D03*
X1597481Y271991D03*
X1600918Y521688D03*
X1604890Y531226D03*
X1596299Y536344D03*
X1599303Y646669D03*
X1602791Y648269D03*
X1600053Y649237D03*
X1596287Y655927D03*
X1591427D03*
X1593857D03*
X1588663Y649592D03*
Y652492D03*
X1590964Y661741D03*
Y658741D03*
X1594844Y713419D03*
Y715919D03*
X1592344D03*
Y713419D03*
X1594818Y710919D03*
X1594844Y718419D03*
X1592344D03*
X1594844Y720919D03*
X1592344D03*
X1594688Y723512D03*
Y726012D03*
Y728512D03*
Y731012D03*
X1592188Y723512D03*
Y726012D03*
Y728512D03*
Y731012D03*
X1594688Y736012D03*
X1592188D03*
X1594688Y733512D03*
X1592188D03*
X1594900Y780112D03*
X1598467Y1267539D03*
X1588832Y1269083D03*
X1597177Y1282288D03*
X1594152Y1282578D03*
X1598883Y1270766D03*
X1590827Y1271378D03*
X1593397Y1271458D03*
X1596273Y1271472D03*
X1591005Y1288892D03*
X1596363Y1286296D03*
X1590921Y1309276D03*
X1599241Y1306622D03*
X1589845Y1305289D03*
X1599007Y1309762D03*
X1597621Y1365384D03*
X1595438Y1370603D03*
X1592788Y1388318D03*
X1597234Y1382689D03*
X1600531Y1404710D03*
X1597992Y1433183D03*
X1595716Y1431861D03*
X1602782Y1435920D03*
X1600442Y1434535D03*
X1602960Y1485895D03*
X1592960Y1505295D03*
X1599660Y1495595D03*
X1589560Y1505295D03*
X1596260Y1495595D03*
X1615020Y183050D03*
X1619909Y298742D03*
Y293742D03*
X1612144Y418552D03*
X1614701Y422587D03*
X1616464Y457509D03*
X1616250Y465042D03*
X1609166Y527300D03*
X1611775D03*
X1609166Y524700D03*
X1611775D03*
X1613169Y531819D03*
X1604991Y536344D03*
X1616084Y549105D03*
X1616198Y556364D03*
X1618859Y542820D03*
X1618356Y612137D03*
Y609137D03*
X1618434Y605753D03*
X1609044Y600986D03*
X1617397Y630822D03*
Y636622D03*
Y633722D03*
X1606745Y646206D03*
X1612014Y648866D03*
X1606745Y648714D03*
X1613507Y657240D03*
X1609734Y652391D03*
X1613507Y659781D03*
X1605644Y715919D03*
Y713419D03*
X1608144D03*
Y715919D03*
X1605628Y710919D03*
X1608128D03*
X1610628D03*
X1610718Y713513D03*
Y716013D03*
X1605644Y718419D03*
Y720919D03*
X1608144Y718419D03*
Y720919D03*
X1610718Y721013D03*
Y718513D03*
X1608118Y723512D03*
X1605618D03*
X1608118Y726012D03*
X1605618D03*
X1610618Y723512D03*
X1605618Y728512D03*
X1617200Y766870D03*
X1607267Y1271978D03*
X1604137Y1271358D03*
X1605801Y1286168D03*
X1608901Y1285887D03*
X1605360Y1294595D03*
X1608652Y1303338D03*
X1608341Y1313269D03*
X1608418Y1333589D03*
Y1331089D03*
X1614767Y1443512D03*
X1605648Y1437305D03*
X1606360Y1485895D03*
X1616360Y1505295D03*
X1622329Y28261D03*
X1631060Y26477D03*
X1627660D03*
X1623189Y48720D03*
X1631200Y164110D03*
X1631455Y167875D03*
X1627152Y168920D03*
X1629597Y227157D03*
X1627156Y238303D03*
X1627986Y282728D03*
X1627909Y286742D03*
Y298742D03*
Y294742D03*
Y290742D03*
X1619909Y303596D03*
X1627909Y302742D03*
X1621680Y366920D03*
X1625000Y383399D03*
X1631657Y392925D03*
X1632012Y603015D03*
X1621512D03*
X1625012D03*
X1628512D03*
X1632303Y627669D03*
X1633053Y630237D03*
X1626857Y636927D03*
X1629287D03*
X1624427D03*
X1621663Y630592D03*
X1619597Y635222D03*
X1621663Y633492D03*
X1619497Y632222D03*
X1623964Y642741D03*
Y639741D03*
X1627643Y694419D03*
Y696919D03*
Y699419D03*
X1625143D03*
Y696919D03*
Y694419D03*
X1627643Y701919D03*
X1625143D03*
X1627617Y691919D03*
X1625117D03*
Y709512D03*
Y704512D03*
Y707012D03*
Y712012D03*
X1627617Y709512D03*
Y704512D03*
Y707012D03*
Y712012D03*
X1628046Y763765D03*
X1626928Y1260917D03*
X1629428D03*
X1631928D03*
X1626333Y1311091D03*
Y1308091D03*
X1627174Y1420450D03*
X1625285Y1433384D03*
X1635281Y1422450D03*
X1627217Y1428366D03*
X1622697Y1440797D03*
X1625170Y1444016D03*
X1635227Y1436528D03*
X1633160Y1485895D03*
X1629760D03*
X1619760Y1505295D03*
X1626460Y1495595D03*
X1623060D03*
X1645233Y26477D03*
X1638165Y19541D03*
X1641833Y26477D03*
X1634765Y19541D03*
X1636047Y224597D03*
Y229912D03*
X1647310Y408922D03*
Y411422D03*
X1635697Y561253D03*
X1635944Y609510D03*
Y612510D03*
X1636022Y606126D03*
X1647158Y618971D03*
X1639745Y627206D03*
X1646507Y640781D03*
X1645014Y629866D03*
X1639745Y629714D03*
X1635791Y629269D03*
X1646507Y638240D03*
X1642734Y633391D03*
X1638443Y699419D03*
Y696919D03*
Y694419D03*
Y701919D03*
X1640943Y694419D03*
Y696919D03*
Y699419D03*
Y701919D03*
X1643517Y702013D03*
Y699513D03*
Y694513D03*
Y697013D03*
X1643427Y691919D03*
X1640927D03*
X1638427D03*
X1640877Y706972D03*
Y709472D03*
X1638377D03*
Y704472D03*
Y706972D03*
X1640877Y704472D03*
X1643377Y709510D03*
Y704510D03*
Y707010D03*
X1640877Y711972D03*
X1638377D03*
X1643377Y712010D03*
X1635088Y767205D03*
Y771005D03*
X1644188Y766870D03*
X1634428Y1260917D03*
X1645163Y1276184D03*
X1641677Y1341488D03*
Y1344488D03*
X1641087Y1396118D03*
X1641065Y1403393D03*
X1644001Y1408069D03*
X1646483Y1412741D03*
X1641065Y1406393D03*
X1635619Y1430536D03*
X1639834Y1434478D03*
X1636167Y1446746D03*
X1642400Y1439674D03*
X1645979Y1437950D03*
X1650400Y1437820D03*
X1641167Y1446746D03*
X1646560Y1505295D03*
X1643160D03*
X1646879Y1681738D03*
X1645029Y1715609D03*
Y1710609D03*
X1648029Y1708609D03*
Y1723759D03*
X1645029Y1725759D03*
Y1730759D03*
X1652338Y19541D03*
X1648938D03*
X1652525Y146762D03*
Y151762D03*
Y161762D03*
X1650023Y221842D03*
X1654419Y224597D03*
X1659419D03*
X1650023Y227157D03*
X1654419Y229912D03*
X1661928Y230172D03*
X1650020Y408952D03*
Y411452D03*
X1654110Y434177D03*
X1657545Y434506D03*
X1650035Y434750D03*
X1657194Y599956D03*
X1651194D03*
X1660194Y609450D03*
X1654194D03*
X1660194Y599956D03*
X1657194Y609450D03*
X1654194Y599956D03*
X1651194Y609450D03*
X1654147Y616523D03*
X1662377Y696300D03*
Y693300D03*
X1651072Y1314137D03*
X1660572Y1313837D03*
X1660635Y1329166D03*
X1651072Y1323137D03*
Y1320137D03*
Y1317137D03*
X1660572Y1322837D03*
Y1319837D03*
X1660635Y1326466D03*
X1660572Y1316837D03*
X1658015Y1328966D03*
X1658115Y1326466D03*
X1660635Y1331666D03*
Y1334166D03*
Y1339166D03*
Y1336666D03*
X1650177Y1341488D03*
X1658277Y1341888D03*
X1658015Y1336466D03*
Y1338966D03*
Y1331466D03*
Y1333966D03*
X1650177Y1344488D03*
X1658677D03*
X1653390Y1386316D03*
Y1388857D03*
X1649197Y1396743D03*
X1654883Y1397231D03*
X1660152Y1397383D03*
X1664106Y1397828D03*
X1660152Y1399891D03*
X1657163Y1393706D03*
X1661807Y1416948D03*
X1663777Y1421568D03*
X1662487Y1424178D03*
X1658089Y1437444D03*
X1649380Y1446713D03*
X1659960Y1485895D03*
X1656560D03*
X1653260Y1495595D03*
X1649860D03*
X1659975Y1592929D03*
X1656101Y1671720D03*
X1651101Y1671833D03*
X1653930Y1660640D03*
X1656180Y1659220D03*
X1656849Y1664949D03*
X1651698Y1665045D03*
X1661125Y1690751D03*
X1656101Y1701094D03*
X1656997Y1718759D03*
Y1733909D03*
X1675194Y26477D03*
X1671794D03*
X1673100Y121762D03*
Y136762D03*
Y131762D03*
X1673403Y199997D03*
X1664335Y210191D03*
X1663310Y215488D03*
X1664789Y767265D03*
Y771065D03*
X1673889Y766870D03*
X1674972Y1313837D03*
X1675134Y1329219D03*
X1675234Y1326519D03*
X1674972Y1316837D03*
X1672623Y1326476D03*
X1663437Y1326526D03*
X1674972Y1319837D03*
Y1322837D03*
X1677754Y1326519D03*
Y1329019D03*
X1663437Y1334726D03*
X1672623Y1334676D03*
X1663437Y1329726D03*
X1672623Y1332176D03*
X1663437Y1332226D03*
X1672623Y1329676D03*
X1675134Y1331719D03*
Y1334219D03*
Y1336719D03*
Y1339219D03*
X1677754Y1339019D03*
Y1336519D03*
Y1331519D03*
Y1334019D03*
X1675931Y1384335D03*
Y1387235D03*
X1667594Y1399428D03*
X1666844Y1396860D03*
X1675470Y1390170D03*
X1673040D03*
X1670610D03*
X1672501Y1416678D03*
X1675641Y1432891D03*
X1672401Y1423365D03*
X1664237Y1426278D03*
X1671079Y1435069D03*
X1663239Y1428592D03*
X1670147Y1444311D03*
X1673360Y1485895D03*
X1669960D03*
X1676685Y1537893D03*
X1671034Y1549734D03*
Y1552234D03*
X1668703Y1550898D03*
X1671034Y1546934D03*
X1668827Y1553551D03*
X1671034Y1557234D03*
Y1554734D03*
X1673706Y1560425D03*
X1671006Y1576744D03*
Y1574244D03*
Y1571744D03*
X1668826Y1575498D03*
Y1572998D03*
X1676176Y1580650D03*
X1674923Y1582973D03*
X1677556Y1656405D03*
X1674356D03*
X1671156D03*
X1666168Y1667688D03*
X1670202Y1663150D03*
X1675290Y1663157D03*
X1674338Y1677832D03*
X1671902Y1676267D03*
X1669377Y1675241D03*
X1670773Y1688827D03*
X1680029Y1710609D03*
Y1715609D03*
X1672500Y1708927D03*
X1675360Y1721252D03*
X1689367Y26477D03*
X1682299Y19541D03*
X1685967Y26477D03*
X1678899Y19541D03*
X1695100Y121762D03*
X1683275Y120762D03*
X1695100Y136762D03*
Y131762D03*
X1684925D03*
Y136762D03*
Y123762D03*
Y126762D03*
Y145762D03*
X1695100Y146762D03*
X1684925Y141762D03*
X1695100Y156762D03*
Y161762D03*
Y166762D03*
X1684925Y157762D03*
Y166762D03*
X1678809Y206451D03*
X1682433Y220857D03*
X1682408Y228337D03*
X1689000Y234000D03*
X1692429Y403985D03*
X1694050Y416643D03*
X1690208Y421855D03*
X1690140Y434160D03*
X1692450Y436772D03*
X1692974Y553115D03*
X1685890Y708610D03*
X1684672Y1313837D03*
X1690697Y1329066D03*
Y1326566D03*
X1684672Y1322837D03*
Y1319837D03*
Y1316837D03*
X1690697Y1336566D03*
Y1334066D03*
Y1331566D03*
X1679028Y1341733D03*
X1687234Y1341533D03*
Y1344033D03*
X1679028Y1344233D03*
X1690697Y1339066D03*
X1686172Y1386416D03*
Y1388957D03*
X1687665Y1397331D03*
X1692934Y1397483D03*
Y1399991D03*
X1689945Y1393806D03*
X1682500Y1390475D03*
X1680300Y1391875D03*
X1682500Y1396275D03*
X1680400Y1394875D03*
X1678234Y1393605D03*
Y1396505D03*
X1682500Y1393375D03*
X1683741Y1443075D03*
X1681538Y1451522D03*
X1689062Y1451496D03*
X1687783Y1472068D03*
X1680730Y1517082D03*
Y1513682D03*
Y1530482D03*
Y1527082D03*
X1685745Y1552579D03*
X1686219Y1549994D03*
X1685745Y1555079D03*
Y1557579D03*
X1685995Y1561516D03*
X1680589Y1559626D03*
Y1563526D03*
X1690353Y1591494D03*
X1680695Y1656307D03*
X1686675Y1659287D03*
X1692415Y1663740D03*
X1685500Y1663599D03*
X1680367Y1663367D03*
X1691952Y1698947D03*
X1689184Y1702095D03*
X1683029Y1708609D03*
X1680877Y1723593D03*
X1692218Y1717539D03*
X1685383Y1729559D03*
X1707186Y15708D03*
X1696472Y19541D03*
X1693072D03*
X1703583Y26505D03*
X1700183D03*
X1703536Y50649D03*
X1700136D03*
X1695100Y126762D03*
Y141762D03*
Y151762D03*
X1705120Y143610D03*
X1693000Y234000D03*
X1698220Y369652D03*
X1699809Y403985D03*
X1695579D03*
X1702959Y404243D03*
X1697161Y406602D03*
X1706500Y415862D03*
Y413362D03*
X1707780Y410738D03*
X1695455Y422287D03*
X1707568Y420370D03*
X1701124Y423802D03*
X1707544Y431745D03*
X1704974Y553115D03*
X1700974D03*
X1696974D03*
X1693490Y620672D03*
X1697530Y636369D03*
X1701661Y644554D03*
X1705561D03*
X1699500Y654738D03*
Y673738D03*
X1694490Y767265D03*
Y771065D03*
X1708049Y766870D03*
X1699072Y1313737D03*
X1696047Y1326576D03*
X1705383D03*
X1693417Y1329266D03*
X1693217Y1326566D03*
X1699072Y1322737D03*
Y1319737D03*
Y1316737D03*
X1693417Y1334266D03*
Y1331766D03*
X1705383Y1334676D03*
X1696047D03*
X1705383Y1329676D03*
X1696047Y1332176D03*
Y1329676D03*
X1705383Y1332176D03*
X1693417Y1336766D03*
Y1339266D03*
X1700376Y1399528D03*
X1696888Y1397928D03*
X1699626Y1396960D03*
X1703392Y1390270D03*
X1705822D03*
X1700272Y1460547D03*
X1702281Y1449801D03*
X1705108Y1451774D03*
X1695020Y1465621D03*
X1698440Y1466590D03*
X1705246Y1465325D03*
X1701348Y1466557D03*
X1709964Y1597490D03*
X1709833Y1612940D03*
Y1606340D03*
X1701984Y1671618D03*
X1695987D03*
X1700156Y1698830D03*
X1702750Y1696185D03*
X1706086Y1691568D03*
X1717148Y19910D03*
X1712977Y19986D03*
X1722148Y19910D03*
X1722085Y25908D03*
X1717055D03*
X1710106Y39768D03*
X1723241Y48822D03*
X1710106Y48978D03*
X1721646Y68115D03*
X1716558Y67866D03*
X1715861Y72593D03*
X1712486Y117908D03*
X1712686Y111908D03*
X1719909Y112713D03*
Y116713D03*
X1713399Y132858D03*
X1721384Y135373D03*
X1717384D03*
X1716609Y141297D03*
X1721628Y147312D03*
X1714293Y156278D03*
X1711293D03*
X1716893D03*
X1719493D03*
X1722093D03*
X1711293Y158878D03*
X1714293D03*
X1711293Y161478D03*
X1714293D03*
X1711293Y163978D03*
X1714293D03*
X1711293Y166478D03*
X1714293D03*
X1722093Y158878D03*
X1719493D03*
X1716893D03*
X1722093Y161478D03*
Y163978D03*
Y166478D03*
X1719493Y161478D03*
X1716893D03*
X1719493Y163978D03*
X1716893D03*
Y166478D03*
X1719493D03*
X1719200Y371162D03*
X1717220Y381152D03*
X1713720D03*
X1717220Y384652D03*
Y388152D03*
X1713720D03*
Y384652D03*
X1717220Y391652D03*
X1713720D03*
X1709000Y415862D03*
Y413362D03*
X1709339Y637251D03*
X1718465Y657982D03*
X1720050Y649142D03*
X1716030Y668182D03*
X1709759Y670221D03*
X1718686Y676154D03*
X1722672Y1313237D03*
X1708672Y1313737D03*
X1707916Y1329319D03*
X1722672Y1316237D03*
X1708672Y1322737D03*
Y1319737D03*
X1710536Y1329119D03*
X1708016Y1326619D03*
X1710536D03*
X1722672Y1319237D03*
Y1322237D03*
X1719916Y1326559D03*
X1717396D03*
X1719916Y1329059D03*
X1717396D03*
X1708672Y1316737D03*
X1707916Y1334319D03*
Y1331819D03*
Y1339319D03*
Y1336819D03*
X1710536Y1336619D03*
Y1339119D03*
X1719916Y1339059D03*
X1717396D03*
X1719916Y1336559D03*
X1717396D03*
X1710536Y1334119D03*
Y1331619D03*
X1719916Y1331559D03*
Y1334059D03*
X1717396D03*
Y1331559D03*
X1710176Y1342089D03*
X1718706Y1341629D03*
Y1344129D03*
X1710176Y1344589D03*
X1708713Y1384435D03*
Y1387335D03*
X1708252Y1390270D03*
X1715282Y1396375D03*
X1713082Y1391975D03*
X1715282Y1390575D03*
X1711016Y1393705D03*
Y1396605D03*
X1713182Y1394975D03*
X1715282Y1393475D03*
X1717447Y1417213D03*
X1714447D03*
X1717447Y1423213D03*
Y1420213D03*
X1714447D03*
Y1423213D03*
X1722334Y1468146D03*
X1718425Y1468245D03*
X1722347Y1471246D03*
X1716070Y1472037D03*
X1712870Y1586615D03*
X1715693Y1597190D03*
X1713593Y1609640D03*
Y1603040D03*
X1720845Y1668498D03*
X1719181Y1706712D03*
X1721172Y1712115D03*
X1710360Y1706502D03*
X1721912Y1705115D03*
X1719218Y1727265D03*
X1719148Y1721530D03*
X1722149Y1720265D03*
X1710230Y1729654D03*
X1736006Y41838D03*
Y44338D03*
X1729836Y54524D03*
X1727336D03*
X1724685Y51454D03*
X1727225Y51424D03*
X1729895Y51354D03*
X1726741Y48822D03*
X1730241D03*
X1737617Y75640D03*
Y73140D03*
Y79140D03*
Y81640D03*
X1722984Y101713D03*
X1723184Y93313D03*
X1736731Y102293D03*
X1728965Y112941D03*
X1729046Y118178D03*
X1739686Y120938D03*
X1725093Y156278D03*
Y158878D03*
Y161478D03*
Y163978D03*
Y166478D03*
X1735471Y293682D03*
Y290682D03*
Y296682D03*
Y299682D03*
X1730331Y293722D03*
Y296722D03*
X1732831D03*
X1730331Y299722D03*
X1732831D03*
Y293722D03*
X1723492Y293068D03*
X1732751Y305732D03*
X1730251D03*
X1732751Y302732D03*
X1730251D03*
X1735391Y305692D03*
Y302692D03*
X1725344Y359334D03*
X1728300Y377787D03*
X1733043Y657091D03*
X1736848Y650974D03*
X1726409Y653641D03*
X1737002Y671494D03*
X1724191Y767299D03*
Y771099D03*
X1737850Y766794D03*
X1732702Y1313007D03*
Y1316007D03*
Y1322007D03*
Y1319007D03*
X1732766Y1410562D03*
Y1413062D03*
X1735266Y1410562D03*
Y1413062D03*
X1732766Y1426362D03*
Y1428862D03*
X1735266Y1426362D03*
Y1428862D03*
X1730004Y1540968D03*
X1726604Y1540970D03*
X1735379Y1566282D03*
X1735354Y1580480D03*
X1735351Y1569832D03*
X1736479Y1584330D03*
X1730202Y1602093D03*
X1735463Y1651965D03*
X1730381Y1647386D03*
X1726381D03*
X1734500Y1656965D03*
X1734589Y1666203D03*
X1734962Y1662965D03*
X1734963Y1673465D03*
X1724263Y1672465D03*
X1734763Y1680465D03*
X1735463Y1694465D03*
X1725423Y1692656D03*
X1731936Y1690165D03*
X1731117Y1715265D03*
X1732251Y1708265D03*
X1731117Y1730415D03*
X1748708Y26641D03*
X1751031Y39063D03*
X1738093Y53103D03*
Y55603D03*
X1741621Y76613D03*
Y74113D03*
Y82613D03*
Y80113D03*
X1743491Y92827D03*
X1738435Y100244D03*
X1741935D03*
X1745435D03*
X1740231Y102293D03*
X1743731D03*
X1748686Y97408D03*
X1740091Y92827D03*
X1750786Y120018D03*
X1744976Y122998D03*
X1754339Y128242D03*
X1752022Y269794D03*
Y266794D03*
X1742971Y293682D03*
Y290682D03*
X1737971D03*
X1740471Y293682D03*
Y290682D03*
Y299682D03*
X1737971D03*
X1740471Y296682D03*
X1737971D03*
Y293682D03*
X1751352Y293386D03*
X1745671Y290682D03*
Y293682D03*
X1737891Y302692D03*
X1740391D03*
X1737891Y305692D03*
X1740391D03*
X1744510Y377452D03*
X1744380Y382892D03*
X1742398Y484304D03*
X1742306Y661032D03*
X1745484Y668216D03*
X1751490Y713890D03*
X1748990D03*
X1746490D03*
X1743990D03*
X1751490Y706390D03*
X1748990D03*
X1746490D03*
X1743990D03*
X1751490Y708890D03*
X1748990D03*
X1746490D03*
X1743990D03*
X1751490Y711390D03*
X1748990D03*
X1746490D03*
X1743990D03*
X1742766Y1418462D03*
Y1415962D03*
X1737766Y1410562D03*
Y1413062D03*
X1740266Y1410562D03*
Y1413062D03*
X1742766D03*
Y1410562D03*
X1740266Y1415962D03*
Y1418462D03*
X1737766Y1426362D03*
Y1428862D03*
X1742766Y1423462D03*
X1740266Y1426362D03*
Y1423462D03*
Y1420962D03*
X1742766D03*
X1741329Y1506405D03*
Y1503405D03*
Y1509405D03*
Y1512405D03*
X1745543Y1518678D03*
X1742758Y1521239D03*
X1745746D03*
X1751120Y1521223D03*
X1751087Y1518704D03*
X1748346Y1521223D03*
X1748313Y1518704D03*
X1739565Y1528105D03*
X1751132Y1526748D03*
Y1524248D03*
Y1529248D03*
X1742810Y1524534D03*
X1745410D03*
X1748358Y1526748D03*
Y1524248D03*
Y1529248D03*
X1746779Y1583378D03*
X1751558Y1579332D03*
X1746079Y1587705D03*
X1750463Y1654465D03*
X1744963Y1656465D03*
X1744463Y1651229D03*
X1747986Y1686215D03*
X1751340Y1686140D03*
X1744620Y1716018D03*
X1750380Y1707468D03*
X1747120Y1710824D03*
X1749480Y1718158D03*
X1765920Y17031D03*
X1765980Y27031D03*
X1765920Y22031D03*
X1758638Y26477D03*
X1755238D03*
X1767266Y48748D03*
X1763010Y51223D03*
X1765527Y53692D03*
X1758635Y50649D03*
X1755235D03*
X1757923Y72637D03*
X1767956Y76843D03*
X1767136Y83653D03*
X1761417Y90017D03*
X1760444Y106173D03*
X1763644D03*
X1755944Y111073D03*
Y108473D03*
X1760944Y116773D03*
X1757944D03*
X1760124Y128246D03*
X1755504Y202263D03*
X1758030D03*
X1762564Y202326D03*
X1765090D03*
X1761573Y266657D03*
X1764573D03*
X1761573Y269657D03*
X1764573D03*
X1758022Y269794D03*
Y266794D03*
X1755022Y269794D03*
Y266794D03*
X1755772Y278859D03*
X1758772D03*
X1761772D03*
X1755772Y281859D03*
X1758772D03*
X1761772D03*
X1752772Y278859D03*
Y281859D03*
X1756800Y364048D03*
Y368048D03*
X1756933Y372452D03*
X1759379Y507927D03*
X1753566Y512968D03*
X1768041Y556537D03*
X1753990Y711390D03*
Y708890D03*
Y706390D03*
Y713890D03*
X1753891Y767305D03*
Y771105D03*
X1767450Y766870D03*
X1759949Y1297324D03*
X1764267Y1460080D03*
X1756329Y1506405D03*
Y1503405D03*
X1764029Y1506405D03*
Y1503405D03*
X1756329Y1509405D03*
Y1512405D03*
X1764029Y1509405D03*
Y1512405D03*
X1765286Y1518471D03*
X1765176Y1515902D03*
X1765286Y1521095D03*
X1765246Y1524001D03*
Y1526601D03*
X1765334Y1529342D03*
X1764679Y1572105D03*
X1765679Y1575405D03*
X1762679D03*
X1766079Y1578705D03*
X1763079D03*
X1753512Y1583478D03*
X1763706Y1616451D03*
X1760206D03*
X1767206D03*
X1765854Y1646456D03*
X1755463Y1654465D03*
X1767888Y1664465D03*
X1762263Y1671765D03*
X1765163Y1670543D03*
X1765463Y1677465D03*
X1761463Y1683465D03*
X1775920Y17031D03*
X1770920D03*
X1775920Y27068D03*
X1770920Y22031D03*
X1775920D03*
X1768956Y37558D03*
X1777720Y37792D03*
X1773830Y49000D03*
X1779377Y50738D03*
X1774294Y60133D03*
X1774291Y57191D03*
X1769240Y50788D03*
X1769200Y54300D03*
X1780300Y54400D03*
X1775546Y73376D03*
X1774294Y63033D03*
X1779744Y72973D03*
Y70073D03*
X1770334Y72737D03*
X1778205Y90982D03*
X1781451Y88238D03*
X1773577Y88339D03*
X1778544Y97973D03*
X1769244Y113773D03*
Y110973D03*
Y108073D03*
X1781368Y162824D03*
X1780929Y179408D03*
X1776930Y179051D03*
X1773581Y194120D03*
X1771055D03*
X1771931Y200920D03*
X1769405D03*
X1777170Y201002D03*
X1774644D03*
X1778796Y261633D03*
X1767573Y266657D03*
X1775633Y261666D03*
X1767573Y269657D03*
X1778796Y266633D03*
Y269133D03*
Y264133D03*
X1775633Y269166D03*
Y266666D03*
Y264166D03*
X1778796Y271633D03*
X1775633Y271666D03*
X1770280Y372452D03*
X1770220Y382952D03*
Y377452D03*
X1782324Y403932D03*
Y410432D03*
Y418932D03*
Y425432D03*
X1779376Y558324D03*
X1782376D03*
X1773963Y557537D03*
X1776986Y749023D03*
X1776550Y763765D03*
X1769650Y1280200D03*
X1771000Y1278060D03*
X1782369Y1447581D03*
X1782385Y1450095D03*
X1782337Y1453191D03*
X1775682Y1466568D03*
X1779029Y1506405D03*
Y1503405D03*
Y1509405D03*
Y1512405D03*
X1780012Y1518631D03*
Y1516031D03*
Y1521231D03*
X1777152Y1518631D03*
Y1516031D03*
Y1521231D03*
X1774552D03*
Y1516031D03*
Y1518631D03*
X1768176Y1515902D03*
X1768286Y1518471D03*
Y1521095D03*
X1770886D03*
Y1518471D03*
X1770776Y1515902D03*
X1780039Y1523860D03*
Y1526360D03*
X1779997Y1528888D03*
X1777179Y1526360D03*
Y1523860D03*
X1774579D03*
Y1526360D03*
X1768246Y1526601D03*
Y1524001D03*
X1768334Y1529342D03*
X1770846Y1524001D03*
Y1526601D03*
X1771079Y1566782D03*
X1770404Y1575330D03*
X1780579Y1582178D03*
X1771094Y1570332D03*
X1778794Y1585332D03*
X1768105Y1595925D03*
X1775794Y1585332D03*
X1768030Y1599249D03*
X1768180Y1606549D03*
X1768030Y1603149D03*
X1780154Y1615026D03*
X1777454D03*
X1780154Y1617726D03*
X1777454D03*
X1773349Y1631938D03*
Y1634438D03*
Y1636938D03*
X1770649Y1631938D03*
Y1634438D03*
X1781423Y1634394D03*
Y1636894D03*
X1778723Y1634294D03*
X1776023D03*
Y1636894D03*
X1778723D03*
X1773929Y1657465D03*
Y1654956D03*
X1768929Y1651956D03*
X1774338Y1676865D03*
X1771038Y1692956D03*
X1787826Y37548D03*
X1783700Y50011D03*
X1794099Y50461D03*
X1788204Y74958D03*
X1785108Y76078D03*
X1787756Y85178D03*
X1788204Y82338D03*
Y78108D03*
X1784144Y113973D03*
Y111173D03*
Y108273D03*
X1797692Y146285D03*
X1784006Y137395D03*
X1788950Y142750D03*
X1787390Y165834D03*
Y156834D03*
Y151834D03*
X1793444Y178083D03*
X1785320Y193072D03*
X1784915Y186053D03*
X1783896Y266633D03*
Y269133D03*
X1794174Y274499D03*
X1790674D03*
X1783896Y271633D03*
X1789771Y367866D03*
X1797929Y385293D03*
X1786260Y379059D03*
X1792507Y403932D03*
X1792335Y418775D03*
X1792450Y410615D03*
X1792220Y425432D03*
X1785376Y558324D03*
X1788376D03*
X1792895Y683536D03*
X1783592Y767565D03*
Y771365D03*
X1792692Y766870D03*
X1794362Y1275546D03*
X1785336Y1447565D03*
Y1450065D03*
X1785634Y1456326D03*
X1782530Y1456229D03*
X1785408Y1453385D03*
X1788029Y1506405D03*
Y1503405D03*
Y1509405D03*
Y1512405D03*
X1794265Y1518262D03*
Y1520862D03*
Y1523462D03*
Y1526062D03*
X1794268Y1528720D03*
X1784601Y1578967D03*
X1787239Y1579406D03*
X1789294Y1583278D03*
X1797118Y1596588D03*
X1797143Y1607014D03*
X1797076Y1603662D03*
X1797043Y1599811D03*
X1791979Y1616550D03*
X1795479D03*
X1782654Y1615026D03*
Y1617726D03*
X1784048Y1636875D03*
Y1634375D03*
X1786615Y1631800D03*
X1786588Y1634472D03*
X1786624Y1637021D03*
X1802565Y156557D03*
X1800554Y177229D03*
X1808622Y170869D03*
X1806470Y186866D03*
X1802570Y186913D03*
X1811274Y198098D03*
X1807596Y264133D03*
Y266633D03*
Y269133D03*
X1797674Y274499D03*
X1801174D03*
X1807596Y271633D03*
X1800160Y362542D03*
X1808962Y698055D03*
Y700555D03*
Y703055D03*
X1798462Y698055D03*
X1801962D03*
X1805462D03*
Y700555D03*
X1801962D03*
X1798462D03*
X1805462Y703055D03*
X1801962D03*
X1798462D03*
X1808962Y705555D03*
Y708055D03*
X1798462Y705555D03*
X1801962D03*
X1805462D03*
X1798462Y708055D03*
X1801962D03*
X1805462D03*
X1809002Y710945D03*
Y713445D03*
Y715945D03*
X1805502Y710945D03*
Y713445D03*
Y715945D03*
X1802050Y710940D03*
X1811526Y1281671D03*
X1803029Y1506405D03*
Y1503405D03*
X1812029Y1506405D03*
Y1503405D03*
X1803029Y1509405D03*
Y1512405D03*
X1812029Y1509405D03*
Y1512405D03*
X1797362Y1518304D03*
X1799882Y1520912D03*
Y1518312D03*
X1797362Y1520904D03*
X1804049Y1528031D03*
X1799882Y1523512D03*
X1797362Y1523504D03*
X1799882Y1526112D03*
X1797362Y1526104D03*
X1799994Y1528674D03*
X1797450Y1528768D03*
X1809890Y1524532D03*
X1807290D03*
X1798479Y1575605D03*
X1798879Y1578905D03*
X1801479Y1575605D03*
X1800479Y1572305D03*
X1801879Y1578905D03*
X1798979Y1616550D03*
X1815005Y149325D03*
X1817196Y163797D03*
Y159947D03*
X1818828Y175241D03*
X1817275Y180619D03*
X1813224Y194699D03*
X1816190Y208879D03*
X1817157Y373829D03*
X1828669Y379552D03*
X1816994Y398052D03*
X1816224Y410432D03*
X1822724Y424948D03*
X1815724Y423932D03*
X1825874Y424948D03*
X1822394Y436225D03*
X1827073Y565157D03*
X1824073D03*
X1821073D03*
X1812462Y698055D03*
Y700555D03*
Y703055D03*
Y705555D03*
Y708055D03*
X1812502Y710945D03*
Y713445D03*
Y715945D03*
X1827029Y1506405D03*
Y1503405D03*
Y1509405D03*
Y1512405D03*
X1818475Y1524682D03*
X1815875D03*
X1823649Y1525144D03*
X1831166Y149986D03*
X1827580Y151834D03*
X1829732Y371329D03*
X1828483Y431678D03*
X1833288Y1469639D03*
X1850791Y170287D03*
G54D30*
X180780Y1507509D03*
X178580D03*
X177487Y1521612D03*
X177086Y1518121D03*
X178745Y1513218D03*
X177533Y1535698D03*
Y1537898D03*
X178980Y1540317D03*
X183051Y1544625D03*
X188155Y1516970D03*
X192879D03*
X197604D03*
X189730Y1519698D03*
X194454D03*
X199178D03*
X188155Y1530608D03*
X192879D03*
X197604D03*
X189730Y1533336D03*
X194454D03*
X199178D03*
X202328Y1516970D03*
X207052D03*
X211777D03*
X216501D03*
X203903Y1519698D03*
X208627D03*
X213352D03*
X202328Y1530608D03*
X207052D03*
X211777D03*
X216501D03*
X203903Y1533336D03*
X208627D03*
X213352D03*
X221226Y1516970D03*
X225950D03*
X230674D03*
X218076Y1519698D03*
X222800D03*
X227525D03*
X221226Y1530608D03*
X225950D03*
X230674D03*
X218076Y1533336D03*
X222800D03*
X227525D03*
X235399Y1516970D03*
X240123D03*
X244848D03*
X236974Y1519698D03*
X241698D03*
X246422D03*
X232249D03*
X235399Y1530608D03*
X240123D03*
X244848D03*
X236974Y1533336D03*
X241698D03*
X246422D03*
X232249D03*
X249572Y1516970D03*
X254297D03*
X259021D03*
X251147Y1519698D03*
X255871D03*
X260596D03*
X249572Y1530608D03*
X254297D03*
X259021D03*
X251147Y1533336D03*
X255871D03*
X260596D03*
X265421Y1507355D03*
X263321D03*
X266828Y1514073D03*
X266772Y1516336D03*
X267123Y1536640D03*
Y1534540D03*
X267124Y1531618D03*
X267035Y1528698D03*
X266538Y1538658D03*
X305549Y1521612D03*
X305148Y1518121D03*
X305595Y1535698D03*
Y1537898D03*
X317957Y886002D03*
X319807Y889191D03*
Y895569D03*
X317957Y892380D03*
X316107Y895569D03*
X319807Y908325D03*
X317957Y898758D03*
X319807Y901947D03*
X317957Y905135D03*
Y911513D03*
X314256Y905135D03*
X317957Y917891D03*
X319807Y921080D03*
X317957Y924269D03*
X319807Y914702D03*
X314256Y924269D03*
X316107Y914702D03*
X319807Y927458D03*
X317957Y937025D03*
X319807Y940214D03*
Y933836D03*
X317957Y930647D03*
X316107Y933836D03*
X317957Y943403D03*
X319807Y946592D03*
X317957Y956159D03*
X319807Y952970D03*
X317957Y949781D03*
X316107Y952970D03*
X314256Y943403D03*
X317957Y962537D03*
X319807Y965726D03*
Y959348D03*
X317957Y968915D03*
X314256Y962537D03*
X317957Y975293D03*
X319807Y978482D03*
Y972104D03*
X316107D03*
X314256Y981671D03*
X317957Y994427D03*
X319807Y997616D03*
X317957Y1000805D03*
X319807Y991238D03*
X314256Y1000805D03*
X316107Y991238D03*
X317957Y988049D03*
X319807Y1010372D03*
X317957Y1007183D03*
X319807Y1003994D03*
X317288Y1028056D03*
X313587D03*
X320988D03*
Y1034434D03*
X319138Y1037623D03*
X320988Y1040812D03*
X319138Y1044001D03*
X315437Y1037623D03*
X319138Y1031245D03*
X320988Y1059946D03*
X319138Y1050379D03*
X320988Y1053568D03*
X315437Y1056757D03*
X317288Y1047190D03*
X319138Y1056757D03*
X320988Y1047190D03*
Y1072702D03*
X319138Y1063135D03*
Y1069513D03*
X320988Y1066324D03*
X317288D03*
X319138Y1075891D03*
X320988Y1079080D03*
X319138Y1082269D03*
Y1088647D03*
X320988Y1085458D03*
X317288D03*
X315437Y1075891D03*
X319138Y1101403D03*
X320988Y1091836D03*
X319138Y1095025D03*
X320988Y1098214D03*
Y1104592D03*
X317288D03*
X315437Y1095025D03*
X320988Y1110970D03*
X319138Y1114159D03*
X320988Y1117348D03*
X319138Y1107781D03*
X315437Y1114159D03*
X319138Y1120537D03*
X320988Y1130103D03*
X319138Y1133293D03*
Y1126915D03*
X320988Y1123726D03*
X315437Y1133293D03*
X317288Y1123726D03*
X320988Y1136481D03*
X319138Y1139670D03*
X320988Y1149237D03*
X319138Y1146048D03*
X320988Y1142859D03*
X317288D03*
X315437Y1158804D03*
X319138Y1152426D03*
X315437D03*
X319138Y1158804D03*
X308893Y1507460D03*
X316217Y1516970D03*
X320941D03*
X317792Y1519698D03*
X306807Y1513218D03*
X316217Y1530608D03*
X320941D03*
X317792Y1533336D03*
X311113Y1544625D03*
X307042Y1540317D03*
X327209Y882813D03*
X323508Y889191D03*
X325358Y892380D03*
X323508Y895569D03*
X332760Y886002D03*
X330910Y889191D03*
Y895569D03*
X332760Y892380D03*
X323508Y882813D03*
X325358Y911513D03*
X323508Y901947D03*
X325358Y905135D03*
X323508Y908325D03*
X325358Y898758D03*
X330910Y908325D03*
X332760Y898758D03*
X330910Y901947D03*
X332760Y905135D03*
Y911513D03*
X323508Y921080D03*
X325358Y924269D03*
X323508Y914702D03*
X325358Y917891D03*
X332760D03*
X330910Y921080D03*
X332760Y924269D03*
X330910Y914702D03*
X323508Y927458D03*
X325358Y930647D03*
X323508Y940214D03*
Y933836D03*
X325358Y937025D03*
X330910Y927458D03*
X332760Y937025D03*
X330910Y940214D03*
Y933836D03*
X332760Y930647D03*
X325358Y943403D03*
X323508Y946592D03*
X325358Y949781D03*
X323508Y952970D03*
X325358Y956159D03*
X332760Y943403D03*
X330910Y946592D03*
X332760Y956159D03*
X330910Y952970D03*
X332760Y949781D03*
X323508Y965726D03*
X325358Y968915D03*
X323508Y959348D03*
X325358Y962537D03*
X332760D03*
X330910Y965726D03*
Y959348D03*
X332760Y968915D03*
X323508Y984860D03*
Y978482D03*
X325358Y981671D03*
X323508Y972104D03*
X325358Y975293D03*
X332760D03*
X330910Y978482D03*
Y972104D03*
X325358Y988049D03*
X323508Y997616D03*
X325358Y1000805D03*
Y994427D03*
X332760D03*
X330910Y997616D03*
X332760Y1000805D03*
X330910Y991238D03*
X332760Y988049D03*
X323508Y991238D03*
Y1003994D03*
X325358Y1007183D03*
X330910Y1010372D03*
X332760Y1007183D03*
X330910Y1003994D03*
X323508Y1010372D03*
X324689Y1028056D03*
X332091D03*
X326539Y1031245D03*
X324689Y1034434D03*
X326539Y1037623D03*
X324689Y1040812D03*
X332091Y1034434D03*
X333941Y1037623D03*
X332091Y1040812D03*
X333941Y1044001D03*
Y1031245D03*
X326540Y1044001D03*
X326539Y1050379D03*
X324689Y1047190D03*
X332091Y1059946D03*
X333941Y1050379D03*
X332091Y1053568D03*
X333941Y1056757D03*
X332091Y1047190D03*
X324689Y1053568D03*
X326539Y1063135D03*
X324689Y1066324D03*
X326539Y1069513D03*
X324689Y1072702D03*
X332091D03*
X333941Y1063135D03*
Y1069513D03*
X332091Y1066324D03*
X326539Y1075891D03*
X324689Y1079080D03*
X326539Y1082269D03*
X324689Y1085458D03*
X326539Y1088647D03*
X333941Y1075891D03*
X332091Y1079080D03*
X333941Y1082269D03*
Y1088647D03*
X332091Y1085458D03*
X324689Y1104592D03*
X326539Y1095025D03*
X324689Y1098214D03*
X326539Y1101403D03*
X324689Y1091836D03*
X333941Y1101403D03*
X332091Y1091836D03*
X333941Y1095025D03*
X332091Y1098214D03*
Y1104592D03*
X326539Y1114159D03*
X324689Y1117348D03*
X326539Y1107781D03*
X324689Y1110970D03*
X332091D03*
X333941Y1114159D03*
X332091Y1117348D03*
X333941Y1107781D03*
X326539Y1120537D03*
X324689Y1123726D03*
X326539Y1133293D03*
Y1126915D03*
X324689Y1130103D03*
X333941Y1120537D03*
X332091Y1130103D03*
X333941Y1133293D03*
Y1126915D03*
X332091Y1123726D03*
X324689Y1136481D03*
X326539Y1139670D03*
X324689Y1142859D03*
X326539Y1146048D03*
X324689Y1149237D03*
X332091Y1136481D03*
X333941Y1139670D03*
X332091Y1149237D03*
X333941Y1146048D03*
X332091Y1142859D03*
X326539Y1152426D03*
X324689Y1155615D03*
X333941Y1152426D03*
X332091Y1155615D03*
Y1161993D03*
X333941Y1165182D03*
X326539D03*
X324689Y1161993D03*
X325666Y1516970D03*
X330390D03*
X335114D03*
X322516Y1519698D03*
X327240D03*
X331965D03*
X325666Y1530608D03*
X330390D03*
X335114D03*
X322516Y1533336D03*
X327240D03*
X331965D03*
X343862Y886002D03*
X349414Y889191D03*
X345713D03*
Y895569D03*
X349414D03*
X343862Y892380D03*
X338311Y889191D03*
X336461Y892380D03*
X338311Y895569D03*
X342012D03*
X345713Y908325D03*
X343862Y898758D03*
X349414Y901947D03*
X345713D03*
X343862Y905135D03*
X349414Y908325D03*
X343862Y911513D03*
X336461D03*
X338311Y901947D03*
X336461Y905135D03*
X338311Y908325D03*
X336461Y898758D03*
X340162Y905135D03*
X343862Y917891D03*
X349414Y921080D03*
X345713D03*
X343862Y924269D03*
X345713Y914702D03*
X349414D03*
X338311Y921080D03*
X336461Y924269D03*
X338311Y914702D03*
X336461Y917891D03*
X340162Y924269D03*
X342012Y914702D03*
X349414Y927458D03*
X345713D03*
X343862Y937025D03*
X349414Y940214D03*
X345713D03*
Y933836D03*
X349414D03*
X343862Y930647D03*
X338311Y927458D03*
X336461Y930647D03*
X338311Y940214D03*
Y933836D03*
X336461Y937025D03*
X342012Y933836D03*
X343862Y943403D03*
X349414Y946592D03*
X345713D03*
X343862Y956159D03*
X345713Y952970D03*
X349414D03*
X343862Y949781D03*
X336461Y943403D03*
X338311Y946592D03*
X336461Y949781D03*
X338311Y952970D03*
X336461Y956159D03*
X342012Y952970D03*
X340162Y943403D03*
X343862Y962537D03*
X349414Y965726D03*
X345713D03*
X349414Y959348D03*
X345713D03*
X343862Y968915D03*
X338311Y965726D03*
X336461Y968915D03*
X338311Y959348D03*
X336461Y962537D03*
X340162D03*
X349414Y984860D03*
X343862Y975293D03*
X349414Y978482D03*
X345713D03*
Y972104D03*
X349414D03*
X338311Y984860D03*
Y978482D03*
X336461Y981671D03*
X338311Y972104D03*
X336461Y975293D03*
X342012Y972104D03*
X340162Y981671D03*
X343862Y994427D03*
X345713Y997616D03*
X349414D03*
X343862Y1000805D03*
X345713Y991238D03*
X336461Y988049D03*
X338311Y997616D03*
X336461Y1000805D03*
Y994427D03*
X340162Y1000805D03*
X342012Y991238D03*
X338311D03*
X349414D03*
X343862Y988049D03*
X345713Y1010372D03*
X343862Y1007183D03*
X345713Y1003994D03*
X349414D03*
X338311D03*
X336461Y1007183D03*
X338311Y1010372D03*
X349414D03*
X343193Y1028056D03*
X350595D03*
X339492D03*
X346894D03*
X350595Y1034434D03*
X346894D03*
X345043Y1037623D03*
X350595Y1040812D03*
X346894D03*
X345043Y1044001D03*
X337642Y1031245D03*
X339492Y1034434D03*
X337642Y1037623D03*
X339492Y1040812D03*
X341343Y1037623D03*
X337642Y1044001D03*
X345043Y1031245D03*
X346894Y1059946D03*
X350595Y1047190D03*
X345043Y1050379D03*
X346894Y1053568D03*
X337642Y1050379D03*
X339492Y1047190D03*
X341343Y1056757D03*
X343193Y1047190D03*
X339492Y1053568D03*
X345043Y1056757D03*
X346894Y1047190D03*
X350595Y1053568D03*
X346894Y1072702D03*
X345043Y1063135D03*
X350595Y1066324D03*
X345043Y1069513D03*
X350595Y1072702D03*
X346894Y1066324D03*
X337642Y1063135D03*
X339492Y1066324D03*
X337642Y1069513D03*
X339492Y1072702D03*
X343193Y1066324D03*
X345043Y1075891D03*
X350595Y1079080D03*
X346894D03*
X345043Y1082269D03*
X350595Y1085458D03*
X345043Y1088647D03*
X346894Y1085458D03*
X337642Y1075891D03*
X339492Y1079080D03*
X337642Y1082269D03*
X339492Y1085458D03*
X337642Y1088647D03*
X343193Y1085458D03*
X341343Y1075891D03*
X345043Y1101403D03*
X350595Y1104592D03*
X346894Y1091836D03*
X345043Y1095025D03*
X350595Y1098214D03*
X346894D03*
Y1104592D03*
X350595Y1091836D03*
X339492Y1104592D03*
X337642Y1095025D03*
X339492Y1098214D03*
X337642Y1101403D03*
X339492Y1091836D03*
X341343Y1095025D03*
X343193Y1104592D03*
X346894Y1110970D03*
X345043Y1114159D03*
X350595Y1117348D03*
X346894D03*
X345043Y1107781D03*
X350595Y1110970D03*
X337642Y1114159D03*
X339492Y1117348D03*
X337642Y1107781D03*
X339492Y1110970D03*
X341343Y1114159D03*
X345043Y1120537D03*
X350595Y1123726D03*
X346894Y1130103D03*
X345043Y1133293D03*
Y1126915D03*
X346894Y1123726D03*
X350595Y1130103D03*
X337642Y1120537D03*
X339492Y1123726D03*
X337642Y1133293D03*
Y1126915D03*
X339492Y1130103D03*
X343193Y1123726D03*
X341343Y1133293D03*
X350595Y1136481D03*
X346894D03*
X345043Y1139670D03*
X350595Y1142859D03*
X346894Y1149237D03*
X345043Y1146048D03*
X346894Y1142859D03*
X350595Y1149237D03*
X339492Y1136481D03*
X337642Y1139670D03*
X339492Y1142859D03*
X337642Y1146048D03*
X339492Y1149237D03*
X343193Y1142859D03*
X345043Y1152426D03*
X350595Y1155615D03*
X337642Y1152426D03*
X339492Y1161993D03*
X341343Y1165182D03*
X350595Y1161993D03*
X341343Y1152426D03*
X345043Y1158804D03*
X339839Y1516970D03*
X344563D03*
X349288D03*
X336689Y1519698D03*
X341414D03*
X346138D03*
X350862D03*
X339839Y1530608D03*
X344563D03*
X349288D03*
X336689Y1533336D03*
X341414D03*
X346138D03*
X350862D03*
X364217Y876435D03*
X358665Y879624D03*
X351264Y892380D03*
Y911513D03*
Y905135D03*
Y898758D03*
Y924269D03*
Y917891D03*
Y930647D03*
Y937025D03*
Y943403D03*
Y949781D03*
Y956159D03*
Y968915D03*
Y962537D03*
Y981671D03*
Y975293D03*
Y988049D03*
Y1000805D03*
Y994427D03*
X364217Y991238D03*
X358666Y988049D03*
X351264Y1007183D03*
X364217Y1010372D03*
X365398Y1028056D03*
X357996D03*
X352445Y1031245D03*
Y1037623D03*
X363547Y1044001D03*
X359847Y1031245D03*
X352445Y1044001D03*
Y1050379D03*
X359847Y1056757D03*
X357996Y1047190D03*
X365398Y1053568D03*
X352445Y1063135D03*
Y1069513D03*
Y1075891D03*
Y1082269D03*
Y1088647D03*
Y1095025D03*
Y1101403D03*
Y1114159D03*
Y1107781D03*
Y1120537D03*
Y1133293D03*
Y1126915D03*
Y1139670D03*
Y1146048D03*
Y1152426D03*
X359847Y1165182D03*
X357996Y1161993D03*
X352445Y1165182D03*
X365398Y1161993D03*
X363461Y1516970D03*
X354012D03*
X358736D03*
X365036Y1519698D03*
X355587D03*
X360311D03*
X363461Y1530608D03*
X354012D03*
X358736D03*
X365036Y1533336D03*
X355587D03*
X360311D03*
X367917Y876435D03*
X371618D03*
X379020D03*
X369768Y873246D03*
X373469D03*
X377169D03*
X371618Y882813D03*
X375319D03*
X379020Y889191D03*
X367917Y895569D03*
X366067Y905135D03*
X379020Y901947D03*
X366067Y924269D03*
X367917Y914702D03*
X379020D03*
X367917Y933836D03*
X379020Y927458D03*
X366067Y943403D03*
X367917Y952970D03*
X379020Y946592D03*
X366067Y962537D03*
X379020Y959348D03*
X366067Y981671D03*
X367917Y972104D03*
X379020D03*
X366067Y1000805D03*
X367917Y991238D03*
X375319D03*
X369768Y988049D03*
X379020Y1010372D03*
X375319D03*
X369099Y1028056D03*
X376500D03*
X372799D03*
X367248Y1037623D03*
X378351Y1044001D03*
X370949Y1031245D03*
X367248Y1056757D03*
X369099Y1047190D03*
X370949Y1056757D03*
X372799Y1047190D03*
X376500Y1053568D03*
X369099Y1066324D03*
X380201D03*
X367248Y1075891D03*
X369099Y1085458D03*
X380201Y1079080D03*
Y1091836D03*
X367248Y1095025D03*
X369099Y1104592D03*
X367248Y1114159D03*
X380201Y1110970D03*
X369099Y1123726D03*
X367248Y1133293D03*
X380201Y1123726D03*
Y1149237D03*
X369099Y1142859D03*
X380201Y1136481D03*
X378351Y1165182D03*
X374650D03*
X367248Y1158804D03*
X370949D03*
X369099Y1161993D03*
X372799D03*
X380201D03*
X367248Y1152426D03*
X368185Y1516970D03*
X372910D03*
X377634D03*
X369760Y1519698D03*
X374484D03*
X379209D03*
X368185Y1530608D03*
X372910D03*
X377634D03*
X369760Y1533336D03*
X374484D03*
X379209D03*
X393823Y876435D03*
X382721D03*
X390122D03*
X380870Y879624D03*
X384571D03*
X380870Y873246D03*
X391973D03*
X395673D03*
Y879624D03*
X391973D03*
Y886002D03*
X393823Y895569D03*
X380870Y886002D03*
X382721Y895569D03*
X390122Y889191D03*
X386421Y895569D03*
X395673Y886002D03*
X393823Y908325D03*
X386421D03*
X382721D03*
X393823Y921080D03*
X382721D03*
X386421D03*
X393823Y940214D03*
X382721D03*
X386421D03*
X380870Y937025D03*
X395673D03*
X388272D03*
X391973D03*
X384571D03*
Y949781D03*
Y943403D03*
Y956159D03*
X395673Y949781D03*
Y943403D03*
Y956159D03*
X388272Y949781D03*
Y943403D03*
Y956159D03*
X393823Y952970D03*
X382721D03*
X386421D03*
X393823Y965726D03*
X382721D03*
X386421D03*
X395673Y962537D03*
Y968915D03*
X384571Y962537D03*
Y968915D03*
X388272Y962537D03*
Y968915D03*
X380870Y981671D03*
X382721Y984860D03*
X388272Y981671D03*
X390122Y984860D03*
X386421Y978482D03*
X393823D03*
X395673Y981671D03*
X382721Y978482D03*
X395673Y975293D03*
X384571D03*
X388272D03*
X395673Y994427D03*
Y988049D03*
Y1000805D03*
X380870Y988049D03*
Y994427D03*
X382721Y997616D03*
Y991238D03*
X380870Y1000805D03*
X388272Y994427D03*
X390122Y997616D03*
X388272Y988049D03*
X390122Y991238D03*
X388272Y1000805D03*
X380870Y1007183D03*
X382721Y1003994D03*
X388272Y1007183D03*
X390122Y1003994D03*
X393823Y1010372D03*
X386421D03*
X391303Y1028056D03*
X383902D03*
X382051Y1031245D03*
Y1037623D03*
Y1044001D03*
X391303Y1034434D03*
X389453Y1037623D03*
X391303Y1040812D03*
X389453Y1044001D03*
Y1031245D03*
X383902Y1040812D03*
Y1034434D03*
X395004Y1059946D03*
X383902D03*
X387603D03*
X389453Y1056757D03*
X382051Y1050379D03*
X391303Y1047190D03*
X383902D03*
X391303Y1053568D03*
X389453Y1050379D03*
X383902Y1053568D03*
X385752Y1056757D03*
X382051D03*
X385752Y1069513D03*
Y1063135D03*
X389453Y1069513D03*
Y1063135D03*
X395004Y1072702D03*
X383902D03*
X387603D03*
X385752Y1075891D03*
X389453D03*
X385752Y1088647D03*
Y1082269D03*
X389453Y1088647D03*
Y1082269D03*
X395004Y1085458D03*
X383902D03*
X387603D03*
X385752Y1095025D03*
X389453D03*
X395004Y1098214D03*
X383902D03*
X387603D03*
X382051Y1101403D03*
X393154D03*
X389453D03*
X385752D03*
X389453Y1114159D03*
Y1107781D03*
X385752Y1114159D03*
Y1107781D03*
X395004Y1117348D03*
X387603D03*
X383902D03*
X389453Y1120537D03*
X385752D03*
X395004Y1130103D03*
X387603D03*
X383902D03*
X395004Y1142859D03*
X387603D03*
X383902D03*
X391303Y1149237D03*
X382051Y1152426D03*
X383902Y1161993D03*
X391303D03*
X395004D03*
X393154Y1152426D03*
X393483Y1507355D03*
X391383D03*
X382359Y1516970D03*
X387083D03*
X383933Y1519698D03*
X388658D03*
X394890Y1514073D03*
X394834Y1516336D03*
X382359Y1530608D03*
X387083D03*
X383933Y1533336D03*
X388658D03*
X395185Y1536640D03*
Y1534540D03*
X395186Y1531618D03*
X395097Y1528698D03*
X394600Y1538658D03*
X404925Y876435D03*
X401225D03*
X403075Y879624D03*
X406776D03*
X403075Y873246D03*
X397524Y895569D03*
X403075Y886002D03*
X401225Y889191D03*
X408626Y895569D03*
X404925D03*
X406776Y886002D03*
X410477D03*
X399374D03*
X397524Y908325D03*
X408626D03*
X404925Y908324D03*
X397524Y921080D03*
X408626D03*
X404925D03*
X397524Y940214D03*
X410477Y930647D03*
X406776D03*
X408626Y940214D03*
X404925D03*
X403075Y937025D03*
X404925Y933836D03*
X410477Y937025D03*
X408626Y933836D03*
X399374Y937025D03*
X406776D03*
Y949781D03*
Y943403D03*
Y956159D03*
X399374Y949781D03*
Y943403D03*
Y956159D03*
X410477Y949781D03*
Y943403D03*
Y956159D03*
X397524Y952970D03*
X408626D03*
X404925D03*
X397524Y965726D03*
X408626D03*
X404925D03*
X406776Y962537D03*
Y968915D03*
X399374Y962537D03*
Y968915D03*
X410477Y962537D03*
Y968915D03*
X397524Y978482D03*
Y984860D03*
X404925Y978482D03*
X408626D03*
X410477Y981671D03*
X403075D03*
X404925Y984860D03*
X406776Y975293D03*
X399374D03*
X410477D03*
X397524Y991238D03*
X410477Y988049D03*
X403075D03*
X404925Y991238D03*
X397524Y997616D03*
X403075Y994427D03*
Y1000805D03*
X401225Y1010372D03*
X397524Y1003994D03*
X406763Y1007175D03*
X403075Y1007183D03*
X406094Y1028064D03*
X402406Y1028056D03*
X406104Y1040820D03*
X404256Y1044001D03*
X398705Y1040812D03*
X406094Y1034442D03*
X404256Y1037623D03*
Y1031245D03*
X402406Y1034434D03*
X396855Y1044001D03*
Y1031245D03*
Y1037623D03*
X398705Y1047190D03*
X406107D03*
X404256Y1050379D03*
X398705Y1059946D03*
Y1053568D03*
X396855Y1050379D03*
Y1056757D03*
X409807Y1059946D03*
X406107D03*
Y1053568D03*
X404256Y1056757D03*
X396855Y1069513D03*
Y1063135D03*
X407957Y1069513D03*
Y1063135D03*
X400555Y1069513D03*
Y1063135D03*
X398705Y1072702D03*
X406107D03*
X409807D03*
X396855Y1075891D03*
X407957D03*
X400555D03*
X396855Y1088647D03*
Y1082269D03*
X407957Y1088647D03*
Y1082269D03*
X400555Y1088647D03*
Y1082269D03*
X398705Y1085458D03*
X406107D03*
X409807D03*
X396855Y1095025D03*
X407957D03*
X400555D03*
X398705Y1098214D03*
X406107D03*
X409807D03*
Y1104592D03*
X407957Y1101403D03*
X404256D03*
X396855D03*
X406107Y1104592D03*
X400555Y1101403D03*
Y1114159D03*
Y1107781D03*
X396855Y1114159D03*
Y1107781D03*
X407957Y1114159D03*
X398705Y1117348D03*
X407957Y1107781D03*
X406107Y1117348D03*
X409807D03*
X400555Y1120537D03*
Y1126915D03*
X396855Y1120537D03*
Y1126915D03*
X407957Y1120537D03*
Y1126915D03*
X398705Y1130103D03*
X406107D03*
X409807D03*
X398705Y1142859D03*
X406107D03*
X409807D03*
X402406Y1149237D03*
X404256Y1152426D03*
X406107Y1161993D03*
X402406D03*
X416028Y876435D03*
X412327D03*
X423429D03*
X414177Y873246D03*
X412327Y889191D03*
X425280Y886002D03*
X423429Y889191D03*
X419729Y895569D03*
X416028D03*
X414177Y886002D03*
X419729Y908325D03*
X416028D03*
Y921080D03*
X419729D03*
X417878Y937025D03*
X421579D03*
X417878Y930647D03*
X421579D03*
X416028Y940214D03*
X419729D03*
X417878Y943403D03*
Y956159D03*
Y949781D03*
X421579Y943403D03*
Y956159D03*
Y949781D03*
X416028Y952970D03*
X419729D03*
Y965726D03*
X416028D03*
X417878Y962537D03*
Y968915D03*
X421579Y962537D03*
Y968915D03*
X412327Y984860D03*
X416028Y978482D03*
X419729D03*
X425280Y981671D03*
X417878D03*
X419729Y984860D03*
X417878Y975293D03*
X421579D03*
X417878Y988049D03*
X425280D03*
X412315Y997608D03*
X412327Y991238D03*
X419716Y997608D03*
X419729Y991238D03*
X413496Y1040820D03*
X420897D03*
X413508Y1047190D03*
X420910D03*
X419059Y1050379D03*
X411658D03*
X413508Y1053568D03*
X411658Y1056757D03*
X420910Y1053568D03*
X419059Y1056757D03*
X417209Y1059946D03*
X420910D03*
X419059Y1063135D03*
Y1069513D03*
X422760Y1063135D03*
X411658Y1069513D03*
Y1063135D03*
X422760Y1069513D03*
X417209Y1072702D03*
X420910D03*
X419059Y1075891D03*
X422760D03*
X411658D03*
X419059Y1082269D03*
Y1088647D03*
X422760Y1082269D03*
X411658Y1088647D03*
Y1082269D03*
X422760Y1088647D03*
X417209Y1085458D03*
X420910D03*
X419059Y1095025D03*
Y1101403D03*
X422760Y1095025D03*
Y1101403D03*
X411658Y1095025D03*
X420910Y1098214D03*
X417209D03*
X411658Y1101403D03*
X422760Y1114159D03*
X411658D03*
X419059D03*
X411658Y1107781D03*
X422760D03*
X419059D03*
X420910Y1117348D03*
X417209D03*
X422760Y1120537D03*
Y1126915D03*
X411658Y1120537D03*
Y1126915D03*
X419059Y1120537D03*
Y1126915D03*
X420910Y1130103D03*
X417209D03*
Y1142859D03*
X420910D03*
X413508Y1149237D03*
X424610D03*
Y1161993D03*
X415358Y1152426D03*
X413508Y1161993D03*
X417209D03*
X427130Y876435D03*
X428981Y892380D03*
X432681D03*
X428981Y911513D03*
X432681D03*
X428981Y898758D03*
X432681D03*
X428981Y924269D03*
X432681D03*
X427130Y940214D03*
X430831D03*
X427130Y933836D03*
X430831D03*
X427130Y946592D03*
Y952970D03*
X430831Y946592D03*
Y952970D03*
X428981Y943403D03*
Y956159D03*
X432681Y943403D03*
Y956159D03*
X428981Y968915D03*
X432681D03*
X427130Y959348D03*
Y965726D03*
X430831Y959348D03*
Y965726D03*
X427130Y984860D03*
X432681Y981671D03*
X434532Y984860D03*
X427130Y978482D03*
Y972104D03*
X430831Y978482D03*
Y972104D03*
X432681Y988049D03*
X434532Y991238D03*
X427118Y997608D03*
X427130Y991238D03*
X434519Y997608D03*
X428299Y1040820D03*
X428311Y1059946D03*
X432012D03*
X428311Y1047190D03*
X435713D03*
X433862Y1050379D03*
X426461D03*
Y1056757D03*
X428311Y1053568D03*
X433862Y1056757D03*
X435713Y1053568D03*
X428311Y1072702D03*
Y1066324D03*
X432012Y1072702D03*
Y1066324D03*
X430162Y1069513D03*
X433862D03*
X428311Y1079080D03*
X432012D03*
X428311Y1085458D03*
X432012D03*
X430162Y1082269D03*
X433862D03*
X428311Y1098214D03*
Y1091836D03*
X432012Y1098214D03*
Y1091836D03*
X430162Y1095025D03*
X428311Y1104592D03*
X433862Y1095025D03*
X432012Y1104592D03*
Y1117348D03*
Y1110970D03*
X428311Y1117348D03*
Y1110970D03*
X430162Y1114159D03*
X433862D03*
X432012Y1123726D03*
X428311D03*
X430162Y1126915D03*
X433862D03*
X430162Y1139670D03*
Y1146048D03*
X433862Y1139670D03*
Y1146048D03*
Y1158804D03*
X432012Y1161993D03*
X428311D03*
X426461Y1152426D03*
X430162D03*
X433862D03*
X432012Y1155615D03*
X426461Y1158804D03*
X428311Y1155615D03*
X454861Y873246D03*
X453011Y876435D03*
X449310D03*
X451160Y879624D03*
X454861D03*
X451160Y873246D03*
Y886002D03*
X454861D03*
X451160Y892380D03*
X447460D03*
Y886002D03*
X449310Y882813D03*
X451160Y911513D03*
X447460D03*
X451160Y898758D03*
X447460D03*
X449310Y921080D03*
Y914702D03*
X453011Y921080D03*
Y914702D03*
X451160Y924269D03*
X447460D03*
X453011Y940214D03*
X449310D03*
Y927458D03*
X453011D03*
X449310Y933836D03*
X453011D03*
Y952970D03*
Y946592D03*
X449310Y952970D03*
Y946592D03*
X451160Y943403D03*
Y956159D03*
X447460Y943403D03*
Y956159D03*
X453011Y959348D03*
Y965726D03*
X449310Y959348D03*
Y965726D03*
X451160Y968915D03*
X447460D03*
X453011Y978482D03*
Y972104D03*
X449310Y978482D03*
Y972104D03*
X451160Y981671D03*
X449310Y984860D03*
X449323Y997608D03*
X451160Y988049D03*
X449310Y991238D03*
X454192Y1059946D03*
X450491D03*
Y1047190D03*
X452341Y1056757D03*
X450491Y1053568D03*
X452341Y1050379D03*
X454192Y1066324D03*
Y1072702D03*
X450491Y1066324D03*
Y1072702D03*
X448641Y1069513D03*
X452341D03*
X454192Y1079080D03*
X450491D03*
X454192Y1085458D03*
X450491D03*
X448641Y1082269D03*
X452341D03*
X454192Y1091836D03*
Y1098214D03*
X450491Y1091836D03*
Y1098214D03*
X448641Y1095025D03*
X452341D03*
X450491Y1104592D03*
X454192D03*
X450491Y1110970D03*
Y1117348D03*
X454192Y1110970D03*
Y1117348D03*
X448641Y1114159D03*
X452341D03*
X450491Y1123726D03*
X454192D03*
X448641Y1126915D03*
X452341D03*
X448641Y1139670D03*
X452341D03*
X448641Y1146048D03*
X452341D03*
X450491Y1161993D03*
X452341Y1165182D03*
X454192Y1161993D03*
X452341Y1152426D03*
X448640Y1165182D03*
X448641Y1158804D03*
X452341D03*
X450491Y1155615D03*
X444953Y1507509D03*
X442753D03*
X442918Y1513218D03*
X441660Y1521612D03*
X441259Y1518121D03*
X452328Y1530608D03*
X453903Y1533336D03*
X441706Y1535698D03*
Y1537898D03*
X443153Y1540317D03*
X447224Y1544625D03*
X462263Y879624D03*
X458562D03*
Y873246D03*
X462263D03*
X456712Y876435D03*
X467814D03*
X464113D03*
X465964Y879624D03*
Y873246D03*
X460412Y882813D03*
X464113D03*
X469664Y886002D03*
X456712Y889191D03*
X460412Y895569D03*
X465964Y886002D03*
X467814Y889191D03*
X464113Y895569D03*
X462263Y886002D03*
X458562D03*
X456712Y882813D03*
X458562Y911513D03*
X469664D03*
X462263D03*
X460412Y908325D03*
X464113D03*
X458562Y924269D03*
Y917891D03*
X469664Y924269D03*
Y917891D03*
X462263Y924269D03*
Y917891D03*
X460412Y921080D03*
X464113D03*
X462263Y937025D03*
X458562D03*
X462263Y930647D03*
X458562D03*
X460412Y940214D03*
X469664Y930647D03*
X464113Y940214D03*
X465964Y930647D03*
X469664Y937025D03*
X462263Y956159D03*
Y943403D03*
Y949781D03*
X458562Y956159D03*
Y943403D03*
Y949781D03*
X469664Y956159D03*
Y943403D03*
Y949781D03*
X460412Y952970D03*
X464113D03*
X462263Y962537D03*
Y968915D03*
X458562Y962537D03*
Y968915D03*
X469664Y962537D03*
Y968915D03*
X460412Y965726D03*
X464113D03*
X462263Y975293D03*
X458562D03*
X469664D03*
X460412Y978482D03*
X458562Y981671D03*
X456712Y984860D03*
X464113Y978482D03*
X465964Y981671D03*
X464113Y984860D03*
X458562Y988049D03*
X456724Y997608D03*
X456712Y991238D03*
X464126Y997608D03*
X465964Y988049D03*
X464113Y991238D03*
X457905Y1040820D03*
X465307D03*
X457893Y1047190D03*
X465294D03*
X459743Y1050379D03*
X465294Y1053568D03*
X467145Y1056757D03*
Y1050379D03*
X457893Y1053568D03*
X461593Y1059946D03*
X459743Y1056757D03*
X465294Y1059946D03*
X463444Y1063135D03*
Y1069513D03*
X459743Y1063135D03*
Y1069513D03*
X461593Y1072702D03*
X465294D03*
X463444Y1075891D03*
X459743D03*
X463444Y1082269D03*
Y1088647D03*
X459743Y1082269D03*
Y1088647D03*
X461593Y1085458D03*
X465294D03*
X463444Y1101403D03*
Y1095025D03*
X459743Y1101403D03*
Y1095025D03*
X461593Y1098214D03*
X465294D03*
X459743Y1114159D03*
X463444D03*
X459743Y1107781D03*
X461593Y1117348D03*
X463444Y1107781D03*
X465294Y1117348D03*
X459743Y1126915D03*
Y1120537D03*
X463444Y1126915D03*
Y1120537D03*
X461593Y1130103D03*
X465294D03*
X461593Y1142859D03*
X457893Y1149237D03*
X465294Y1142859D03*
X468995Y1149237D03*
X467145Y1165182D03*
X468995Y1161993D03*
X465294D03*
X467145Y1152426D03*
X457893Y1161993D03*
X456042Y1152426D03*
X459743Y1165182D03*
X456042Y1158804D03*
X457893Y1155615D03*
X456042Y1165182D03*
X461593Y1161993D03*
Y1155615D03*
X463444Y1152426D03*
Y1158804D03*
X467145D03*
X468995Y1155615D03*
X463444Y1165182D03*
X457052Y1530608D03*
X461777D03*
X466501D03*
X458627Y1533336D03*
X463351D03*
X468076D03*
X484467Y873246D03*
X473365D03*
X477066D03*
X484467Y879624D03*
X477066D03*
X473365D03*
X475215Y876435D03*
X478916D03*
X484467Y886002D03*
X480767D03*
X473365D03*
X477066D03*
X475215Y895569D03*
X471515D03*
X478916Y889191D03*
X482617Y895569D03*
X480767Y911513D03*
X484467D03*
X473365D03*
X475215Y908325D03*
X471515D03*
X482617D03*
X480767Y917891D03*
Y924269D03*
X484467Y917891D03*
Y924269D03*
X473365D03*
Y917891D03*
X475215Y921080D03*
X471515D03*
X482617D03*
X480767Y930647D03*
X484467D03*
X473365D03*
X471515Y940214D03*
X475215D03*
X482617D03*
X477066Y937025D03*
X480767D03*
X475215Y933836D03*
X471515D03*
X484467Y937025D03*
X473365D03*
X484467Y956159D03*
Y943403D03*
Y949781D03*
X473365Y956159D03*
Y943403D03*
Y949781D03*
X480767Y956159D03*
Y943403D03*
Y949781D03*
X475215Y952970D03*
X471515D03*
X482617D03*
X484467Y962537D03*
Y968915D03*
X473365Y962537D03*
Y968915D03*
X480767Y962537D03*
Y968915D03*
X475215Y965726D03*
X471515D03*
X482617D03*
X484467Y975293D03*
X473365D03*
X480767D03*
X475215Y978482D03*
X471515D03*
X473365Y981671D03*
X471515Y984860D03*
X478916D03*
X482617Y978482D03*
X480767Y981671D03*
X473365Y988049D03*
X471527Y997608D03*
X471515Y991238D03*
X478916Y997616D03*
Y991238D03*
X480767Y994427D03*
Y988049D03*
Y1000805D03*
X478916Y1003994D03*
Y1010372D03*
X480767Y1007183D03*
X483798Y1028056D03*
X472708Y1040820D03*
X481948Y1044001D03*
Y1037623D03*
X480097Y1040812D03*
X483798Y1034434D03*
X478247Y1031245D03*
X472696Y1047190D03*
X480097D03*
X474546Y1050379D03*
Y1056757D03*
X472696Y1053568D03*
Y1059946D03*
X476397D03*
X483798D03*
X481948Y1056757D03*
X480097Y1053568D03*
X481948Y1050379D03*
X474546Y1063135D03*
Y1069513D03*
X481948Y1063135D03*
Y1069513D03*
X470845Y1063135D03*
Y1069513D03*
X476397Y1072702D03*
X472696D03*
X483798D03*
X474546Y1075891D03*
X481948D03*
X470845D03*
X474546Y1082269D03*
Y1088647D03*
X481948Y1082269D03*
Y1088647D03*
X470845Y1082269D03*
Y1088647D03*
X472696Y1085458D03*
X476397D03*
X483798D03*
X474546Y1095025D03*
X481948D03*
X470845D03*
X472696Y1098214D03*
X476397D03*
X483798D03*
X478247Y1101403D03*
X472696Y1104592D03*
X481948Y1101403D03*
X476397Y1104592D03*
X470845Y1101403D03*
X474546D03*
X481948Y1114159D03*
X470845D03*
X481948Y1107781D03*
X474546Y1114159D03*
X470845Y1107781D03*
X474546D03*
X476397Y1117348D03*
X472696D03*
X483798D03*
X481948Y1126915D03*
Y1120537D03*
X470845Y1126915D03*
Y1120537D03*
X474546Y1126915D03*
Y1120537D03*
X472696Y1130103D03*
X483798D03*
X476396D03*
X472696Y1142859D03*
X476397D03*
X483798D03*
X480097Y1149237D03*
X483798Y1155615D03*
X480097Y1161993D03*
X476397D03*
X478247Y1152426D03*
X470846Y1165182D03*
X481948D03*
X483798Y1161993D03*
X472696Y1155615D03*
X481948Y1152426D03*
X478247Y1158804D03*
X474546D03*
X478247Y1165182D03*
X480097Y1155615D03*
X474546Y1165182D03*
X470845Y1152426D03*
X472696Y1161993D03*
X471225Y1530608D03*
X475950D03*
X480674D03*
X472800Y1533336D03*
X477525D03*
X482249D03*
X499271Y879624D03*
X488168Y873246D03*
Y879624D03*
X486318Y876435D03*
X490019D03*
X497420D03*
X495570Y879624D03*
Y886002D03*
X491869D03*
X488168D03*
X490019Y889191D03*
X493719Y895569D03*
X486318D03*
X499271Y886002D03*
X497420Y895569D03*
Y882813D03*
X493719Y908325D03*
X486318D03*
X497420D03*
X491869Y917891D03*
Y924269D03*
X495570Y917891D03*
Y924269D03*
X493719Y921080D03*
X486318D03*
X497420D03*
X491869Y930647D03*
X495570D03*
X493719Y940214D03*
X486318D03*
X497420D03*
X499271Y937025D03*
X488168D03*
X491869D03*
X495570D03*
Y956159D03*
Y943403D03*
Y949781D03*
X491869Y956159D03*
Y943403D03*
Y949781D03*
X486318Y952970D03*
X493719D03*
X497420D03*
X495570Y962537D03*
Y968915D03*
X491869Y962537D03*
Y968915D03*
X493719Y965726D03*
X486318D03*
X497420D03*
X495570Y975293D03*
X491869D03*
X493719Y978482D03*
X486318D03*
X488168Y981671D03*
X493719Y984860D03*
X486318D03*
X495570Y981671D03*
X497420Y978482D03*
X488168Y988049D03*
Y994427D03*
X486318Y997616D03*
X493719D03*
X486318Y991238D03*
X493719D03*
X488168Y1000805D03*
X495570Y994427D03*
Y988049D03*
Y1000805D03*
X488168Y1007183D03*
X486318Y1003994D03*
Y1010372D03*
X493719Y1003994D03*
Y1010372D03*
X495570Y1007183D03*
X491200Y1028056D03*
X498601D03*
X494901Y1040812D03*
X489349Y1044001D03*
X487499Y1040812D03*
X489349Y1037623D03*
X496751Y1044001D03*
Y1037623D03*
X485649Y1031245D03*
X493050D03*
X491200Y1034434D03*
X498601D03*
X496751Y1050379D03*
X494901Y1047190D03*
X487499D03*
X489349Y1050379D03*
X494901Y1059946D03*
Y1053568D03*
X487499Y1059946D03*
X489349Y1056757D03*
X487499Y1053568D03*
X496751Y1056757D03*
X498601Y1059946D03*
X485649Y1063135D03*
Y1069513D03*
X496751Y1063135D03*
Y1069513D03*
X493050Y1063135D03*
Y1069513D03*
X494901Y1072702D03*
X487499D03*
X498601D03*
X485649Y1075891D03*
X496751D03*
X493050D03*
X485649Y1082269D03*
Y1088647D03*
X496751Y1082269D03*
Y1088647D03*
X493050Y1082269D03*
Y1088647D03*
X494901Y1085458D03*
X487499D03*
X498601D03*
X485649Y1095025D03*
X496751D03*
X493050D03*
X494901Y1098214D03*
X487499D03*
X498601D03*
X493050Y1101403D03*
X485649D03*
X489349D03*
X493050Y1107781D03*
Y1114159D03*
X485649D03*
X496751Y1107781D03*
Y1114159D03*
X485649Y1107781D03*
X494901Y1117348D03*
X487499D03*
X498601D03*
X493050Y1120537D03*
X485649Y1126915D03*
Y1120537D03*
X496751D03*
X487499Y1130103D03*
X494901D03*
X498601D03*
X494901Y1142859D03*
X487499D03*
X491200Y1149237D03*
X498601Y1142859D03*
Y1161993D03*
X487499D03*
X491200D03*
X489349Y1152426D03*
X493050Y1165182D03*
X485649Y1158804D03*
Y1165182D03*
X496751D03*
Y1158804D03*
X489349D03*
X491200Y1155615D03*
X493050Y1152426D03*
X494901Y1161993D03*
Y1155615D03*
X489349Y1165182D03*
X499572Y1530608D03*
X485399D03*
X490123D03*
X494847D03*
X486973Y1533336D03*
X491698D03*
X496422D03*
X510373Y879624D03*
X514074D03*
X508523Y876435D03*
X506672Y879624D03*
X512223Y876435D03*
X501121D03*
Y889191D03*
X512223Y895569D03*
X501121Y882813D03*
X514074Y905135D03*
X501121Y901947D03*
X512223Y914702D03*
X514074Y924269D03*
X501121Y914702D03*
X512223Y933836D03*
X501121Y927458D03*
X514074Y943403D03*
X512223Y952970D03*
X501121Y946592D03*
X514074Y962537D03*
X501121Y959348D03*
X514074Y981671D03*
X512223Y972104D03*
X501121D03*
Y984860D03*
Y997616D03*
Y991238D03*
X512223D03*
X514074Y1000805D03*
X502971Y994427D03*
X508523Y991238D03*
X501121Y1010372D03*
X512223D03*
X501121Y1003994D03*
X504822Y1010372D03*
X506003Y1028056D03*
X509704D03*
X502302Y1040812D03*
X500452Y1031245D03*
X511554Y1044001D03*
Y1031245D03*
X502302Y1047190D03*
Y1053568D03*
X513405Y1047190D03*
X511554Y1056757D03*
X509704Y1047190D03*
X506003Y1053568D03*
X513405Y1066324D03*
X502302D03*
X513405Y1085458D03*
X502302Y1079080D03*
X513405Y1104592D03*
X502302Y1091836D03*
X500452Y1101403D03*
X502302Y1110970D03*
X513405Y1123726D03*
X502302D03*
X513405Y1142859D03*
X502302Y1136481D03*
Y1149237D03*
X513405Y1161993D03*
X511554Y1158804D03*
X509704Y1161993D03*
X502302D03*
X500452Y1152426D03*
X506003Y1161993D03*
X500452Y1158804D03*
Y1165182D03*
X507853D03*
X504153D03*
X504296Y1530608D03*
X509021D03*
X513745D03*
X501147Y1533336D03*
X505871D03*
X510595D03*
X521475Y879624D03*
X519625Y876435D03*
X517775Y879624D03*
X521475Y873246D03*
X517775D03*
X527027Y876435D03*
X528877Y879624D03*
Y892380D03*
X515924Y882813D03*
X527027D03*
X528877Y911513D03*
Y905135D03*
Y898758D03*
Y924269D03*
Y917891D03*
Y930647D03*
Y937025D03*
Y943403D03*
Y949781D03*
Y956159D03*
Y968915D03*
Y962537D03*
Y981671D03*
Y975293D03*
Y988049D03*
Y1000805D03*
X517775Y994427D03*
X523326Y991238D03*
X528877Y994427D03*
Y1007183D03*
X515924Y1010372D03*
X517105Y1028056D03*
X524507D03*
X515255Y1037623D03*
X522656Y1044001D03*
Y1031245D03*
X515255Y1056757D03*
X522656D03*
X524507Y1047190D03*
X517105Y1053568D03*
X515255Y1075891D03*
Y1095025D03*
Y1114159D03*
Y1133293D03*
X528208Y1161993D03*
X515255Y1152426D03*
X524507Y1161993D03*
X520806D03*
X518956Y1158804D03*
X529594Y1507355D03*
X527494D03*
X518470Y1530608D03*
X523194D03*
X515320Y1533336D03*
X520044D03*
X524769D03*
X530727Y876435D03*
X532578Y873246D03*
X536279Y886002D03*
X530727Y889191D03*
X534428D03*
Y895569D03*
X530727D03*
X536279Y892380D03*
X541830Y889191D03*
X543680Y892380D03*
X541830Y895569D03*
X538129D03*
X539979Y886002D03*
X530727Y882813D03*
X541830D03*
X534428Y908325D03*
X536279Y898758D03*
X530727Y901947D03*
X534428D03*
X536279Y905135D03*
X530727Y908325D03*
X536279Y911513D03*
X543680D03*
X541830Y901947D03*
X543680Y905135D03*
X541830Y908325D03*
X543680Y898758D03*
X539979Y905135D03*
X536279Y917891D03*
X530727Y921080D03*
X534428D03*
X536279Y924269D03*
X534428Y914702D03*
X530727D03*
X541830Y921080D03*
X543680Y924269D03*
X541830Y914702D03*
X543680Y917891D03*
X539979Y924269D03*
X538129Y914702D03*
X530727Y927458D03*
X534428D03*
X536279Y937025D03*
X530727Y940214D03*
X534428D03*
Y933836D03*
X530727D03*
X536279Y930647D03*
X541830Y927458D03*
X543680Y930647D03*
X541830Y940214D03*
Y933836D03*
X543680Y937025D03*
X538129Y933836D03*
X536279Y943403D03*
X530727Y946592D03*
X534428D03*
X536279Y956159D03*
X534428Y952970D03*
X530727D03*
X536279Y949781D03*
X543680Y943403D03*
X541830Y946592D03*
X543680Y949781D03*
X541830Y952970D03*
X543680Y956159D03*
X538129Y952970D03*
X539979Y943403D03*
X536279Y962537D03*
X530727Y965726D03*
X534428D03*
X530727Y959348D03*
X534428D03*
X536279Y968915D03*
X541830Y965726D03*
X543680Y968915D03*
X541830Y959348D03*
X543680Y962537D03*
X539979D03*
X530727Y984860D03*
X536279Y975293D03*
X530727Y978482D03*
X534428D03*
Y972104D03*
X530727D03*
X541830Y984860D03*
Y978482D03*
X543680Y981671D03*
X541830Y972104D03*
X543680Y975293D03*
X538129Y972104D03*
X539979Y981671D03*
X536279Y994427D03*
X534428Y997616D03*
X530727D03*
X536279Y1000805D03*
Y988049D03*
X530727Y991238D03*
X543680Y988049D03*
X541830Y997616D03*
X543680Y1000805D03*
X541830Y991238D03*
X539979Y1000805D03*
X538129Y991238D03*
X543680Y994427D03*
X534428Y991238D03*
Y1010372D03*
X536279Y1007183D03*
X534428Y1003994D03*
X530727D03*
X541830D03*
X543680Y1007183D03*
X538129Y1010372D03*
X530727D03*
X541830D03*
X531908Y1028056D03*
X543011D03*
X535609D03*
X530058Y1031245D03*
X531908Y1034434D03*
X535609D03*
X537460Y1037623D03*
X530058D03*
X531908Y1040812D03*
X535609D03*
X530058Y1044001D03*
X543011Y1034434D03*
Y1040812D03*
X541160Y1037623D03*
X537460Y1044001D03*
Y1031245D03*
X530058Y1050379D03*
X535609Y1059946D03*
X531908Y1047190D03*
X537460Y1050379D03*
X535609Y1053568D03*
X543011Y1047190D03*
X541160Y1056757D03*
X539310Y1047190D03*
X543011Y1053568D03*
X537460Y1056757D03*
X535609Y1047190D03*
X531908Y1053568D03*
X535609Y1072702D03*
X530058Y1063135D03*
X537460D03*
X531908Y1066324D03*
X530058Y1069513D03*
X537460D03*
X531908Y1072702D03*
X535609Y1066324D03*
X543011D03*
Y1072702D03*
X539310Y1066324D03*
X530058Y1075891D03*
X537460D03*
X531908Y1079080D03*
X535609D03*
X530058Y1082269D03*
X537460D03*
X531908Y1085458D03*
X537460Y1088647D03*
X530058D03*
X535609Y1085458D03*
X543011Y1079080D03*
Y1085458D03*
X539310D03*
X541160Y1075891D03*
X537460Y1101403D03*
X531908Y1104592D03*
X535609Y1091836D03*
X530058Y1095025D03*
X537460D03*
X531908Y1098214D03*
X535609D03*
X530058Y1101403D03*
X535609Y1104592D03*
X531908Y1091836D03*
X543011Y1104592D03*
Y1098214D03*
Y1091836D03*
X541160Y1095025D03*
X539310Y1104592D03*
X535609Y1110970D03*
X530058Y1114159D03*
X537460D03*
X531908Y1117348D03*
X535609D03*
X537460Y1107781D03*
X530058D03*
X531908Y1110970D03*
X543011Y1117348D03*
Y1110970D03*
X541160Y1114159D03*
X530058Y1120537D03*
X537460D03*
X531908Y1123726D03*
X535609Y1130103D03*
X530058Y1133293D03*
X537460D03*
Y1126915D03*
X530058D03*
X535609Y1123726D03*
X531908Y1130103D03*
X543011Y1123726D03*
Y1130103D03*
X539310Y1123726D03*
X541160Y1133293D03*
X531908Y1136481D03*
X535609D03*
X530058Y1139670D03*
X537460D03*
X531908Y1142859D03*
X535609Y1149237D03*
X537460Y1146048D03*
X530058D03*
X535609Y1142859D03*
X531908Y1149237D03*
X543011Y1136481D03*
Y1142859D03*
Y1149237D03*
X539310Y1142859D03*
X530058Y1152426D03*
X537460D03*
X531908Y1155615D03*
X541160Y1152426D03*
X531908Y1161993D03*
X535609D03*
X539310D03*
X537460Y1158804D03*
X541160D03*
X531001Y1514073D03*
X530945Y1516336D03*
X532310Y1536640D03*
X531926Y1534540D03*
X531537Y1531618D03*
X531208Y1528698D03*
X530711Y1538658D03*
X554783Y879624D03*
X556633Y889191D03*
X554783Y892380D03*
X556633Y895569D03*
X547381Y886002D03*
X549231Y889191D03*
Y895569D03*
X547381Y892380D03*
X556633Y882813D03*
X552932D03*
X554783Y911513D03*
X556633Y901947D03*
X554783Y905135D03*
X556633Y908325D03*
X554783Y898758D03*
X549231Y908325D03*
X547381Y898758D03*
X549231Y901947D03*
X547381Y905135D03*
Y911513D03*
X556633Y921080D03*
X554783Y924269D03*
X556633Y914702D03*
X554783Y917891D03*
X547381D03*
X549231Y921080D03*
X547381Y924269D03*
X549231Y914702D03*
X556633Y927458D03*
X554783Y930647D03*
X556633Y940214D03*
Y933836D03*
X554783Y937025D03*
X549231Y927458D03*
X547381Y937025D03*
X549231Y940214D03*
Y933836D03*
X547381Y930647D03*
X554783Y943403D03*
X556633Y946592D03*
X554783Y949781D03*
X556633Y952970D03*
X554783Y956159D03*
X547381Y943403D03*
X549231Y946592D03*
X547381Y956159D03*
X549231Y952970D03*
X547381Y949781D03*
X556633Y965726D03*
X554783Y968915D03*
X556633Y959348D03*
X554783Y962537D03*
X547381D03*
X549231Y965726D03*
Y959348D03*
X547381Y968915D03*
X556633Y984860D03*
Y978482D03*
X554783Y981671D03*
X556633Y972104D03*
X554783Y975293D03*
X547381D03*
X549231Y978482D03*
Y972104D03*
X554783Y988049D03*
X556633Y997616D03*
X554783Y1000805D03*
X556633Y991238D03*
X547381Y994427D03*
X549231Y997616D03*
X547381Y1000805D03*
Y988049D03*
X554782Y994427D03*
X549231Y991238D03*
X556633Y1003994D03*
X554783Y1007183D03*
X549231Y1010372D03*
X547381Y1007183D03*
X549231Y1003994D03*
X556633Y1010372D03*
X557814Y1028056D03*
X550412D03*
X555964Y1031245D03*
X557814Y1034434D03*
X555964Y1037623D03*
X557814Y1040812D03*
X555964Y1044001D03*
X544861Y1031245D03*
X550412Y1034434D03*
X548562Y1037623D03*
X544861D03*
X550412Y1040812D03*
X544861Y1044001D03*
X548562D03*
Y1031245D03*
X555964Y1050379D03*
X557814Y1047190D03*
X544861Y1050379D03*
X550412Y1059946D03*
X548562Y1050379D03*
X550412Y1053568D03*
X557814D03*
X548562Y1056757D03*
X550412Y1047190D03*
X555964Y1063135D03*
X557814Y1066324D03*
X555964Y1069513D03*
X557814Y1072702D03*
X550412D03*
X544861Y1063135D03*
X548562D03*
X544861Y1069513D03*
X548562D03*
X550412Y1066324D03*
X555964Y1075891D03*
X557814Y1079080D03*
X555964Y1082269D03*
X557814Y1085458D03*
X555964Y1088647D03*
X544861Y1075891D03*
X548562D03*
X550412Y1079080D03*
X544861Y1082269D03*
X548562D03*
Y1088647D03*
X544861D03*
X550412Y1085458D03*
X557814Y1104592D03*
X555964Y1095025D03*
X557814Y1098214D03*
X555964Y1101403D03*
X557814Y1091836D03*
X548562Y1101403D03*
X550412Y1091836D03*
X544861Y1095025D03*
X548562D03*
X550412Y1098214D03*
X544861Y1101403D03*
X550412Y1104592D03*
X555964Y1114159D03*
X557814Y1117348D03*
X555964Y1107781D03*
X557814Y1110970D03*
X550412D03*
X544861Y1114159D03*
X548562D03*
X550412Y1117348D03*
X548562Y1107781D03*
X544861D03*
X555964Y1120537D03*
X557814Y1123726D03*
X555964Y1133293D03*
Y1126915D03*
X557814Y1130103D03*
X544861Y1120537D03*
X548562D03*
X550412Y1130103D03*
X544861Y1133293D03*
X548562D03*
Y1126915D03*
X544861D03*
X550412Y1123726D03*
X557814Y1136481D03*
X555964Y1139670D03*
X557814Y1142859D03*
X555964Y1146048D03*
X557814Y1149237D03*
X550412Y1136481D03*
X544861Y1139670D03*
X548562D03*
X550412Y1149237D03*
X548562Y1146048D03*
X544861D03*
X550412Y1142859D03*
X546712Y1161993D03*
X555964Y1152426D03*
X557814Y1155615D03*
X544861Y1152426D03*
X548562D03*
X550412Y1155615D03*
X557814Y1161993D03*
X544861Y1158804D03*
X562184Y873246D03*
X565885Y879624D03*
X564034Y876435D03*
X573286Y879624D03*
X571436Y876435D03*
X569586Y879624D03*
X562184Y886002D03*
X560334Y889191D03*
Y895569D03*
X562184Y892380D03*
X564034Y895569D03*
X565885Y886002D03*
X567735Y882813D03*
X560334Y908325D03*
X562184Y898758D03*
X560334Y901947D03*
X562184Y905135D03*
Y911513D03*
X565885Y905135D03*
X562184Y917891D03*
X560334Y921080D03*
X562184Y924269D03*
X560334Y914702D03*
X565885Y924269D03*
X564034Y914702D03*
X560334Y927458D03*
X562184Y937025D03*
X560334Y940214D03*
Y933836D03*
X562184Y930647D03*
X564034Y933836D03*
X562184Y943403D03*
X560334Y946592D03*
X562184Y956159D03*
X560334Y952970D03*
X562184Y949781D03*
X564034Y952970D03*
X565885Y943403D03*
X562184Y962537D03*
X560334Y965726D03*
Y959348D03*
X562184Y968915D03*
X565885Y962537D03*
X562184Y975293D03*
X560334Y978482D03*
Y972104D03*
X565885Y981671D03*
X564034Y972104D03*
X562184Y994427D03*
X560334Y997616D03*
X562184Y1000805D03*
Y988049D03*
X565885Y1000805D03*
X564034Y991238D03*
X560334D03*
Y1010372D03*
X562184Y1007183D03*
X560334Y1003994D03*
X564034Y1010372D03*
X567735D03*
X568916Y1028056D03*
X561515D03*
Y1034434D03*
X563365Y1037623D03*
X561515Y1040812D03*
X567066Y1037623D03*
X563365Y1044001D03*
Y1031245D03*
X561515Y1059946D03*
X563365Y1050379D03*
X561515Y1053568D03*
X567066Y1056757D03*
X565215Y1047190D03*
X563365Y1056757D03*
X561515Y1047190D03*
Y1072702D03*
X563365Y1063135D03*
Y1069513D03*
X561515Y1066324D03*
X565215D03*
X563365Y1075891D03*
X561515Y1079080D03*
X563365Y1082269D03*
Y1088647D03*
X561515Y1085458D03*
X565215D03*
X567066Y1075891D03*
X563365Y1101403D03*
X561515Y1091836D03*
X563365Y1095025D03*
X561515Y1098214D03*
Y1104592D03*
X565215D03*
X567066Y1095025D03*
X561515Y1110970D03*
X563365Y1114159D03*
X561515Y1117348D03*
X563365Y1107781D03*
X567066Y1114159D03*
X563365Y1120537D03*
X561515Y1130103D03*
X563365Y1133293D03*
Y1126915D03*
X561515Y1123726D03*
X567066Y1133293D03*
X565215Y1123726D03*
X561515Y1136481D03*
X563365Y1139670D03*
X561515Y1149237D03*
X563365Y1146048D03*
X561515Y1142859D03*
X565215D03*
X567066Y1158804D03*
X563365Y1152426D03*
Y1158804D03*
X567066Y1152426D03*
X572617Y1161993D03*
X570767Y1165182D03*
X567066D03*
X568916Y1161993D03*
X570815Y1507509D03*
X573066Y1507460D03*
X570980Y1513218D03*
X569722Y1521612D03*
X569321Y1518121D03*
X569768Y1535698D03*
Y1537898D03*
X571215Y1540317D03*
X580390Y1516970D03*
X585114D03*
X581965Y1519698D03*
X586689D03*
X575286Y1544625D03*
X589839Y1516970D03*
X594563D03*
X599287D03*
X604012D03*
X591413Y1519698D03*
X596138D03*
X600862D03*
X608736Y1516970D03*
X613461D03*
X618185D03*
X605587Y1519698D03*
X610311D03*
X615035D03*
X627634Y1516970D03*
X632358D03*
X622909D03*
X629209Y1519698D03*
X633933D03*
X619760D03*
X624484D03*
X637083Y1516970D03*
X641807D03*
X646532D03*
X638657Y1519698D03*
X643382D03*
X648106D03*
X657656Y1507355D03*
X655556D03*
X651256Y1516970D03*
X652831Y1519698D03*
X659063Y1514073D03*
X659007Y1516336D03*
X659358Y1536640D03*
Y1534540D03*
X659359Y1531618D03*
X659270Y1528698D03*
X662353Y1534413D03*
X660877Y1530158D03*
X658773Y1538658D03*
X1184959Y1551121D03*
X1185360Y1554612D03*
X1185406Y1568698D03*
Y1570898D03*
X1196028Y1549970D03*
X1197603Y1552698D03*
X1188653Y1540509D03*
X1186453D03*
X1186618Y1546218D03*
X1186853Y1573317D03*
X1190924Y1577625D03*
X1200752Y1549970D03*
X1205477D03*
X1210201D03*
X1214925D03*
X1202327Y1552698D03*
X1207051D03*
X1211776D03*
X1219650Y1549970D03*
X1224374D03*
X1229099D03*
X1216500Y1552698D03*
X1221225D03*
X1225949D03*
X1243272Y1549970D03*
X1233823D03*
X1238547D03*
X1244847Y1552698D03*
X1230673D03*
X1235398D03*
X1240122D03*
X1247996Y1549970D03*
X1252721D03*
X1257445D03*
X1249571Y1552698D03*
X1254295D03*
X1259020D03*
X1262170Y1549970D03*
X1266894D03*
X1263744Y1552698D03*
X1268469D03*
X1273294Y1540355D03*
X1271194D03*
X1274701Y1547073D03*
X1274645Y1549336D03*
X1274996Y1567540D03*
X1274997Y1564618D03*
X1274908Y1561698D03*
X1274411Y1571658D03*
X1274996Y1569640D03*
X1288549Y876434D03*
X1288548Y1010371D03*
X1289729Y1028055D03*
X1297800Y879623D03*
X1299650Y876434D03*
X1290399Y879623D03*
X1303351Y882812D03*
X1294099Y886001D03*
X1299650Y889190D03*
X1295949D03*
X1301500Y892379D03*
X1295949Y895568D03*
X1299650D03*
X1294099Y892379D03*
X1292249Y895568D03*
X1299650Y882812D03*
X1295949Y908324D03*
X1301500Y911512D03*
X1294099Y898757D03*
X1299650Y901946D03*
X1295949D03*
X1301500Y905134D03*
X1294099D03*
X1299650Y908324D03*
X1294099Y911512D03*
X1301500Y898757D03*
X1290398Y905134D03*
X1294099Y917890D03*
X1299650Y921079D03*
X1295949D03*
X1301500Y924268D03*
X1294099D03*
X1295949Y914701D03*
X1299650D03*
X1301500Y917890D03*
X1292249Y914701D03*
X1290398Y924268D03*
X1299650Y927457D03*
X1295949D03*
X1301500Y930646D03*
X1294099Y937024D03*
X1299650Y940213D03*
X1295949D03*
Y933835D03*
X1299650D03*
X1294099Y930646D03*
X1301500Y937024D03*
X1292249Y933835D03*
X1301500Y943402D03*
X1294099D03*
X1299650Y946591D03*
X1295949D03*
X1301500Y949780D03*
X1294099Y956158D03*
X1295949Y952969D03*
X1299650D03*
X1294099Y949780D03*
X1301500Y956158D03*
X1292249Y952969D03*
X1290398Y943402D03*
X1294099Y962536D03*
X1299650Y965725D03*
X1295949D03*
X1301500Y968914D03*
X1299650Y959347D03*
X1295949D03*
X1301500Y962536D03*
X1294099Y968914D03*
X1290398Y962536D03*
X1299650Y984859D03*
X1294099Y975292D03*
X1299650Y978481D03*
X1295949D03*
X1301500Y981670D03*
X1295949Y972103D03*
X1299650D03*
X1301500Y975292D03*
X1292249Y972103D03*
X1290398Y981670D03*
X1301500Y988048D03*
X1294099Y994426D03*
X1295949Y997615D03*
X1299650D03*
X1301500Y1000804D03*
X1294099D03*
X1295949Y991237D03*
X1301500Y994426D03*
X1292249Y991237D03*
X1290398Y1000804D03*
X1299650Y991237D03*
X1294099Y988048D03*
X1295949Y1010371D03*
X1294099Y1007182D03*
X1295949Y1003993D03*
X1299650D03*
X1301500Y1007182D03*
X1299650Y1010371D03*
X1293430Y1028055D03*
X1300831D03*
X1297130D03*
X1302681Y1031244D03*
X1300831Y1034433D03*
X1297130D03*
X1295280Y1037622D03*
X1302681D03*
X1300831Y1040811D03*
X1297130D03*
X1295280Y1044000D03*
X1291579Y1037622D03*
X1302682Y1044000D03*
X1295280Y1031244D03*
X1302681Y1050378D03*
X1297130Y1059945D03*
X1300831Y1047189D03*
X1295280Y1050378D03*
X1297130Y1053567D03*
X1291579Y1056756D03*
X1293430Y1047189D03*
X1295280Y1056756D03*
X1297130Y1047189D03*
X1300831Y1053567D03*
X1297130Y1072701D03*
X1302681Y1063134D03*
X1295280D03*
X1300831Y1066323D03*
X1302681Y1069512D03*
X1295280D03*
X1300831Y1072701D03*
X1297130Y1066323D03*
X1293430D03*
X1302681Y1075890D03*
X1295280D03*
X1300831Y1079079D03*
X1297130D03*
X1302681Y1082268D03*
X1295280D03*
X1300831Y1085457D03*
X1295280Y1088646D03*
X1302681D03*
X1297130Y1085457D03*
X1293430D03*
X1291579Y1075890D03*
X1295280Y1101402D03*
X1300831Y1104591D03*
X1297130Y1091835D03*
X1302681Y1095024D03*
X1295280D03*
X1300831Y1098213D03*
X1297130D03*
X1302681Y1101402D03*
X1297130Y1104591D03*
X1300831Y1091835D03*
X1293430Y1104591D03*
X1291579Y1095024D03*
X1297130Y1110969D03*
X1302681Y1114158D03*
X1295280D03*
X1300831Y1117347D03*
X1297130D03*
X1295280Y1107780D03*
X1302681D03*
X1300831Y1110969D03*
X1291579Y1114158D03*
X1302681Y1120536D03*
X1295280D03*
X1300831Y1123725D03*
X1297130Y1130102D03*
X1302681Y1133292D03*
X1295280D03*
Y1126914D03*
X1302681D03*
X1297130Y1123725D03*
X1300831Y1130102D03*
X1291579Y1133292D03*
X1293430Y1123725D03*
X1300831Y1136480D03*
X1297130D03*
X1302681Y1139669D03*
X1295280D03*
X1300831Y1142858D03*
X1297130Y1149236D03*
X1295280Y1146047D03*
X1302681D03*
X1297130Y1142858D03*
X1300831Y1149236D03*
X1293430Y1142858D03*
X1291579Y1158803D03*
X1302681Y1152425D03*
X1295280D03*
X1300831Y1155614D03*
X1295280Y1158803D03*
X1291579Y1152425D03*
X1300831Y1161992D03*
X1302682Y1165181D03*
X1318154Y876434D03*
X1305201Y879623D03*
X1312603D03*
X1316304D03*
X1307052Y876434D03*
X1308902Y886001D03*
X1314453Y889190D03*
X1307052D03*
X1312603Y892379D03*
X1307052Y895568D03*
X1314453D03*
X1308902Y892379D03*
X1318154Y895568D03*
X1307052Y908324D03*
X1312603Y911512D03*
X1308902Y898757D03*
X1314453Y901946D03*
X1307052D03*
X1312603Y905134D03*
X1308902D03*
X1314453Y908324D03*
X1308902Y911512D03*
X1312603Y898757D03*
X1316304Y905134D03*
X1308902Y917890D03*
X1314453Y921079D03*
X1307052D03*
X1312603Y924268D03*
X1308902D03*
X1307052Y914701D03*
X1314453D03*
X1312603Y917890D03*
X1316304Y924268D03*
X1318154Y914701D03*
X1314453Y927457D03*
X1307052D03*
X1312603Y930646D03*
X1308902Y937024D03*
X1314453Y940213D03*
X1307052D03*
Y933835D03*
X1314453D03*
X1308902Y930646D03*
X1312603Y937024D03*
X1318154Y933835D03*
X1312603Y943402D03*
X1308902D03*
X1314453Y946591D03*
X1307052D03*
X1312603Y949780D03*
X1308902Y956158D03*
X1307052Y952969D03*
X1314453D03*
X1308902Y949780D03*
X1312603Y956158D03*
X1318154Y952969D03*
X1316304Y943402D03*
X1308902Y962536D03*
X1314453Y965725D03*
X1307052D03*
X1312603Y968914D03*
X1314453Y959347D03*
X1307052D03*
X1312603Y962536D03*
X1308902Y968914D03*
X1316304Y962536D03*
X1314453Y984859D03*
X1308902Y975292D03*
X1314453Y978481D03*
X1307052D03*
X1312603Y981670D03*
X1307052Y972103D03*
X1314453D03*
X1312603Y975292D03*
X1316304Y981670D03*
X1318154Y972103D03*
X1312603Y988048D03*
X1308902Y994426D03*
X1307052Y997615D03*
X1314453D03*
X1312603Y1000804D03*
X1308902D03*
X1307052Y991237D03*
X1312603Y994426D03*
X1316304Y1000804D03*
X1318154Y991237D03*
X1314453D03*
X1308902Y988048D03*
X1307052Y1010371D03*
X1308902Y1007182D03*
X1307052Y1003993D03*
X1314453D03*
X1312603Y1007182D03*
X1314453Y1010371D03*
X1319335Y1028055D03*
X1315634D03*
X1308233D03*
X1313784Y1031244D03*
X1315634Y1034433D03*
X1308233D03*
X1310083Y1037622D03*
X1313784D03*
X1315634Y1040811D03*
X1308233D03*
X1310083Y1044000D03*
X1317485Y1037622D03*
X1313784Y1044000D03*
X1310083Y1031244D03*
X1313784Y1050378D03*
X1308233Y1059945D03*
X1315634Y1047189D03*
X1310083Y1050378D03*
X1308233Y1053567D03*
X1317485Y1056756D03*
X1319335Y1047189D03*
X1310083Y1056756D03*
X1308233Y1047189D03*
X1315634Y1053567D03*
X1308233Y1072701D03*
X1313784Y1063134D03*
X1310083D03*
X1315634Y1066323D03*
X1313784Y1069512D03*
X1310083D03*
X1315634Y1072701D03*
X1308233Y1066323D03*
X1319335D03*
X1313784Y1075890D03*
X1310083D03*
X1315634Y1079079D03*
X1308233D03*
X1313784Y1082268D03*
X1310083D03*
X1315634Y1085457D03*
X1310083Y1088646D03*
X1313784D03*
X1308233Y1085457D03*
X1319335D03*
X1317485Y1075890D03*
X1310083Y1101402D03*
X1315634Y1104591D03*
X1308233Y1091835D03*
X1313784Y1095024D03*
X1310083D03*
X1315634Y1098213D03*
X1308233D03*
X1313784Y1101402D03*
X1308233Y1104591D03*
X1315634Y1091835D03*
X1319335Y1104591D03*
X1317485Y1095024D03*
X1308233Y1110969D03*
X1313784Y1114158D03*
X1310083D03*
X1315634Y1117347D03*
X1308233D03*
X1310083Y1107780D03*
X1313784D03*
X1315634Y1110969D03*
X1317485Y1114158D03*
X1313784Y1120536D03*
X1310083D03*
X1315634Y1123725D03*
X1308233Y1130102D03*
X1313784Y1133292D03*
X1310083D03*
Y1126914D03*
X1313784D03*
X1308233Y1123725D03*
X1315634Y1130102D03*
X1317485Y1133292D03*
X1319335Y1123725D03*
X1315634Y1136480D03*
X1308233D03*
X1313784Y1139669D03*
X1310083D03*
X1315634Y1142858D03*
X1308233Y1149236D03*
X1310083Y1146047D03*
X1313784D03*
X1308233Y1142858D03*
X1315634Y1149236D03*
X1319335Y1142858D03*
X1313784Y1152425D03*
X1310083D03*
X1308233Y1155614D03*
X1317485Y1152425D03*
X1308233Y1161992D03*
X1310083Y1165181D03*
X1317485D03*
X1315634Y1161992D03*
X1316766Y1540460D03*
X1314515Y1540509D03*
X1314680Y1546218D03*
X1313021Y1551121D03*
X1313422Y1554612D03*
X1313468Y1568698D03*
Y1570898D03*
X1318986Y1577625D03*
X1314915Y1573317D03*
X1323705Y879623D03*
X1327406D03*
X1321855Y876434D03*
X1332957D03*
X1329256D03*
X1334807Y879623D03*
X1320004Y886001D03*
X1325556Y889190D03*
X1321855D03*
X1327406Y892379D03*
X1321855Y895568D03*
X1325556D03*
X1320004Y892379D03*
X1321855Y908324D03*
X1327406Y911512D03*
X1320004Y898757D03*
X1325556Y901946D03*
X1321855D03*
X1327406Y905134D03*
X1320004D03*
X1325556Y908324D03*
X1320004Y911512D03*
X1327406Y898757D03*
X1320004Y917890D03*
X1325556Y921079D03*
X1321855D03*
X1327406Y924268D03*
X1320004D03*
X1321855Y914701D03*
X1325556D03*
X1327406Y917890D03*
X1325556Y927457D03*
X1321855D03*
X1327406Y930646D03*
X1320004Y937024D03*
X1325556Y940213D03*
X1321855D03*
Y933835D03*
X1325556D03*
X1320004Y930646D03*
X1327406Y937024D03*
Y943402D03*
X1320004D03*
X1325556Y946591D03*
X1321855D03*
X1327406Y949780D03*
X1320004Y956158D03*
X1321855Y952969D03*
X1325556D03*
X1320004Y949780D03*
X1327406Y956158D03*
X1320004Y962536D03*
X1325556Y965725D03*
X1321855D03*
X1327406Y968914D03*
X1325556Y959347D03*
X1321855D03*
X1327406Y962536D03*
X1320004Y968914D03*
X1325556Y984859D03*
X1320004Y975292D03*
X1325556Y978481D03*
X1321855D03*
X1327406Y981670D03*
X1321855Y972103D03*
X1325556D03*
X1327406Y975292D03*
Y988048D03*
X1320004Y994426D03*
X1321855Y997615D03*
X1325556D03*
X1327406Y1000804D03*
X1320004D03*
X1321855Y991237D03*
X1327406Y994426D03*
X1334808Y988048D03*
X1325556Y991237D03*
X1320004Y988048D03*
X1321855Y1010371D03*
X1320004Y1007182D03*
X1321855Y1003993D03*
X1325556D03*
X1327406Y1007182D03*
X1325556Y1010371D03*
X1326737Y1028055D03*
X1334138D03*
X1323036D03*
X1328587Y1031244D03*
X1326737Y1034433D03*
X1323036D03*
X1321185Y1037622D03*
X1328587D03*
X1326737Y1040811D03*
X1323036D03*
X1321185Y1044000D03*
X1328587D03*
X1321185Y1031244D03*
X1328587Y1050378D03*
X1323036Y1059945D03*
X1326737Y1047189D03*
X1321185Y1050378D03*
X1323036Y1053567D03*
X1334138Y1047189D03*
X1321185Y1056756D03*
X1323036Y1047189D03*
X1326737Y1053567D03*
X1323036Y1072701D03*
X1328587Y1063134D03*
X1321185D03*
X1326737Y1066323D03*
X1328587Y1069512D03*
X1321185D03*
X1326737Y1072701D03*
X1323036Y1066323D03*
X1328587Y1075890D03*
X1321185D03*
X1326737Y1079079D03*
X1323036D03*
X1328587Y1082268D03*
X1321185D03*
X1326737Y1085457D03*
X1321185Y1088646D03*
X1328587D03*
X1323036Y1085457D03*
X1321185Y1101402D03*
X1326737Y1104591D03*
X1323036Y1091835D03*
X1328587Y1095024D03*
X1321185D03*
X1326737Y1098213D03*
X1323036D03*
X1328587Y1101402D03*
X1323036Y1104591D03*
X1326737Y1091835D03*
X1323036Y1110969D03*
X1328587Y1114158D03*
X1321185D03*
X1326737Y1117347D03*
X1323036D03*
X1321185Y1107780D03*
X1328587D03*
X1326737Y1110969D03*
X1328587Y1120536D03*
X1321185D03*
X1326737Y1123725D03*
X1323036Y1130102D03*
X1328587Y1133292D03*
X1321185D03*
Y1126914D03*
X1328587D03*
X1323036Y1123725D03*
X1326737Y1130102D03*
Y1136480D03*
X1323036D03*
X1328587Y1139669D03*
X1321185D03*
X1326737Y1142858D03*
X1323036Y1149236D03*
X1321185Y1146047D03*
X1328587D03*
X1323036Y1142858D03*
X1326737Y1149236D03*
X1328587Y1152425D03*
X1321185D03*
X1326737Y1155614D03*
X1321185Y1158803D03*
X1334138Y1161992D03*
X1324090Y1549970D03*
X1328814D03*
X1333539D03*
X1325665Y1552698D03*
X1330389D03*
X1324090Y1563608D03*
X1328814D03*
X1333539D03*
X1325665Y1566336D03*
X1330389D03*
X1344059Y876434D03*
X1347760D03*
X1340359D03*
X1347760Y882812D03*
X1344059Y895568D03*
X1342209Y905134D03*
X1344059Y914701D03*
X1342209Y924268D03*
X1344059Y933835D03*
X1342209Y943402D03*
X1344059Y952969D03*
X1342209Y962536D03*
Y981670D03*
X1344059Y972103D03*
Y991237D03*
X1342209Y1000804D03*
X1340359Y991237D03*
X1345910Y988048D03*
X1340359Y1010371D03*
X1345241Y1028055D03*
X1341540D03*
X1348941D03*
X1343390Y1037622D03*
X1339689Y1044000D03*
X1335989Y1031244D03*
X1347091D03*
X1345241Y1047189D03*
X1343390Y1056756D03*
X1335989D03*
X1341540Y1053567D03*
X1347091Y1056756D03*
X1348941Y1047189D03*
X1345241Y1066323D03*
X1343390Y1075890D03*
X1345241Y1085457D03*
X1343390Y1095024D03*
X1345241Y1104591D03*
X1343390Y1114158D03*
Y1133292D03*
X1345241Y1123725D03*
Y1142858D03*
X1347091Y1158803D03*
X1348941Y1161992D03*
X1345241D03*
X1343390Y1152425D03*
X1335989Y1165181D03*
X1343390Y1158803D03*
X1341540Y1161992D03*
X1338263Y1549970D03*
X1342987D03*
X1347712D03*
X1335113Y1552698D03*
X1339838D03*
X1344562D03*
X1349287D03*
X1338263Y1563608D03*
X1342987D03*
X1347712D03*
X1335113Y1566336D03*
X1339838D03*
X1344562D03*
X1349287D03*
X1358863Y876434D03*
X1355162D03*
X1351461Y882812D03*
X1357012Y886001D03*
X1362563Y895568D03*
X1358863D03*
X1355162Y889190D03*
X1362563Y908324D03*
X1358863D03*
X1355162Y901946D03*
X1364414Y917890D03*
Y924268D03*
X1360713Y917890D03*
Y924268D03*
X1358863Y921079D03*
X1362563D03*
X1355162Y914701D03*
X1364414Y930646D03*
X1360713D03*
X1362563Y940213D03*
X1358863D03*
X1357012Y937024D03*
X1355162Y927457D03*
X1364414Y937024D03*
X1360713D03*
Y956158D03*
Y943402D03*
Y949780D03*
X1364414Y956158D03*
Y943402D03*
Y949780D03*
X1362563Y952969D03*
X1358863D03*
X1355162Y946591D03*
X1360713Y962536D03*
Y968914D03*
X1364414Y962536D03*
Y968914D03*
X1362563Y965725D03*
X1358863D03*
X1355162Y959347D03*
X1360713Y975292D03*
X1364414D03*
X1357012Y981670D03*
X1364414D03*
X1358863Y984859D03*
X1362563Y978481D03*
X1358863D03*
X1355162Y972103D03*
X1357012Y988048D03*
X1358863Y997615D03*
X1357012Y994426D03*
X1358863Y991237D03*
X1364414Y988048D03*
Y994426D03*
X1357012Y1000804D03*
X1364414D03*
X1351461Y991237D03*
X1357012Y1007182D03*
X1358863Y1003993D03*
X1364414Y1007182D03*
X1355162Y1010371D03*
X1362563D03*
X1351461D03*
X1360044Y1028055D03*
X1352642D03*
X1358193Y1031244D03*
X1360044Y1040811D03*
Y1034433D03*
X1358193Y1037622D03*
Y1044000D03*
X1354493D03*
X1363745Y1059945D03*
X1360044D03*
Y1047189D03*
X1358193Y1050378D03*
X1360044Y1053567D03*
X1361894Y1056756D03*
X1358193D03*
X1352642Y1053567D03*
X1361894Y1069512D03*
Y1063134D03*
X1363745Y1072701D03*
X1360044D03*
X1356343Y1066323D03*
X1361894Y1075890D03*
Y1088646D03*
Y1082268D03*
X1363745Y1085457D03*
X1360044D03*
X1356343Y1079079D03*
X1361894Y1095024D03*
X1363745Y1098213D03*
X1360044D03*
X1356343Y1091835D03*
X1358193Y1101402D03*
X1361894D03*
Y1114158D03*
Y1107780D03*
X1363745Y1117347D03*
X1360044D03*
X1356343Y1110969D03*
X1361894Y1120536D03*
X1363745Y1130102D03*
X1360044D03*
X1356343Y1123725D03*
X1360044Y1142858D03*
X1363745D03*
X1356343Y1149236D03*
Y1136480D03*
X1358193Y1152425D03*
X1356343Y1161992D03*
X1360044D03*
X1352436Y1549970D03*
X1357161D03*
X1361885D03*
X1354011Y1552698D03*
X1358735D03*
X1363460D03*
X1352436Y1563608D03*
X1357161D03*
X1361885D03*
X1354011Y1566336D03*
X1358735D03*
X1363460D03*
X1369965Y876434D03*
X1366264D03*
X1377367D03*
X1368115Y879623D03*
X1371815D03*
X1368115Y886001D03*
X1369965Y895568D03*
X1373666D03*
X1366264Y889190D03*
X1377366D03*
X1379216Y886001D03*
X1371815D03*
X1375516D03*
Y911512D03*
X1371815D03*
X1369965Y908324D03*
X1373666D03*
X1375516Y917890D03*
Y924268D03*
X1371815Y917890D03*
Y924268D03*
X1369965Y921079D03*
X1373666D03*
X1375516Y930646D03*
X1371815D03*
X1369965Y940213D03*
X1373666D03*
X1371815Y937024D03*
X1379217D03*
X1368115D03*
X1375516D03*
X1371815Y956158D03*
Y943402D03*
Y949780D03*
X1375516Y956158D03*
Y943402D03*
Y949780D03*
X1369965Y952969D03*
X1373666D03*
X1371815Y962536D03*
Y968914D03*
X1375516Y962536D03*
Y968914D03*
X1369965Y965725D03*
X1373666D03*
X1371815Y975292D03*
X1375516D03*
X1366264Y984859D03*
X1369965Y978481D03*
X1373666D03*
X1371815Y981670D03*
X1379217D03*
X1373666Y984859D03*
Y991237D03*
X1371815Y988048D03*
Y994426D03*
Y1000804D03*
X1366264Y997615D03*
Y991237D03*
X1379217Y988048D03*
Y994426D03*
X1373666Y997615D03*
X1379217Y1000804D03*
X1366264Y1003993D03*
X1379217Y1007182D03*
X1377367Y1010371D03*
X1373666Y1003993D03*
X1369965Y1010371D03*
X1378548Y1028055D03*
X1367445D03*
X1374847Y1040811D03*
X1378548Y1034433D03*
X1372997Y1037622D03*
Y1044000D03*
X1367445Y1040811D03*
Y1034433D03*
X1365595Y1031244D03*
Y1037622D03*
Y1044000D03*
X1372997Y1031244D03*
X1374847Y1047189D03*
Y1053567D03*
X1371146Y1059945D03*
X1372997Y1056756D03*
Y1050378D03*
X1374847Y1059945D03*
X1365595Y1056756D03*
X1367445Y1047189D03*
Y1053567D03*
X1365595Y1050378D03*
X1372997Y1069512D03*
Y1063134D03*
X1365595Y1069512D03*
Y1063134D03*
X1376697Y1069512D03*
Y1063134D03*
X1371146Y1072701D03*
X1374847D03*
X1372997Y1075890D03*
X1365595D03*
X1376697D03*
X1372997Y1088646D03*
Y1082268D03*
X1365595Y1088646D03*
Y1082268D03*
X1376697Y1088646D03*
Y1082268D03*
X1374847Y1085457D03*
X1371146D03*
X1372997Y1095024D03*
X1365595D03*
X1376697D03*
X1374847Y1098213D03*
X1371146D03*
X1372997Y1101402D03*
X1376697D03*
X1369296D03*
X1365595D03*
Y1114158D03*
Y1107780D03*
X1376697Y1114158D03*
Y1107780D03*
X1372997Y1114158D03*
Y1107780D03*
X1374847Y1117347D03*
X1371146D03*
X1365595Y1120536D03*
X1376697D03*
Y1126914D03*
X1372997Y1120536D03*
Y1126914D03*
X1371146Y1130102D03*
X1374847D03*
Y1142858D03*
X1371146D03*
X1378548Y1149236D03*
X1367445D03*
X1369296Y1152425D03*
X1371146Y1161992D03*
X1378548D03*
X1367445D03*
X1371334Y1549970D03*
X1376058D03*
X1366609D03*
X1372909Y1552698D03*
X1377633D03*
X1368184D03*
X1371334Y1563608D03*
X1376058D03*
X1366609D03*
X1372909Y1566336D03*
X1377633D03*
X1368184D03*
X1388469Y876434D03*
X1392170D03*
X1381067D03*
X1390320Y879623D03*
X1394021D03*
X1381067Y895568D03*
X1384768D03*
X1390319Y886001D03*
X1392170Y895568D03*
X1388469Y889190D03*
X1394021Y886001D03*
X1386619Y911512D03*
X1394020D03*
X1382918D03*
X1384768Y908324D03*
X1392170D03*
X1381067Y908323D03*
X1386619Y924268D03*
Y917890D03*
X1394020Y924268D03*
Y917890D03*
X1382918Y924268D03*
Y917890D03*
X1384768Y921079D03*
X1381067D03*
X1392170D03*
X1394020Y937024D03*
X1382918Y930646D03*
X1386619D03*
X1384768Y940213D03*
X1381067D03*
X1394020Y930646D03*
X1392170Y940213D03*
X1381067Y933835D03*
X1386619Y937024D03*
X1384768Y933835D03*
X1382918Y937024D03*
X1394020Y956158D03*
Y943402D03*
Y949780D03*
X1382918Y956158D03*
Y943402D03*
Y949780D03*
X1386619Y956158D03*
Y943402D03*
Y949780D03*
X1384768Y952969D03*
X1381067D03*
X1392170D03*
X1394020Y962536D03*
Y968914D03*
X1382918Y962536D03*
Y968914D03*
X1386619Y962536D03*
Y968914D03*
X1384768Y965725D03*
X1381067D03*
X1392170D03*
X1394020Y975292D03*
X1382918D03*
X1386619D03*
X1381067Y978481D03*
X1384768D03*
X1386619Y981670D03*
X1381067Y984859D03*
X1392170Y978481D03*
X1394020Y981670D03*
X1388469Y984859D03*
X1386619Y988048D03*
X1394020D03*
X1381067Y991237D03*
X1388457Y997607D03*
X1388469Y991237D03*
X1382905Y1007174D03*
X1382236Y1028063D03*
X1380398Y1044000D03*
X1382246Y1040819D03*
X1389638D03*
X1382236Y1034441D03*
X1380398Y1037622D03*
Y1031244D03*
X1382249Y1047189D03*
X1389650D03*
X1380398Y1050378D03*
X1382249Y1059945D03*
Y1053567D03*
X1385949Y1059945D03*
X1380398Y1056756D03*
X1387800D03*
X1393351Y1059945D03*
X1387800Y1050378D03*
X1389650Y1053567D03*
X1384099Y1069512D03*
Y1063134D03*
X1387800Y1069512D03*
Y1063134D03*
X1382249Y1072701D03*
X1385949D03*
X1393351D03*
X1384099Y1075890D03*
X1387800D03*
X1384099Y1088646D03*
Y1082268D03*
X1387800Y1088646D03*
Y1082268D03*
X1382249Y1085457D03*
X1385949D03*
X1393351D03*
X1384099Y1095024D03*
X1387800D03*
X1382249Y1098213D03*
X1385949D03*
X1393351D03*
X1385949Y1104591D03*
X1384099Y1101402D03*
X1380398D03*
X1382249Y1104591D03*
X1387800Y1101402D03*
Y1114158D03*
X1384099D03*
Y1107780D03*
X1382249Y1117347D03*
X1385949D03*
X1387800Y1107780D03*
X1393351Y1117347D03*
X1387800Y1120536D03*
Y1126914D03*
X1384099Y1120536D03*
Y1126914D03*
X1385949Y1130102D03*
X1382249D03*
X1393351D03*
X1382249Y1142858D03*
X1385949D03*
X1393351D03*
X1389650Y1149236D03*
X1380398Y1152425D03*
X1382249Y1161992D03*
X1391500Y1152425D03*
X1393351Y1161992D03*
X1389650D03*
X1380783Y1549970D03*
X1385507D03*
X1390232D03*
X1382357Y1552698D03*
X1387082D03*
X1391806D03*
X1380783Y1563608D03*
X1385507D03*
X1390232D03*
X1382357Y1566336D03*
X1387082D03*
X1391806D03*
X1399571Y876434D03*
X1403272D03*
X1405123Y879623D03*
X1401423D03*
X1401422Y886001D03*
X1395871Y895568D03*
X1399571Y889190D03*
X1408823Y892379D03*
X1405123D03*
X1397722Y886001D03*
X1408824D03*
X1405123D03*
X1397721Y911512D03*
X1395871Y908324D03*
X1408823Y911512D03*
X1405123D03*
X1408823Y898757D03*
X1405123D03*
X1406973Y921079D03*
Y914701D03*
X1397721Y924268D03*
Y917890D03*
X1403272Y921079D03*
Y914701D03*
X1395871Y921079D03*
X1408823Y924268D03*
X1405123D03*
X1403272Y940213D03*
X1406973D03*
X1397721Y937024D03*
X1406973Y927457D03*
X1403272D03*
X1397721Y930646D03*
X1395871Y940213D03*
X1406973Y933835D03*
X1403272D03*
Y952969D03*
Y946591D03*
X1406973Y952969D03*
Y946591D03*
X1397721Y956158D03*
Y943402D03*
Y949780D03*
X1395871Y952969D03*
X1405123Y943402D03*
X1408823D03*
X1405123Y956158D03*
X1408823D03*
X1403272Y959347D03*
Y965725D03*
X1406973Y959347D03*
Y965725D03*
X1397721Y962536D03*
Y968914D03*
X1405123D03*
X1395871Y965725D03*
X1408823Y968914D03*
X1403272Y978481D03*
Y972103D03*
X1406973Y978481D03*
Y972103D03*
X1397721Y975292D03*
X1395871Y978481D03*
X1401422Y981670D03*
X1395871Y984859D03*
X1408823Y981670D03*
X1403272Y984859D03*
X1401422Y988048D03*
X1395858Y997607D03*
X1395871Y991237D03*
X1403260Y997607D03*
X1408823Y988048D03*
X1403272Y991237D03*
X1397039Y1040819D03*
X1404441D03*
X1404453Y1059945D03*
X1408154D03*
X1397052Y1047189D03*
X1404453D03*
X1395201Y1050378D03*
X1402603Y1056756D03*
Y1050378D03*
X1395201Y1056756D03*
X1397052Y1059945D03*
Y1053567D03*
X1404453D03*
X1395201Y1063134D03*
X1404453Y1072701D03*
Y1066323D03*
X1395201Y1069512D03*
X1398902Y1063134D03*
X1408154Y1072701D03*
Y1066323D03*
X1398902Y1069512D03*
X1406304D03*
X1397052Y1072701D03*
X1395201Y1075890D03*
X1404453Y1079079D03*
X1398902Y1075890D03*
X1408154Y1079079D03*
X1395201Y1082268D03*
X1404453Y1085457D03*
X1395201Y1088646D03*
X1398902Y1082268D03*
X1408154Y1085457D03*
X1398902Y1088646D03*
X1397052Y1085457D03*
X1406304Y1082268D03*
X1395201Y1095024D03*
Y1101402D03*
X1404453Y1098213D03*
Y1091835D03*
X1398902Y1095024D03*
Y1101402D03*
X1408154Y1098213D03*
Y1091835D03*
X1397052Y1098213D03*
X1406304Y1095024D03*
X1408154Y1104591D03*
X1404453D03*
X1398902Y1114158D03*
X1408154Y1117347D03*
Y1110969D03*
X1395201Y1114158D03*
X1404453Y1117347D03*
Y1110969D03*
X1398902Y1107780D03*
X1395201D03*
X1397052Y1117347D03*
X1406304Y1114158D03*
X1398902Y1120536D03*
Y1126914D03*
X1408154Y1123725D03*
X1395201Y1120536D03*
Y1126914D03*
X1404453Y1123725D03*
X1397052Y1130102D03*
X1406304Y1126914D03*
X1397052Y1142858D03*
X1400752Y1149236D03*
X1406304Y1139669D03*
Y1146047D03*
X1402603Y1152425D03*
X1400752Y1161992D03*
X1406304Y1152425D03*
X1404453Y1161992D03*
X1408154Y1155614D03*
X1394956Y1549970D03*
X1396531Y1552698D03*
X1399256Y1540355D03*
X1401356D03*
X1402763Y1547073D03*
X1402707Y1549336D03*
X1394956Y1563608D03*
X1396531Y1566336D03*
X1403058Y1567540D03*
X1403059Y1564618D03*
X1402970Y1561698D03*
X1402473Y1571658D03*
X1423602Y892379D03*
Y911512D03*
Y898757D03*
Y924268D03*
Y943402D03*
Y956158D03*
Y968914D03*
X1410674Y984859D03*
X1410661Y997607D03*
X1410674Y991237D03*
X1411855Y1047189D03*
X1410004Y1050378D03*
X1411855Y1053567D03*
X1410004Y1056756D03*
Y1069512D03*
Y1082268D03*
Y1095024D03*
Y1114158D03*
Y1126914D03*
Y1139669D03*
Y1146047D03*
Y1152425D03*
Y1158803D03*
X1438405Y879623D03*
X1431003Y873245D03*
X1434704Y879623D03*
Y873245D03*
X1438405D03*
X1429153Y876434D03*
X1432854D03*
X1436554Y882812D03*
X1431003Y886001D03*
X1427302D03*
Y892379D03*
X1432854Y889190D03*
X1436554Y895568D03*
X1438405Y886001D03*
X1427302Y911512D03*
X1436554Y908324D03*
X1427302Y898757D03*
Y924268D03*
X1436554Y921079D03*
X1438405Y937024D03*
X1429153Y940213D03*
X1434704Y937024D03*
X1425452Y940213D03*
X1429153Y933835D03*
X1425452D03*
X1434704Y930646D03*
X1438405D03*
X1436554Y940213D03*
X1438405Y943402D03*
Y956158D03*
X1429153Y946591D03*
Y952969D03*
X1438405Y949780D03*
X1434704Y943402D03*
Y956158D03*
X1425452Y946591D03*
Y952969D03*
X1434704Y949780D03*
X1427302Y943402D03*
Y956158D03*
X1436554Y952969D03*
X1438405Y962536D03*
X1429153Y965725D03*
Y959347D03*
X1438405Y968914D03*
X1434704Y962536D03*
X1425452Y965725D03*
Y959347D03*
X1434704Y968914D03*
X1427302D03*
X1436554Y965725D03*
X1438405Y975292D03*
X1429153Y972103D03*
Y978481D03*
X1434704Y975292D03*
X1425452Y972103D03*
Y978481D03*
X1427302Y981670D03*
X1434704D03*
X1425452Y984859D03*
X1432854D03*
X1436554Y978481D03*
X1434704Y988048D03*
X1425465Y997607D03*
X1432866D03*
X1427302Y988048D03*
X1425452Y991237D03*
X1432854D03*
X1434047Y1040819D03*
X1430334Y1059945D03*
X1426633D03*
X1434035Y1047189D03*
X1426633D03*
X1435885Y1050378D03*
X1428483D03*
X1437735Y1059945D03*
X1435885Y1056756D03*
X1428483D03*
X1426633Y1053567D03*
X1434035D03*
X1430334Y1066323D03*
Y1072701D03*
X1426633Y1066323D03*
Y1072701D03*
X1435885Y1063134D03*
Y1069512D03*
X1428483D03*
X1424783D03*
X1437735Y1072701D03*
X1430334Y1079079D03*
X1426633D03*
X1435885Y1075890D03*
Y1088646D03*
X1428483Y1082268D03*
X1424783D03*
X1437735Y1085457D03*
X1430334D03*
X1426633D03*
X1435885Y1082268D03*
Y1101402D03*
Y1095024D03*
X1428483D03*
X1424783D03*
X1430334Y1104591D03*
X1426633D03*
X1437735Y1098213D03*
X1430334Y1091835D03*
Y1098213D03*
X1426633Y1091835D03*
Y1098213D03*
Y1110969D03*
Y1117347D03*
X1435885Y1114158D03*
X1430334Y1110969D03*
Y1117347D03*
X1428483Y1114158D03*
X1424783D03*
X1435885Y1107780D03*
X1437735Y1117347D03*
X1426633Y1123725D03*
X1435885Y1126914D03*
Y1120536D03*
X1430334Y1123725D03*
X1424783Y1126914D03*
X1428483D03*
X1437735Y1130102D03*
X1428483Y1139669D03*
X1424783D03*
X1434035Y1149236D03*
X1428483Y1146047D03*
X1424783D03*
X1437735Y1142858D03*
X1426633Y1161992D03*
X1424783Y1152425D03*
X1426633Y1155614D03*
X1428483Y1152425D03*
X1432184D03*
X1434035Y1161992D03*
X1430334D03*
X1424783Y1158803D03*
X1432184D03*
X1434035Y1155614D03*
X1428484Y1158803D03*
X1437735Y1155614D03*
X1443956Y876434D03*
X1440255D03*
X1451358D03*
X1449507Y873245D03*
X1453208D03*
X1440255Y882812D03*
X1442106Y886001D03*
X1443956Y889190D03*
X1447657Y895568D03*
X1440255D03*
X1453208Y886001D03*
X1451358Y895568D03*
X1447657Y908324D03*
X1440255D03*
X1451357D03*
X1447657Y921079D03*
X1440255D03*
X1451357D03*
X1445806Y930646D03*
X1449507D03*
X1447657Y940213D03*
X1440255D03*
X1451357D03*
X1442106Y930646D03*
X1453208Y937024D03*
X1445806D03*
X1451357Y933835D03*
X1447657D03*
X1449507Y937024D03*
Y949780D03*
Y943402D03*
Y956158D03*
X1445806Y949780D03*
Y943402D03*
Y956158D03*
X1447657Y952969D03*
X1440255D03*
X1451357D03*
X1449507Y968914D03*
Y962536D03*
X1445806Y968914D03*
Y962536D03*
X1440255Y965725D03*
X1447657D03*
X1451357D03*
X1449507Y975292D03*
X1445806D03*
X1440255Y978481D03*
X1447657D03*
X1442106Y981670D03*
X1449507D03*
X1447657Y984859D03*
X1440255D03*
X1451357Y978481D03*
X1449507Y988048D03*
X1440268Y997607D03*
X1447669D03*
X1442106Y988048D03*
X1440255Y991237D03*
X1447657D03*
X1441449Y1040819D03*
X1448850D03*
X1441436Y1047189D03*
X1448838D03*
X1450688Y1050378D03*
Y1056756D03*
X1441436Y1059945D03*
Y1053567D03*
X1443287Y1056756D03*
X1448838Y1053567D03*
X1443287Y1050378D03*
X1448838Y1059945D03*
X1452539D03*
X1439586Y1063134D03*
Y1069512D03*
X1450688Y1063134D03*
Y1069512D03*
X1446987Y1063134D03*
Y1069512D03*
X1441436Y1072701D03*
X1448838D03*
X1452539D03*
X1439586Y1075890D03*
X1450688D03*
X1446987D03*
X1439586Y1088646D03*
X1450688Y1082268D03*
X1446987D03*
X1448838Y1085457D03*
X1441436D03*
X1452539D03*
X1439586Y1082268D03*
X1450688Y1088646D03*
X1446987D03*
X1439586Y1101402D03*
Y1095024D03*
X1448838Y1098213D03*
X1441436D03*
X1452539D03*
X1448838Y1104591D03*
X1452539D03*
X1446987Y1101402D03*
X1450688D03*
Y1095024D03*
X1446987D03*
Y1114158D03*
X1439586D03*
X1450688D03*
Y1107780D03*
X1446987D03*
X1439586D03*
X1448838Y1117347D03*
X1441436D03*
X1452539D03*
X1446987Y1126914D03*
Y1120536D03*
X1439586Y1126914D03*
Y1120536D03*
X1450688Y1126914D03*
Y1120536D03*
X1448838Y1130102D03*
X1441436D03*
X1452539Y1130103D03*
X1448838Y1142858D03*
X1441436D03*
X1445137Y1149236D03*
X1452539Y1142858D03*
X1446987Y1152425D03*
X1443287Y1165181D03*
X1439586Y1158803D03*
X1443287Y1152425D03*
X1452539Y1161992D03*
X1441436D03*
X1445137D03*
X1448838Y1155614D03*
X1439586Y1152425D03*
X1445137Y1155614D03*
X1443287Y1158803D03*
X1450627Y1540509D03*
X1452827D03*
X1450792Y1546218D03*
X1449133Y1551121D03*
X1449534Y1554612D03*
X1449580Y1568698D03*
Y1570898D03*
X1451027Y1573317D03*
X1462460Y876434D03*
X1455058D03*
X1466161D03*
X1464310Y873245D03*
X1460609D03*
Y879623D03*
X1464310D03*
Y886001D03*
X1458759Y895568D03*
X1462460D03*
X1466161Y889190D03*
X1455058D03*
X1460609Y886001D03*
X1456909D03*
X1468011D03*
X1458759Y908324D03*
X1462460D03*
X1458759Y921079D03*
X1462460D03*
Y940213D03*
X1458759D03*
X1456909Y937024D03*
X1464310D03*
X1460609D03*
X1468011D03*
X1460609Y949780D03*
Y943402D03*
Y956158D03*
X1468011Y949780D03*
Y943402D03*
Y956158D03*
X1456909Y949780D03*
Y943402D03*
Y956158D03*
X1458759Y952969D03*
X1462460D03*
X1460609Y968914D03*
Y962536D03*
X1468011Y968914D03*
Y962536D03*
X1456909Y968914D03*
Y962536D03*
X1462460Y965725D03*
X1458759D03*
X1460609Y975292D03*
X1468011D03*
X1456909D03*
X1462460Y978481D03*
X1458759D03*
X1464310Y981670D03*
X1456909D03*
X1462460Y984859D03*
X1455058D03*
X1464310Y988048D03*
Y994426D03*
X1456909Y988048D03*
Y994426D03*
X1462460Y997615D03*
Y991237D03*
X1455058Y997615D03*
Y991237D03*
X1456909Y1000804D03*
X1464310D03*
Y1007182D03*
X1456909D03*
X1462460Y1010371D03*
Y1003993D03*
X1455058Y1010371D03*
Y1003993D03*
X1459940Y1028055D03*
X1467342D03*
X1458090Y1037622D03*
Y1044000D03*
X1465491Y1037622D03*
Y1044000D03*
X1463641Y1040811D03*
X1456239D03*
X1459940Y1034433D03*
X1461791Y1031244D03*
X1454389D03*
X1467342Y1034433D03*
X1463641Y1047189D03*
X1456239D03*
X1465491Y1050378D03*
X1456239Y1053567D03*
X1463641D03*
X1458090Y1056756D03*
X1463641Y1059945D03*
X1465491Y1056756D03*
X1458090Y1050378D03*
X1459940Y1059945D03*
X1461791Y1063134D03*
Y1069512D03*
X1458090Y1063134D03*
Y1069512D03*
X1463641Y1072701D03*
X1459940D03*
X1461791Y1075890D03*
X1458090D03*
X1463641Y1085457D03*
X1459940D03*
X1461791Y1082268D03*
Y1088646D03*
X1458090Y1082268D03*
Y1088646D03*
X1463641Y1098213D03*
X1459940D03*
X1454389Y1101402D03*
X1461791D03*
X1458090D03*
X1465491D03*
X1461791Y1095024D03*
X1458090D03*
Y1114158D03*
Y1107780D03*
X1461791Y1114158D03*
Y1107780D03*
X1459940Y1117347D03*
X1463641D03*
X1458090Y1126914D03*
Y1120536D03*
X1461791Y1126914D03*
Y1120536D03*
X1459940Y1130102D03*
X1463641D03*
Y1142858D03*
X1459940D03*
X1456239Y1149236D03*
X1467342D03*
X1454389Y1158803D03*
X1467342Y1155614D03*
X1465491Y1158803D03*
X1459940Y1155614D03*
X1465491Y1152425D03*
X1454389D03*
X1467342Y1161992D03*
X1463641D03*
X1456239D03*
X1461791Y1165181D03*
X1458090Y1152425D03*
X1461791Y1158803D03*
X1456239Y1155614D03*
X1460202Y1563608D03*
X1464926D03*
X1461777Y1566336D03*
X1466501D03*
X1455098Y1577625D03*
X1475413Y879623D03*
X1482814D03*
X1473562Y876434D03*
X1477263D03*
X1471712Y873245D03*
X1475413D03*
X1480964Y876434D03*
X1475413Y886001D03*
X1477263Y889190D03*
X1473562Y895568D03*
X1469861D03*
X1471712Y886001D03*
X1469861Y908324D03*
X1473562D03*
X1477263Y901946D03*
X1473562Y921079D03*
X1469861D03*
X1477263Y914701D03*
X1469861Y940213D03*
X1473562D03*
X1477263Y927457D03*
X1475413Y937024D03*
X1471712D03*
Y949780D03*
Y943402D03*
Y956158D03*
X1473562Y952969D03*
X1469861D03*
X1477263Y946591D03*
X1471712Y968914D03*
Y962536D03*
X1473562Y965725D03*
X1469861D03*
X1477263Y959347D03*
X1471712Y975292D03*
Y981670D03*
X1473562Y978481D03*
X1469861D03*
Y984859D03*
X1477263Y972103D03*
Y984859D03*
Y991237D03*
X1469861Y997615D03*
Y991237D03*
X1471712Y988048D03*
Y994426D03*
X1477263Y997615D03*
X1471712Y1000804D03*
X1479113Y994426D03*
X1471712Y1007182D03*
X1477263Y1010371D03*
Y1003993D03*
X1469861Y1010371D03*
Y1003993D03*
X1480964Y1010371D03*
X1474743Y1028055D03*
X1482145D03*
X1478444Y1040811D03*
X1471043D03*
X1472893Y1037622D03*
Y1044000D03*
X1474743Y1034433D03*
X1476594Y1031244D03*
X1469192D03*
X1472893Y1050378D03*
X1478444Y1047189D03*
X1471043D03*
X1478444Y1053567D03*
X1472893Y1056756D03*
X1471043Y1053567D03*
X1474743Y1059945D03*
X1471043D03*
X1482145Y1053567D03*
X1472893Y1063134D03*
Y1069512D03*
X1469192Y1063134D03*
Y1069512D03*
X1478444Y1066323D03*
X1471043Y1072701D03*
X1474743D03*
X1472893Y1075890D03*
X1469192D03*
X1478444Y1079079D03*
X1474743Y1085457D03*
X1471043D03*
X1472893Y1082268D03*
Y1088646D03*
X1469192Y1082268D03*
Y1088646D03*
X1478444Y1091835D03*
X1476594Y1101402D03*
X1474743Y1098213D03*
X1471043D03*
X1469192Y1101402D03*
X1472893Y1095024D03*
X1469192D03*
Y1107780D03*
Y1114158D03*
X1472893Y1107780D03*
Y1114158D03*
X1478444Y1110969D03*
X1474743Y1117347D03*
X1471043D03*
X1469192Y1120536D03*
X1472893D03*
X1478444Y1123725D03*
X1474743Y1130102D03*
X1471043D03*
X1478444Y1136480D03*
X1474743Y1142858D03*
X1471043D03*
X1478444Y1149236D03*
X1472893Y1158803D03*
X1471043Y1155614D03*
Y1161992D03*
X1469192Y1152425D03*
X1476594D03*
X1478444Y1161992D03*
X1474743D03*
X1476594Y1158803D03*
X1476778Y1165778D03*
X1469651Y1563608D03*
X1474375D03*
X1479099D03*
X1483824D03*
X1471225Y1566336D03*
X1475950D03*
X1480674D03*
X1486515Y879623D03*
X1490216D03*
X1484665Y876434D03*
X1488365D03*
Y895568D03*
X1492066Y882812D03*
X1490216Y905134D03*
X1488365Y914701D03*
X1490216Y924268D03*
X1488365Y933835D03*
X1490216Y943402D03*
X1488365Y952969D03*
X1490216Y962536D03*
Y981670D03*
X1488365Y972103D03*
Y991237D03*
X1490216Y1000804D03*
X1493917Y994426D03*
X1484665Y991237D03*
X1488365Y1010371D03*
X1492066D03*
X1493247Y1028055D03*
X1485846D03*
X1491397Y1037622D03*
X1498798Y1044000D03*
Y1031244D03*
X1487696Y1044000D03*
Y1031244D03*
X1489547Y1047189D03*
X1491397Y1056756D03*
X1498798D03*
X1493247Y1053567D03*
X1487696Y1056756D03*
X1485846Y1047189D03*
X1489547Y1066323D03*
X1491397Y1075890D03*
X1489547Y1085457D03*
X1491397Y1095024D03*
X1489547Y1104591D03*
X1491397Y1114158D03*
Y1133292D03*
X1489547Y1123725D03*
Y1142858D03*
X1491397Y1152425D03*
X1489547Y1161992D03*
X1485846D03*
X1487696Y1158803D03*
X1488548Y1563608D03*
X1493273D03*
X1497997D03*
X1485399Y1566336D03*
X1490123D03*
X1494847D03*
X1506869Y876434D03*
X1512421Y879623D03*
X1505019D03*
X1512421Y886001D03*
X1506869Y889190D03*
X1510570D03*
X1505019Y892379D03*
X1510570Y895568D03*
X1506869D03*
X1512421Y892379D03*
X1506869Y882812D03*
X1510570Y908324D03*
X1505019Y911512D03*
X1512421Y898757D03*
X1506869Y901946D03*
X1510570D03*
X1505019Y905134D03*
X1512421D03*
X1506869Y908324D03*
X1512421Y911512D03*
X1505019Y898757D03*
X1512421Y917890D03*
X1506869Y921079D03*
X1510570D03*
X1505019Y924268D03*
X1512421D03*
X1510570Y914701D03*
X1506869D03*
X1505019Y917890D03*
X1506869Y927457D03*
X1510570D03*
X1505019Y930646D03*
X1512421Y937024D03*
X1506869Y940213D03*
X1510570D03*
Y933835D03*
X1506869D03*
X1512421Y930646D03*
X1505019Y937024D03*
Y943402D03*
X1512421D03*
X1506869Y946591D03*
X1510570D03*
X1505019Y949780D03*
X1512421Y956158D03*
X1510570Y952969D03*
X1506869D03*
X1512421Y949780D03*
X1505019Y956158D03*
X1512421Y962536D03*
X1506869Y965725D03*
X1510570D03*
X1505019Y968914D03*
X1506869Y959347D03*
X1510570D03*
X1505019Y962536D03*
X1512421Y968914D03*
X1506869Y984859D03*
X1512421Y975292D03*
X1506869Y978481D03*
X1510570D03*
X1505019Y981670D03*
X1510570Y972103D03*
X1506869D03*
X1505019Y975292D03*
Y988048D03*
X1512421Y994426D03*
X1510570Y997615D03*
X1506869D03*
X1505019Y1000804D03*
X1512421D03*
Y988048D03*
X1506869Y991237D03*
X1499468D03*
X1505019Y994426D03*
X1510570Y991237D03*
Y1010371D03*
X1512421Y1007182D03*
X1510570Y1003993D03*
X1506869D03*
X1505019Y1007182D03*
X1506869Y1010371D03*
X1508050Y1028055D03*
X1500649D03*
X1511751D03*
X1506200Y1031244D03*
X1508050Y1034433D03*
X1511751D03*
X1513602Y1037622D03*
X1506200D03*
X1508050Y1040811D03*
X1511751D03*
X1506200Y1044000D03*
X1513602D03*
Y1031244D03*
X1506200Y1050378D03*
X1511751Y1059945D03*
X1508050Y1047189D03*
X1513602Y1050378D03*
X1511751Y1053567D03*
X1500649Y1047189D03*
X1513602Y1056756D03*
X1511751Y1047189D03*
X1508050Y1053567D03*
X1511751Y1072701D03*
X1506200Y1063134D03*
X1513602D03*
X1508050Y1066323D03*
X1506200Y1069512D03*
X1513602D03*
X1508050Y1072701D03*
X1511751Y1066323D03*
X1506200Y1075890D03*
X1513602D03*
X1508050Y1079079D03*
X1511751D03*
X1506200Y1082268D03*
X1513602D03*
X1508050Y1085457D03*
X1513602Y1088646D03*
X1506200D03*
X1511751Y1085457D03*
X1513602Y1101402D03*
X1508050Y1104591D03*
X1511751Y1091835D03*
X1506200Y1095024D03*
X1513602D03*
X1508050Y1098213D03*
X1511751D03*
X1506200Y1101402D03*
X1511751Y1104591D03*
X1508050Y1091835D03*
X1511751Y1110969D03*
X1506200Y1114158D03*
X1513602D03*
X1508050Y1117347D03*
X1511751D03*
X1513602Y1107780D03*
X1506200D03*
X1508050Y1110969D03*
X1506200Y1120536D03*
X1513602D03*
X1508050Y1123725D03*
X1511751Y1130102D03*
X1506200Y1133292D03*
X1513602D03*
Y1126914D03*
X1506200D03*
X1511751Y1123725D03*
X1508050Y1130102D03*
Y1136480D03*
X1511751D03*
X1506200Y1139669D03*
X1513602D03*
X1508050Y1142858D03*
X1511751Y1149236D03*
X1513602Y1146047D03*
X1506200D03*
X1511751Y1142858D03*
X1508050Y1149236D03*
X1506200Y1152425D03*
X1513602D03*
X1508050Y1155614D03*
X1513602Y1158803D03*
X1500649Y1161992D03*
X1504350D03*
X1507446Y1563608D03*
X1512170D03*
X1502721D03*
X1509021Y1566336D03*
X1513745D03*
X1499572D03*
X1504296D03*
X1527224Y873245D03*
X1516121D03*
X1519822D03*
X1514271Y876434D03*
X1523523Y879623D03*
X1525373Y876434D03*
X1523523Y886001D03*
X1517972Y889190D03*
X1525373D03*
X1519822Y892379D03*
X1525373Y895568D03*
X1517972D03*
X1523523Y892379D03*
X1516121Y886001D03*
X1514271Y895568D03*
X1525373Y908324D03*
X1519822Y911512D03*
X1523523Y898757D03*
X1517972Y901946D03*
X1525373D03*
X1519822Y905134D03*
X1523523D03*
X1517972Y908324D03*
X1523523Y911512D03*
X1519822Y898757D03*
X1516121Y905134D03*
X1523523Y917890D03*
X1517972Y921079D03*
X1525373D03*
X1519822Y924268D03*
X1523523D03*
X1525373Y914701D03*
X1517972D03*
X1519822Y917890D03*
X1516121Y924268D03*
X1514271Y914701D03*
X1517972Y927457D03*
X1525373D03*
X1519822Y930646D03*
X1523523Y937024D03*
X1517972Y940213D03*
X1525373D03*
Y933835D03*
X1517972D03*
X1523523Y930646D03*
X1519822Y937024D03*
X1514271Y933835D03*
X1519822Y943402D03*
X1523523D03*
X1517972Y946591D03*
X1525373D03*
X1519822Y949780D03*
X1523523Y956158D03*
X1525373Y952969D03*
X1517972D03*
X1523523Y949780D03*
X1519822Y956158D03*
X1516121Y943402D03*
X1514271Y952969D03*
X1523523Y962536D03*
X1517972Y965725D03*
X1525373D03*
X1519822Y968914D03*
X1517972Y959347D03*
X1525373D03*
X1519822Y962536D03*
X1523523Y968914D03*
X1516121Y962536D03*
X1517972Y984859D03*
X1523523Y975292D03*
X1517972Y978481D03*
X1525373D03*
X1519822Y981670D03*
X1525373Y972103D03*
X1517972D03*
X1519822Y975292D03*
X1516121Y981670D03*
X1514271Y972103D03*
X1519822Y988048D03*
X1523523Y994426D03*
X1525373Y997615D03*
X1517972D03*
X1519822Y1000804D03*
X1523523D03*
Y988048D03*
X1517972Y991237D03*
X1516121Y1000804D03*
X1514271Y991237D03*
X1519822Y994426D03*
X1525373Y991237D03*
Y1010371D03*
X1523523Y1007182D03*
X1525373Y1003993D03*
X1517972D03*
X1519822Y1007182D03*
X1514271Y1010371D03*
X1517972D03*
X1519153Y1028055D03*
X1526554D03*
X1521003Y1031244D03*
X1519153Y1034433D03*
X1526554D03*
X1524704Y1037622D03*
X1521003D03*
X1519153Y1040811D03*
X1526554D03*
X1521003Y1044000D03*
X1517302Y1037622D03*
X1524704Y1044000D03*
Y1031244D03*
X1521003Y1050378D03*
X1526554Y1059945D03*
X1519153Y1047189D03*
X1524704Y1050378D03*
X1526554Y1053567D03*
X1517302Y1056756D03*
X1515452Y1047189D03*
X1524704Y1056756D03*
X1526554Y1047189D03*
X1519153Y1053567D03*
X1526554Y1072701D03*
X1521003Y1063134D03*
X1524704D03*
X1519153Y1066323D03*
X1521003Y1069512D03*
X1524704D03*
X1519153Y1072701D03*
X1526554Y1066323D03*
X1515452D03*
X1521003Y1075890D03*
X1524704D03*
X1519153Y1079079D03*
X1526554D03*
X1521003Y1082268D03*
X1524704D03*
X1519153Y1085457D03*
X1524704Y1088646D03*
X1521003D03*
X1526554Y1085457D03*
X1515452D03*
X1517302Y1075890D03*
X1524704Y1101402D03*
X1519153Y1104591D03*
X1526554Y1091835D03*
X1521003Y1095024D03*
X1524704D03*
X1519153Y1098213D03*
X1526554D03*
X1521003Y1101402D03*
X1526554Y1104591D03*
X1519153Y1091835D03*
X1515452Y1104591D03*
X1517302Y1095024D03*
X1526554Y1110969D03*
X1521003Y1114158D03*
X1524704D03*
X1519153Y1117347D03*
X1526554D03*
X1524704Y1107780D03*
X1521003D03*
X1519153Y1110969D03*
X1517302Y1114158D03*
X1521003Y1120536D03*
X1524704D03*
X1519153Y1123725D03*
X1526554Y1130102D03*
X1521003Y1133292D03*
X1524704D03*
Y1126914D03*
X1521003D03*
X1526554Y1123725D03*
X1519153Y1130102D03*
X1517302Y1133292D03*
X1515452Y1123725D03*
X1519153Y1136480D03*
X1526554D03*
X1521003Y1139669D03*
X1524704D03*
X1519153Y1142858D03*
X1526554Y1149236D03*
X1524704Y1146047D03*
X1521003D03*
X1526554Y1142858D03*
X1519153Y1149236D03*
X1515452Y1142858D03*
X1521003Y1152425D03*
X1524704D03*
X1526554Y1155614D03*
X1517302Y1152425D03*
X1521003Y1158803D03*
X1515452Y1161992D03*
X1516895Y1563608D03*
X1521619D03*
X1526344D03*
X1518469Y1566336D03*
X1523194D03*
X1527918D03*
X1542027Y879623D03*
X1540176Y876434D03*
X1530924Y873245D03*
X1534625Y879623D03*
X1536476Y876434D03*
X1538326Y886001D03*
X1532775Y889190D03*
X1536476D03*
X1530925Y892379D03*
X1536476Y895568D03*
X1532775D03*
X1538326Y892379D03*
X1540176Y895568D03*
X1542027Y886001D03*
X1532775Y882812D03*
X1536476Y908324D03*
X1530925Y911512D03*
X1538326Y898757D03*
X1532775Y901946D03*
X1536476D03*
X1530925Y905134D03*
X1538326D03*
X1532775Y908324D03*
X1538326Y911512D03*
X1530925Y898757D03*
X1542027Y905134D03*
X1538326Y917890D03*
X1532775Y921079D03*
X1536476D03*
X1530925Y924268D03*
X1538326D03*
X1536476Y914701D03*
X1532775D03*
X1530925Y917890D03*
X1542027Y924268D03*
X1540176Y914701D03*
X1532775Y927457D03*
X1536476D03*
X1530925Y930646D03*
X1538326Y937024D03*
X1532775Y940213D03*
X1536476D03*
Y933835D03*
X1532775D03*
X1538326Y930646D03*
X1530925Y937024D03*
X1540176Y933835D03*
X1530925Y943402D03*
X1538326D03*
X1532775Y946591D03*
X1536476D03*
X1530925Y949780D03*
X1538326Y956158D03*
X1536476Y952969D03*
X1532775D03*
X1538326Y949780D03*
X1530925Y956158D03*
X1540176Y952969D03*
X1542027Y943402D03*
X1538326Y962536D03*
X1532775Y965725D03*
X1536476D03*
X1530925Y968914D03*
X1532775Y959347D03*
X1536476D03*
X1530925Y962536D03*
X1538326Y968914D03*
X1542027Y962536D03*
X1532775Y984859D03*
X1538326Y975292D03*
X1532775Y978481D03*
X1536476D03*
X1530925Y981670D03*
X1536476Y972103D03*
X1532775D03*
X1530925Y975292D03*
X1542027Y981670D03*
X1540176Y972103D03*
X1530925Y988048D03*
X1538326Y994426D03*
X1536476Y997615D03*
X1532775D03*
X1530925Y1000804D03*
X1538326D03*
Y988048D03*
X1532775Y991237D03*
X1542027Y1000804D03*
X1540176Y991237D03*
X1530924Y994426D03*
X1536476Y991237D03*
Y1010371D03*
X1538326Y1007182D03*
X1536476Y1003993D03*
X1532775D03*
X1530925Y1007182D03*
X1540176Y1010371D03*
X1532775D03*
X1533956Y1028055D03*
X1537657D03*
X1532106Y1031244D03*
X1533956Y1034433D03*
X1537657D03*
X1539507Y1037622D03*
X1532106D03*
X1533956Y1040811D03*
X1537657D03*
X1532106Y1044000D03*
X1543208Y1037622D03*
X1539507Y1044000D03*
Y1031244D03*
X1532106Y1050378D03*
X1537657Y1059945D03*
X1533956Y1047189D03*
X1539507Y1050378D03*
X1537657Y1053567D03*
X1543208Y1056756D03*
X1541357Y1047189D03*
X1539507Y1056756D03*
X1537657Y1047189D03*
X1533956Y1053567D03*
X1537657Y1072701D03*
X1532106Y1063134D03*
X1539507D03*
X1533956Y1066323D03*
X1532106Y1069512D03*
X1539507D03*
X1533956Y1072701D03*
X1537657Y1066323D03*
X1541357D03*
X1532106Y1075890D03*
X1539507D03*
X1533956Y1079079D03*
X1537657D03*
X1532106Y1082268D03*
X1539507D03*
X1533956Y1085457D03*
X1539507Y1088646D03*
X1532106D03*
X1537657Y1085457D03*
X1541357D03*
X1543208Y1075890D03*
X1539507Y1101402D03*
X1533956Y1104591D03*
X1537657Y1091835D03*
X1532106Y1095024D03*
X1539507D03*
X1533956Y1098213D03*
X1537657D03*
X1532106Y1101402D03*
X1537657Y1104591D03*
X1533956Y1091835D03*
X1541357Y1104591D03*
X1543208Y1095024D03*
X1537657Y1110969D03*
X1532106Y1114158D03*
X1539507D03*
X1533956Y1117347D03*
X1537657D03*
X1539507Y1107780D03*
X1532106D03*
X1533956Y1110969D03*
X1543208Y1114158D03*
X1532106Y1120536D03*
X1539507D03*
X1533956Y1123725D03*
X1537657Y1130102D03*
X1532106Y1133292D03*
X1539507D03*
Y1126914D03*
X1532106D03*
X1537657Y1123725D03*
X1533956Y1130102D03*
X1543208Y1133292D03*
X1541357Y1123725D03*
X1533956Y1136480D03*
X1537657D03*
X1532106Y1139669D03*
X1539507D03*
X1533956Y1142858D03*
X1537657Y1149236D03*
X1539507Y1146047D03*
X1532106D03*
X1537657Y1142858D03*
X1533956Y1149236D03*
X1541357Y1142858D03*
X1533956Y1161992D03*
X1543208Y1158803D03*
X1532106Y1152425D03*
X1539507D03*
X1533956Y1155614D03*
X1539507Y1158803D03*
X1543208Y1152425D03*
X1537657Y1161992D03*
X1530255D03*
X1535368Y1540355D03*
X1537468D03*
X1538875Y1547073D03*
X1538819Y1549336D03*
X1531068Y1563608D03*
X1532643Y1566336D03*
X1539170Y1567540D03*
X1539171Y1564618D03*
X1539082Y1561698D03*
X1538585Y1571658D03*
X1539170Y1569640D03*
X1549428Y879623D03*
X1545728D03*
X1543877Y1010371D03*
X1545058Y1028055D03*
X1548759Y1161992D03*
X1546909Y1165181D03*
X1588264Y1549970D03*
X1580940Y1540460D03*
X1578689Y1540509D03*
X1578854Y1546218D03*
X1577195Y1551121D03*
X1577596Y1554612D03*
X1577642Y1568698D03*
Y1570898D03*
X1583160Y1577625D03*
X1579089Y1573317D03*
X1592988Y1549970D03*
X1597713D03*
X1602437D03*
X1589839Y1552698D03*
X1594563D03*
X1599287D03*
X1607161Y1549970D03*
X1611886D03*
X1616610D03*
X1604012Y1552698D03*
X1608736D03*
X1613461D03*
X1621335Y1549970D03*
X1626059D03*
X1630783D03*
X1618185Y1552698D03*
X1622909D03*
X1627634D03*
X1632358D03*
X1635508Y1549970D03*
X1640232D03*
X1644957D03*
X1637083Y1552698D03*
X1641807D03*
X1646531D03*
X1649681Y1549970D03*
X1654406D03*
X1659130D03*
X1651256Y1552698D03*
X1655980D03*
X1660705D03*
X1663430Y1540355D03*
X1665530D03*
X1666937Y1547073D03*
X1666881Y1549336D03*
X1667231Y1567540D03*
X1667232Y1564618D03*
X1667143Y1561698D03*
X1670227Y1567413D03*
X1668750Y1563158D03*
X1666647Y1571658D03*
X1667231Y1569640D03*
G54D39*
X326731Y653394D03*
X363731D03*
X433624Y594259D03*
X754645Y1426892D03*
X766889Y1486756D03*
Y1530256D03*
X1166535Y1412479D03*
X1291146Y1375715D03*
X1320516D03*
X1415690Y601230D03*
X1487677Y640145D03*
X1524437Y640365D03*
X1701285Y198612D03*
X1700840Y1424519D03*
X1731660Y198612D03*
X1770442Y284934D03*
X1800002D03*
G54D25*
X79729Y289822D03*
Y310256D03*
X89729Y289822D03*
X99729D03*
X89729Y310256D03*
X99729D03*
X757184Y1712772D03*
Y1722772D03*
X1072863Y1419176D03*
Y1429176D03*
X1080970Y1650958D03*
Y1660958D03*
X1299439Y92812D03*
Y102812D03*
X1530377Y581353D03*
X1540377D03*
G54D67*
X1233404Y60384D03*
X1241278D03*
X1249152D03*
X1439049Y87432D03*
X1431175D03*
X1446923D03*
G54D23*
X64823Y756832D03*
Y760178D03*
X73933Y768706D03*
X73960Y766090D03*
X69323Y780257D03*
Y786950D03*
Y803682D03*
Y793643D03*
Y796989D03*
Y817068D03*
Y810375D03*
Y823761D03*
Y830454D03*
Y833800D03*
Y840493D03*
Y847186D03*
Y853879D03*
Y860572D03*
Y877304D03*
Y867265D03*
Y870611D03*
Y883997D03*
Y890690D03*
Y897383D03*
Y904076D03*
Y907423D03*
Y914115D03*
Y920808D03*
Y927501D03*
Y934194D03*
Y940887D03*
Y950926D03*
Y944234D03*
Y964312D03*
Y957619D03*
Y971005D03*
Y977698D03*
Y984391D03*
Y1001123D03*
Y997777D03*
Y991084D03*
Y1031241D03*
Y1037934D03*
Y1044627D03*
Y1058013D03*
Y1051320D03*
Y1074745D03*
Y1068052D03*
Y1064706D03*
Y1081438D03*
Y1088131D03*
Y1098171D03*
Y1104863D03*
Y1091478D03*
Y1111556D03*
Y1118249D03*
Y1134982D03*
Y1124942D03*
Y1128289D03*
Y1148367D03*
Y1141675D03*
Y1155060D03*
Y1161753D03*
Y1165100D03*
Y1171793D03*
Y1178486D03*
Y1185178D03*
Y1191871D03*
Y1208604D03*
Y1198564D03*
Y1201911D03*
Y1215297D03*
Y1221989D03*
Y1228682D03*
Y1235375D03*
Y1238722D03*
Y1245415D03*
Y1252108D03*
X94524Y760178D03*
Y756832D03*
X89965D03*
X90015Y766871D03*
X85465Y776911D03*
X89965Y763525D03*
X94474D03*
X90015Y770218D03*
X85465Y783604D03*
Y790297D03*
Y800336D03*
Y807029D03*
Y793643D03*
Y813722D03*
Y820415D03*
Y837147D03*
Y830454D03*
Y827108D03*
Y843840D03*
Y850533D03*
Y857226D03*
Y863919D03*
Y873958D03*
Y880651D03*
Y867265D03*
Y887344D03*
Y894037D03*
Y910769D03*
Y904076D03*
Y900730D03*
Y924155D03*
Y917462D03*
Y930848D03*
Y940887D03*
Y937541D03*
Y947580D03*
Y954273D03*
Y960966D03*
Y967659D03*
Y974352D03*
Y981045D03*
Y987737D03*
Y994430D03*
Y1001123D03*
Y1027895D03*
Y1034588D03*
Y1041281D03*
Y1047974D03*
Y1054667D03*
Y1061360D03*
Y1071399D03*
Y1064706D03*
Y1078092D03*
Y1088131D03*
Y1084785D03*
Y1094824D03*
Y1101517D03*
Y1108210D03*
Y1114903D03*
Y1131635D03*
Y1124942D03*
Y1121596D03*
Y1138328D03*
Y1145021D03*
Y1151714D03*
Y1161753D03*
Y1158407D03*
Y1168446D03*
Y1175139D03*
Y1181832D03*
Y1188525D03*
Y1205257D03*
Y1198564D03*
Y1195218D03*
Y1211950D03*
Y1218643D03*
Y1225336D03*
Y1235375D03*
Y1232029D03*
Y1242068D03*
Y1248761D03*
X103574Y763766D03*
X99024Y780257D03*
Y786950D03*
Y803682D03*
Y793643D03*
Y796989D03*
Y817068D03*
Y810375D03*
Y823761D03*
Y830454D03*
Y833800D03*
Y840493D03*
Y847186D03*
Y853879D03*
Y860572D03*
Y877304D03*
Y867265D03*
Y870611D03*
Y883997D03*
Y890690D03*
Y897383D03*
Y904076D03*
Y907423D03*
Y914115D03*
Y920808D03*
Y927501D03*
Y934194D03*
Y940887D03*
Y950926D03*
Y944234D03*
Y964312D03*
Y957619D03*
Y971005D03*
Y977698D03*
Y984391D03*
Y1001123D03*
Y997777D03*
Y991084D03*
Y1031241D03*
Y1037934D03*
Y1044627D03*
Y1058013D03*
Y1051320D03*
Y1074745D03*
Y1068052D03*
Y1064706D03*
Y1081438D03*
Y1088131D03*
Y1098171D03*
Y1104863D03*
Y1091478D03*
Y1111556D03*
Y1118249D03*
Y1134982D03*
Y1124942D03*
Y1128289D03*
Y1148367D03*
Y1141675D03*
Y1155060D03*
Y1161753D03*
Y1165100D03*
Y1171793D03*
Y1178486D03*
Y1185178D03*
Y1191871D03*
Y1208604D03*
Y1198564D03*
Y1201911D03*
Y1215297D03*
Y1221989D03*
Y1228682D03*
Y1235375D03*
Y1238722D03*
Y1245415D03*
Y1252108D03*
X124224Y760178D03*
Y756832D03*
X119666D03*
X119616Y767166D03*
X115166Y776911D03*
X119666Y763525D03*
X124174D03*
X119716Y770218D03*
X115166Y783604D03*
Y790297D03*
Y800336D03*
Y807029D03*
Y793643D03*
Y813722D03*
Y820415D03*
Y837147D03*
Y830454D03*
Y827108D03*
Y843840D03*
Y850533D03*
Y857226D03*
Y863919D03*
Y873958D03*
Y880651D03*
Y867265D03*
Y887344D03*
Y894037D03*
Y910769D03*
Y904076D03*
Y900730D03*
Y924155D03*
Y917462D03*
Y930848D03*
Y940887D03*
Y937541D03*
Y947580D03*
Y954273D03*
Y960966D03*
Y967659D03*
Y974352D03*
Y981045D03*
Y987737D03*
Y994430D03*
Y1001123D03*
Y1027895D03*
Y1034588D03*
Y1041281D03*
Y1047974D03*
Y1054667D03*
Y1061360D03*
Y1071399D03*
Y1064706D03*
Y1078092D03*
Y1088131D03*
Y1084785D03*
Y1094824D03*
Y1101517D03*
Y1108210D03*
Y1114903D03*
Y1131635D03*
Y1124942D03*
Y1121596D03*
Y1138328D03*
Y1145021D03*
Y1151714D03*
Y1161753D03*
Y1158407D03*
Y1168446D03*
Y1175139D03*
Y1181832D03*
Y1188525D03*
Y1205257D03*
Y1198564D03*
Y1195218D03*
Y1211950D03*
Y1218643D03*
Y1225336D03*
Y1235375D03*
Y1232029D03*
Y1242068D03*
Y1248761D03*
X133124Y763766D03*
X128724Y1068052D03*
Y1064706D03*
X153925Y760178D03*
Y756832D03*
X149366D03*
X149416Y766871D03*
X149366Y763525D03*
X153875D03*
X149416Y770218D03*
X144866Y960966D03*
X150366D03*
X162975Y763766D03*
X158425Y1068052D03*
Y1064706D03*
X183626Y760178D03*
Y756832D03*
X179067D03*
X179117Y766871D03*
X179067Y763525D03*
X183576D03*
X179117Y770218D03*
X174567Y960966D03*
X180067D03*
X186530Y1523953D03*
X192676Y763766D03*
X188126Y780257D03*
Y786950D03*
Y803682D03*
Y793643D03*
Y796989D03*
Y817068D03*
Y810375D03*
Y823761D03*
Y830454D03*
Y833800D03*
Y840493D03*
Y847186D03*
Y853879D03*
Y860572D03*
Y877304D03*
Y867265D03*
Y870611D03*
Y883997D03*
Y890690D03*
Y897383D03*
Y904076D03*
Y907423D03*
Y914115D03*
Y920808D03*
Y927501D03*
Y934194D03*
Y940887D03*
Y950926D03*
Y944234D03*
Y964312D03*
Y957619D03*
Y971005D03*
Y977698D03*
Y984391D03*
Y1001123D03*
Y997777D03*
Y991084D03*
Y1031241D03*
Y1037934D03*
Y1044627D03*
Y1058013D03*
Y1051320D03*
Y1074745D03*
Y1068052D03*
Y1064706D03*
Y1081438D03*
Y1088131D03*
Y1098171D03*
Y1104863D03*
Y1091478D03*
Y1111556D03*
Y1118249D03*
Y1134982D03*
Y1124942D03*
Y1128289D03*
Y1148367D03*
Y1141675D03*
Y1155060D03*
Y1161753D03*
Y1165100D03*
Y1171793D03*
Y1178486D03*
Y1185178D03*
Y1191871D03*
Y1208604D03*
Y1198564D03*
Y1201911D03*
Y1215297D03*
Y1221989D03*
Y1228682D03*
Y1235375D03*
Y1238722D03*
Y1245415D03*
Y1252108D03*
X195979Y1523953D03*
X196530Y1526353D03*
X191805D03*
X187081D03*
X200703Y1523953D03*
X201254Y1526353D03*
X191254Y1523953D03*
X188254Y1544997D03*
X192978D03*
X197703D03*
X188254Y1548397D03*
X192978D03*
X197703D03*
X188166Y1592380D03*
X200226D03*
X191566D03*
X188166Y1624292D03*
X200226D03*
X191566D03*
X213327Y760178D03*
Y756832D03*
X208768D03*
X204268Y776911D03*
X208768Y763525D03*
X212772Y766871D03*
X213277Y763525D03*
X208818Y770218D03*
X204268Y783604D03*
Y790297D03*
Y800336D03*
Y807029D03*
Y793643D03*
Y813722D03*
Y820415D03*
Y837147D03*
Y830454D03*
Y827108D03*
Y843840D03*
Y850533D03*
Y857226D03*
Y863919D03*
Y873958D03*
Y880651D03*
Y867265D03*
Y887344D03*
Y894037D03*
Y910769D03*
Y904076D03*
Y900730D03*
Y924155D03*
Y917462D03*
Y930848D03*
Y940887D03*
Y937541D03*
Y947580D03*
Y954273D03*
Y960966D03*
Y967659D03*
Y974352D03*
Y981045D03*
Y987737D03*
Y994430D03*
Y1001123D03*
Y1027895D03*
Y1034588D03*
Y1041281D03*
Y1047974D03*
Y1054667D03*
Y1061360D03*
Y1071399D03*
Y1064706D03*
Y1078092D03*
Y1088131D03*
Y1084785D03*
Y1094824D03*
Y1101517D03*
Y1108210D03*
Y1114903D03*
Y1131635D03*
Y1124942D03*
Y1121596D03*
Y1138328D03*
Y1145021D03*
Y1151714D03*
Y1161753D03*
Y1158407D03*
Y1168446D03*
Y1175139D03*
Y1181832D03*
Y1188525D03*
Y1205257D03*
Y1198564D03*
Y1195218D03*
Y1211950D03*
Y1218643D03*
Y1225336D03*
Y1235375D03*
Y1232029D03*
Y1242068D03*
Y1248761D03*
X205427Y1523953D03*
X205978Y1526353D03*
X210703D03*
X210152Y1523953D03*
X214876D03*
X215427Y1526353D03*
X202427Y1544997D03*
X207152D03*
X211876D03*
X216601D03*
X202427Y1548397D03*
X207152D03*
X211876D03*
X216601D03*
X212286Y1592380D03*
X203626D03*
X215686D03*
X212286Y1624292D03*
X203626D03*
X215686D03*
X222377Y763766D03*
X227540Y960966D03*
X220152Y1526353D03*
X224876D03*
X224325Y1523953D03*
X219601D03*
X229049D03*
X229600Y1526353D03*
X221325Y1544997D03*
X226050D03*
X230774D03*
X221325Y1548397D03*
X226050D03*
X230774D03*
X224346Y1592380D03*
X227746D03*
X224346Y1624292D03*
X227746D03*
X238469Y756832D03*
Y763525D03*
X238519Y770218D03*
X233969Y960966D03*
X243223Y1523953D03*
X243774Y1526353D03*
X238498Y1523953D03*
X239049Y1526353D03*
X233774Y1523953D03*
X234325Y1526353D03*
X235499Y1544997D03*
X240223D03*
X244947D03*
X235499Y1548397D03*
X240223D03*
X244947D03*
X236406Y1592380D03*
X239806D03*
X236406Y1624292D03*
X239806D03*
X257396Y1523953D03*
X253223Y1526353D03*
X252672Y1523953D03*
X257947Y1526353D03*
X248498D03*
X247947Y1523953D03*
X249671Y1544997D03*
X254396D03*
X259120D03*
X249671Y1548397D03*
X254396D03*
X259120D03*
X248466Y1592380D03*
X260526D03*
X251866D03*
X248466Y1624292D03*
X260526D03*
X251866D03*
X272525Y108556D03*
X268981D03*
Y111056D03*
X265438Y108556D03*
X261895D03*
Y111056D03*
X265438D03*
X272525D03*
X272586Y1592380D03*
X263926D03*
X275986D03*
X272586Y1624292D03*
X263926D03*
X275986D03*
X284646Y1592380D03*
X288046D03*
X284646Y1624292D03*
X288046D03*
X296706Y1592380D03*
X300106D03*
X296706Y1624292D03*
X300106D03*
X306694Y1507279D03*
X319867Y1526353D03*
X315143D03*
X319316Y1523953D03*
X314592D03*
X316316Y1544997D03*
X321040D03*
X316316Y1548397D03*
X321040D03*
X308766Y1592380D03*
X320826D03*
X312166D03*
X308766Y1624292D03*
X320826D03*
X312166D03*
X324041Y1523953D03*
X324592Y1526353D03*
X328765Y1523953D03*
X329316Y1526353D03*
X334040D03*
X333489Y1523953D03*
X325765Y1544997D03*
X330489D03*
X335214D03*
X325765Y1548397D03*
X330489D03*
X335214D03*
X332886Y1592380D03*
X324226D03*
X332886Y1624292D03*
X324226D03*
X338765Y1526353D03*
X338214Y1523953D03*
X347663D03*
X348214Y1526353D03*
X343489D03*
X342938Y1523953D03*
X339938Y1544997D03*
X344663D03*
X349387D03*
X339938Y1548397D03*
X344663D03*
X349387D03*
X344946Y1592380D03*
X336286D03*
X348346D03*
X344946Y1624292D03*
X336286D03*
X348346D03*
X362387Y1526353D03*
X361836Y1523953D03*
X352387D03*
X352938Y1526353D03*
X357662D03*
X357111Y1523953D03*
X363561Y1544997D03*
X354112D03*
X358836D03*
X363561Y1548397D03*
X354112D03*
X358836D03*
X357006Y1592380D03*
X360406D03*
X357006Y1624292D03*
X360406D03*
X380734Y1523953D03*
X376560Y1526353D03*
X376009Y1523953D03*
X371285D03*
X371836Y1526353D03*
X367111D03*
X366560Y1523953D03*
X368285Y1544997D03*
X373009D03*
X377733D03*
X368285Y1548397D03*
X373009D03*
X377733D03*
X369066Y1592380D03*
X372466D03*
X369066Y1624292D03*
X372466D03*
X385458Y1523953D03*
X381285Y1526353D03*
X386009D03*
X382458Y1544997D03*
X387182D03*
X382458Y1548397D03*
X387182D03*
X450703Y1523953D03*
X451254Y1526353D03*
X452427Y1544997D03*
Y1548397D03*
X452339Y1624292D03*
X464876Y1523953D03*
X460703Y1526353D03*
X455978D03*
X465427D03*
X455427Y1523953D03*
X460152D03*
X469600D03*
X470151Y1526353D03*
X457151Y1544997D03*
X461876D03*
X466600D03*
X457151Y1548397D03*
X461876D03*
X466600D03*
X464399Y1624292D03*
X455739D03*
X467799D03*
X474325Y1523953D03*
X474876Y1526353D03*
X483774Y1523953D03*
X484325Y1526353D03*
X479049Y1523953D03*
X479600Y1526353D03*
X471325Y1544997D03*
X476049D03*
X480774D03*
X471325Y1548397D03*
X476049D03*
X480774D03*
X476459Y1624292D03*
X479859D03*
X497947Y1523953D03*
X498498Y1526353D03*
X488498Y1523953D03*
X489049Y1526353D03*
X493222Y1523953D03*
X493773Y1526353D03*
X499672Y1544997D03*
X485498D03*
X490223D03*
X494947D03*
X499672Y1548397D03*
X485498D03*
X490223D03*
X494947D03*
X488519Y1624292D03*
X491919D03*
X507947Y1526353D03*
X507396Y1523953D03*
X512120D03*
X512671Y1526353D03*
X503222D03*
X502671Y1523953D03*
X504396Y1544997D03*
X509120D03*
X513844D03*
X504396Y1548397D03*
X509120D03*
X513844D03*
X500579Y1624292D03*
X512639D03*
X503979D03*
X521569Y1523953D03*
X522120Y1526353D03*
X517396D03*
X516845Y1523953D03*
X518569Y1544997D03*
X523293D03*
X518569Y1548397D03*
X523293D03*
X524699Y1624292D03*
X516039D03*
X528099D03*
X536759D03*
X540159D03*
X548819D03*
X552219D03*
X572939D03*
X560879D03*
X564279D03*
X588765Y1526353D03*
X588214Y1523953D03*
X578765D03*
X583489D03*
X579316Y1526353D03*
X584040D03*
X580489Y1544997D03*
X585213D03*
X580489Y1548397D03*
X585213D03*
X584999Y1624292D03*
X576339D03*
X588399D03*
X602387Y1523953D03*
X602938Y1526353D03*
X592938Y1523953D03*
X593489Y1526353D03*
X598213D03*
X597662Y1523953D03*
X589938Y1544997D03*
X594662D03*
X599387D03*
X604111D03*
X589938Y1548397D03*
X594662D03*
X599387D03*
X604111D03*
X597059Y1624292D03*
X600459D03*
X616560Y1523953D03*
X617111Y1526353D03*
X607111Y1523953D03*
X607662Y1526353D03*
X612387D03*
X611836Y1523953D03*
X608836Y1544997D03*
X613560D03*
X618285D03*
X608836Y1548397D03*
X613560D03*
X618285D03*
X609119Y1624292D03*
X612519D03*
X626009Y1523953D03*
X626560Y1526353D03*
X631284D03*
X630733Y1523953D03*
X621835Y1526353D03*
X621284Y1523953D03*
X627734Y1544997D03*
X632458D03*
X623009D03*
X627734Y1548397D03*
X632458D03*
X623009D03*
X621179Y1624292D03*
X633239D03*
X624579D03*
X642854Y760178D03*
Y756832D03*
X642804Y763525D03*
X644907Y1523953D03*
X640733Y1526353D03*
X640182Y1523953D03*
X635458D03*
X636009Y1526353D03*
X645458D03*
X637182Y1544997D03*
X641906D03*
X646631D03*
X637182Y1548397D03*
X641906D03*
X646631D03*
X636639Y1624292D03*
X651905Y763766D03*
X663496Y960966D03*
X657996D03*
X650182Y1526353D03*
X649631Y1523953D03*
X651355Y1544997D03*
Y1548397D03*
X664634Y449952D03*
X667996Y756832D03*
X672555D03*
Y760178D03*
X668046Y766871D03*
X667996Y763525D03*
X672505D03*
X668046Y770218D03*
X677055Y780257D03*
Y786950D03*
Y803682D03*
Y793643D03*
Y796989D03*
Y817068D03*
Y810375D03*
Y823761D03*
Y830454D03*
Y833800D03*
Y840493D03*
Y847186D03*
Y853879D03*
Y860572D03*
Y877304D03*
Y867265D03*
Y870611D03*
Y883997D03*
Y890690D03*
Y897383D03*
Y904076D03*
Y907423D03*
Y914115D03*
Y920808D03*
Y927501D03*
Y934194D03*
Y940887D03*
Y950926D03*
Y944234D03*
Y964312D03*
Y957619D03*
Y971005D03*
Y977698D03*
Y984391D03*
Y1001123D03*
Y997777D03*
Y991084D03*
Y1031241D03*
Y1037934D03*
Y1044627D03*
Y1058013D03*
Y1051320D03*
Y1074745D03*
Y1068052D03*
Y1064706D03*
Y1081438D03*
Y1088131D03*
Y1098171D03*
Y1104863D03*
Y1091478D03*
Y1111556D03*
Y1118249D03*
Y1134982D03*
Y1124942D03*
Y1128289D03*
Y1148367D03*
Y1141675D03*
Y1155060D03*
Y1161753D03*
Y1165100D03*
Y1171793D03*
Y1178486D03*
Y1185178D03*
Y1191871D03*
Y1208604D03*
Y1198564D03*
Y1201911D03*
Y1215297D03*
Y1221989D03*
Y1228682D03*
Y1235375D03*
Y1238722D03*
Y1245415D03*
Y1252108D03*
X695796Y430957D03*
Y437256D03*
Y468672D03*
X693197Y776911D03*
X681606Y763766D03*
X693197Y783604D03*
Y790297D03*
Y800336D03*
Y807029D03*
Y793643D03*
Y813722D03*
Y820415D03*
Y837147D03*
Y830454D03*
Y827108D03*
Y843840D03*
Y850533D03*
Y857226D03*
Y863919D03*
Y873958D03*
Y880651D03*
Y867265D03*
Y887344D03*
Y894037D03*
Y910769D03*
Y904076D03*
Y900730D03*
Y924155D03*
Y917462D03*
Y930848D03*
Y940887D03*
Y937541D03*
Y947580D03*
Y954273D03*
Y960966D03*
Y967659D03*
Y974352D03*
Y981045D03*
Y987737D03*
Y994430D03*
Y1001123D03*
Y1027895D03*
Y1034588D03*
Y1041281D03*
Y1047974D03*
Y1054667D03*
Y1061360D03*
Y1071399D03*
Y1064706D03*
Y1078092D03*
Y1088131D03*
Y1084785D03*
Y1094824D03*
Y1101517D03*
Y1108210D03*
Y1114903D03*
Y1131635D03*
Y1124942D03*
Y1121596D03*
Y1138328D03*
Y1145021D03*
Y1151714D03*
Y1161753D03*
Y1158407D03*
Y1168446D03*
Y1175139D03*
Y1181832D03*
Y1188525D03*
Y1205257D03*
Y1198564D03*
Y1195218D03*
Y1211950D03*
Y1218643D03*
Y1225336D03*
Y1235375D03*
Y1232029D03*
Y1242068D03*
Y1248761D03*
X698599Y115178D03*
X705686D03*
X702142D03*
X698599Y112678D03*
X705686D03*
X702142D03*
X695056D03*
Y115178D03*
X708395Y427807D03*
Y424657D03*
X705245D03*
Y427807D03*
X702095D03*
X708395Y434106D03*
X705245Y430957D03*
X702095Y434106D03*
X698946Y427807D03*
X705245Y437256D03*
X698946Y430957D03*
X705245Y434106D03*
X702095Y430957D03*
X705245Y446705D03*
X708395Y440405D03*
Y443555D03*
X702095Y446705D03*
X705245Y443555D03*
X702095Y437256D03*
Y440405D03*
Y443555D03*
X705245Y440405D03*
X708395Y437256D03*
X698946Y446705D03*
X708395D03*
X698946Y449854D03*
X708395Y462373D03*
Y449854D03*
X705245Y459223D03*
X702095Y456074D03*
Y459223D03*
X708395Y456074D03*
X705245Y462373D03*
X702095D03*
X705245Y456074D03*
X695796Y449854D03*
X708395Y459223D03*
Y465523D03*
X705245Y468672D03*
X702095D03*
X698946Y471822D03*
X702095Y465523D03*
X695796Y471822D03*
X708395Y478121D03*
X705245Y471822D03*
X695796Y465523D03*
X702095Y478121D03*
X705245Y474971D03*
X708395Y471822D03*
Y468672D03*
X705245Y465523D03*
X702095Y471822D03*
X698946Y465523D03*
X705245Y478121D03*
X702095Y474971D03*
X698946Y487570D03*
Y481271D03*
Y484420D03*
X705245Y481271D03*
X702095D03*
X695796Y484420D03*
X708395D03*
Y481271D03*
X697697Y756832D03*
X702256D03*
Y760178D03*
X697747Y766871D03*
X697697Y763525D03*
X702206D03*
X697747Y770218D03*
X706756Y1068052D03*
Y1064706D03*
X720993Y418358D03*
X717843D03*
Y421508D03*
X720993Y430957D03*
X711544D03*
X714694D03*
X717843Y434106D03*
X720993D03*
X717843Y430957D03*
X720993Y421508D03*
X711544Y434106D03*
X714694D03*
X720993Y424657D03*
X717843D03*
Y427807D03*
X714694Y424657D03*
Y427807D03*
X711544Y424657D03*
Y427807D03*
X720993D03*
X717843Y437256D03*
X720993D03*
X714694D03*
X711544D03*
Y443555D03*
X717843D03*
X714694Y446705D03*
Y440405D03*
X720993D03*
X711544D03*
X714694Y443555D03*
X711544Y446705D03*
Y459223D03*
X714694D03*
X717843Y462373D03*
Y456074D03*
Y449854D03*
X714694Y462373D03*
X711544D03*
X714694Y449854D03*
X711544D03*
X714694Y456074D03*
X711544D03*
X720993Y471822D03*
Y468672D03*
X711544Y478121D03*
X717843Y474971D03*
X724143Y471822D03*
X720993Y478121D03*
X717843D03*
X720993Y474971D03*
X714694Y465523D03*
X717843Y471822D03*
Y468672D03*
X714694Y471822D03*
X711544D03*
X714694Y468672D03*
X711544D03*
X720993Y465523D03*
X711544Y474971D03*
X714694Y478121D03*
Y474971D03*
X724143Y481271D03*
X711544Y465523D03*
X717843Y481271D03*
X714694D03*
X720993D03*
X711544D03*
X720993Y484420D03*
X711307Y763766D03*
X722898Y960966D03*
X717398D03*
X731208Y398737D03*
X733512Y418358D03*
X727292D03*
X724143D03*
X736661Y424657D03*
Y430957D03*
Y434106D03*
X733512D03*
Y421508D03*
Y424657D03*
Y430957D03*
X727292D03*
Y434106D03*
X724143Y430957D03*
X727292Y427807D03*
X736661D03*
X727292Y424657D03*
X724143Y434106D03*
Y421508D03*
X739811Y430957D03*
X724143Y427807D03*
Y424657D03*
X733512Y437256D03*
X727292Y440405D03*
X724143Y446705D03*
X736661D03*
X733512Y440405D03*
X736661D03*
X727292Y437256D03*
X724143Y440405D03*
Y437256D03*
X736661D03*
Y459223D03*
Y456074D03*
X733512D03*
Y449854D03*
X736661D03*
X727292Y456074D03*
X724143Y459223D03*
Y456074D03*
X727292Y449854D03*
X724143D03*
X727292Y471822D03*
X724143Y468672D03*
X727292D03*
X736661D03*
X724143Y474971D03*
X733512Y478121D03*
X724143Y465523D03*
X727292D03*
X733512D03*
X736661D03*
X733512Y474971D03*
Y468672D03*
X736661Y478121D03*
Y471822D03*
X724143Y478121D03*
X727292D03*
X733512Y471822D03*
X736661Y474971D03*
Y487570D03*
Y481271D03*
X733512D03*
X727292D03*
X724143Y487570D03*
X727292Y484420D03*
Y487570D03*
X727398Y756832D03*
X731957D03*
Y760178D03*
X727398Y763525D03*
X731462Y766871D03*
X731907Y763525D03*
X727448Y770218D03*
X736457Y1068052D03*
Y1064706D03*
X755559Y421508D03*
X739811Y424657D03*
Y427807D03*
X742961Y424657D03*
Y427807D03*
X746110Y424657D03*
Y427807D03*
X752409Y430957D03*
Y434106D03*
X749260D03*
X752409Y424657D03*
X749260D03*
X746110Y430957D03*
X749260D03*
X742961D03*
X752409Y427807D03*
X749260D03*
X739811Y434106D03*
X742961D03*
X746110D03*
X752409Y443555D03*
X739811Y437256D03*
X746110D03*
X742961D03*
X746110Y440405D03*
X749260Y437256D03*
X739811Y440405D03*
X742961Y443555D03*
Y446705D03*
X752409Y440405D03*
X749260D03*
Y446705D03*
X752409Y437256D03*
Y446705D03*
X746110D03*
Y443555D03*
X749260D03*
X742961Y459223D03*
Y462373D03*
Y456074D03*
Y449854D03*
X752409Y456074D03*
X749260Y449854D03*
X746110Y459223D03*
X752409Y462373D03*
Y459223D03*
X749260D03*
X746110Y456074D03*
Y449854D03*
Y462373D03*
X749260D03*
X752409Y449854D03*
X749260Y456074D03*
X742961Y474971D03*
Y468672D03*
X739811Y478121D03*
Y474971D03*
Y471822D03*
X749260D03*
X739811Y468672D03*
X749260D03*
Y474971D03*
X742961Y471822D03*
X749260Y478121D03*
X746110Y474971D03*
X752409Y468672D03*
X742961Y478121D03*
X746110Y468672D03*
X739811Y465523D03*
X752409Y478121D03*
Y471822D03*
Y465523D03*
X746110D03*
X749260D03*
X752409Y474971D03*
X746110Y478121D03*
Y471822D03*
X749260Y481271D03*
X742961Y484420D03*
X739811Y481271D03*
X746110Y484420D03*
X749260D03*
X752409Y487570D03*
X742961D03*
Y490070D03*
X746110Y481271D03*
X752409D03*
X742961D03*
X741007Y763766D03*
X752599Y960966D03*
X747099D03*
X755559Y418358D03*
X758709D03*
X761858D03*
X755559Y427807D03*
Y430957D03*
X758709Y427807D03*
Y430957D03*
X765008Y424657D03*
X755559D03*
X758709D03*
Y421508D03*
X761858Y424657D03*
X765008Y430957D03*
X755559Y434106D03*
X761858Y430957D03*
Y427807D03*
X758709Y434106D03*
X765008Y427807D03*
Y446705D03*
X758709D03*
X755559Y443555D03*
Y446705D03*
Y437256D03*
X758709Y440405D03*
X755559D03*
X758709Y443555D03*
X761858Y446705D03*
X755559Y449854D03*
Y459223D03*
X765008Y456074D03*
X758709Y465523D03*
X755559Y462373D03*
X758709Y459223D03*
Y462373D03*
Y456074D03*
Y449854D03*
X755559Y478121D03*
Y468672D03*
Y471822D03*
X758709D03*
X761858Y478121D03*
Y474971D03*
Y471822D03*
X758709Y474971D03*
X765008Y471822D03*
Y474971D03*
Y465523D03*
X758709Y478121D03*
X761858Y468672D03*
Y465523D03*
X765008Y468672D03*
X755559Y465523D03*
Y474971D03*
Y481271D03*
Y484420D03*
X765008Y481271D03*
X761858D03*
X758709D03*
X757099Y756832D03*
X761658D03*
Y760178D03*
X757149Y766871D03*
X757099Y763525D03*
X761608D03*
X757149Y770218D03*
X766158Y780257D03*
Y786950D03*
Y803682D03*
Y793643D03*
Y796989D03*
Y817068D03*
Y810375D03*
Y823761D03*
Y830454D03*
Y833800D03*
Y840493D03*
Y847186D03*
Y853879D03*
Y860572D03*
Y877304D03*
Y867265D03*
Y870611D03*
Y883997D03*
Y890690D03*
Y897383D03*
Y904076D03*
Y907423D03*
Y914115D03*
Y920808D03*
Y927501D03*
Y934194D03*
Y940887D03*
Y950926D03*
Y944234D03*
Y964312D03*
Y957619D03*
Y971005D03*
Y977698D03*
Y984391D03*
Y1001123D03*
Y997777D03*
Y991084D03*
Y1031241D03*
Y1037934D03*
Y1044627D03*
Y1058013D03*
Y1051320D03*
Y1074745D03*
Y1068052D03*
Y1064706D03*
Y1081438D03*
Y1088131D03*
Y1098171D03*
Y1104863D03*
Y1091478D03*
Y1111556D03*
Y1118249D03*
Y1134982D03*
Y1124942D03*
Y1128289D03*
Y1148367D03*
Y1141675D03*
Y1155060D03*
Y1161753D03*
Y1165100D03*
Y1171793D03*
Y1178486D03*
Y1185178D03*
Y1191871D03*
Y1208604D03*
Y1198564D03*
Y1201911D03*
Y1215297D03*
Y1221989D03*
Y1228682D03*
Y1235375D03*
Y1238722D03*
Y1245415D03*
Y1252108D03*
X782300Y776911D03*
X770708Y763766D03*
X782300Y783604D03*
Y790297D03*
Y800336D03*
Y807029D03*
Y793643D03*
Y813722D03*
Y820415D03*
Y837147D03*
Y830454D03*
Y827108D03*
Y843840D03*
Y850533D03*
Y857226D03*
Y863919D03*
Y873958D03*
Y880651D03*
Y867265D03*
Y887344D03*
Y894037D03*
Y910769D03*
Y904076D03*
Y900730D03*
Y924155D03*
Y917462D03*
Y930848D03*
Y940887D03*
Y937541D03*
Y947580D03*
Y954273D03*
Y960966D03*
Y967659D03*
Y974352D03*
Y981045D03*
Y987737D03*
Y994430D03*
Y1001123D03*
Y1027895D03*
Y1034588D03*
Y1041281D03*
Y1047974D03*
Y1054667D03*
Y1061360D03*
Y1071399D03*
Y1064706D03*
Y1078092D03*
Y1088131D03*
Y1084785D03*
Y1094824D03*
Y1101517D03*
Y1108210D03*
Y1114903D03*
Y1131635D03*
Y1124942D03*
Y1121596D03*
Y1138328D03*
Y1145021D03*
Y1151714D03*
Y1161753D03*
Y1158407D03*
Y1168446D03*
Y1175139D03*
Y1181832D03*
Y1188525D03*
Y1205257D03*
Y1198564D03*
Y1195218D03*
Y1211950D03*
Y1218643D03*
Y1225336D03*
Y1235375D03*
Y1232029D03*
Y1242068D03*
Y1248761D03*
X786800Y756832D03*
X791358Y760178D03*
Y756832D03*
X786850Y766871D03*
X786800Y763525D03*
X791308D03*
X786850Y770218D03*
X795858Y780257D03*
Y786950D03*
Y803682D03*
Y793643D03*
Y796989D03*
Y817068D03*
Y810375D03*
Y823761D03*
Y830454D03*
Y833800D03*
Y840493D03*
Y847186D03*
Y853879D03*
Y860572D03*
Y877304D03*
Y867265D03*
Y870611D03*
Y883997D03*
Y890690D03*
Y897383D03*
Y904076D03*
Y907423D03*
Y914115D03*
Y920808D03*
Y927501D03*
Y934194D03*
Y940887D03*
Y950926D03*
Y944234D03*
Y964312D03*
Y957619D03*
Y971005D03*
Y977698D03*
Y984391D03*
Y1001123D03*
Y997777D03*
Y991084D03*
Y1031241D03*
Y1037934D03*
Y1044627D03*
Y1058013D03*
Y1051320D03*
Y1074745D03*
Y1068052D03*
Y1064706D03*
Y1081438D03*
Y1088131D03*
Y1098171D03*
Y1104863D03*
Y1091478D03*
Y1111556D03*
Y1118249D03*
Y1134982D03*
Y1124942D03*
Y1128289D03*
Y1148367D03*
Y1141675D03*
Y1155060D03*
Y1161753D03*
Y1165100D03*
Y1171793D03*
Y1178486D03*
Y1185178D03*
Y1191871D03*
Y1208604D03*
Y1198564D03*
Y1201911D03*
Y1215297D03*
Y1221989D03*
Y1228682D03*
Y1235375D03*
Y1238722D03*
Y1245415D03*
Y1252108D03*
X812000Y776911D03*
X800409Y763765D03*
X812000Y783604D03*
Y790297D03*
Y800336D03*
Y807029D03*
Y793643D03*
Y813722D03*
Y820415D03*
Y837147D03*
Y830454D03*
Y827108D03*
Y843840D03*
Y850533D03*
Y857226D03*
Y863919D03*
Y873958D03*
Y880651D03*
Y867265D03*
Y887344D03*
Y894037D03*
Y910769D03*
Y904076D03*
Y900730D03*
Y924155D03*
Y917462D03*
Y930848D03*
Y940887D03*
Y937541D03*
Y947580D03*
Y954273D03*
Y960966D03*
Y967659D03*
Y974352D03*
Y981045D03*
Y987737D03*
Y994430D03*
Y1001123D03*
Y1027895D03*
Y1034588D03*
Y1041281D03*
Y1047974D03*
Y1054667D03*
Y1061360D03*
Y1071399D03*
Y1064706D03*
Y1078092D03*
Y1088131D03*
Y1084785D03*
Y1094824D03*
Y1101517D03*
Y1108210D03*
Y1114903D03*
Y1131635D03*
Y1124942D03*
Y1121596D03*
Y1138328D03*
Y1145021D03*
Y1151714D03*
Y1161753D03*
Y1158407D03*
Y1168446D03*
Y1175139D03*
Y1181832D03*
Y1188525D03*
Y1205257D03*
Y1198564D03*
Y1195218D03*
Y1211950D03*
Y1218643D03*
Y1225336D03*
Y1235375D03*
Y1232029D03*
Y1242068D03*
Y1248761D03*
X816500Y756832D03*
X816550Y770218D03*
X816500Y763525D03*
X998206Y196191D03*
X1000706D03*
X998206Y199735D03*
X1000706D03*
X998206Y206821D03*
X1000706D03*
X998206Y203278D03*
X1000706D03*
X1040965Y756831D03*
Y760177D03*
X1050015Y763765D03*
X1040915Y763524D03*
X1045465Y780256D03*
Y786949D03*
Y803681D03*
Y793642D03*
Y796988D03*
Y817067D03*
Y810374D03*
Y823760D03*
Y830453D03*
Y833799D03*
Y840492D03*
Y847185D03*
Y853878D03*
Y860571D03*
Y877303D03*
Y867264D03*
Y870610D03*
Y883996D03*
Y890689D03*
Y897382D03*
Y904075D03*
Y907422D03*
Y914114D03*
Y920807D03*
Y927500D03*
Y934193D03*
Y940886D03*
Y950925D03*
Y944233D03*
Y964311D03*
Y957618D03*
Y971004D03*
Y977697D03*
Y984390D03*
Y1001122D03*
Y997776D03*
Y991083D03*
Y1031240D03*
Y1037933D03*
Y1044626D03*
Y1058012D03*
Y1051319D03*
Y1074744D03*
Y1068051D03*
Y1064705D03*
Y1081437D03*
Y1088130D03*
Y1098170D03*
Y1104862D03*
Y1091477D03*
Y1111555D03*
Y1118248D03*
Y1134981D03*
Y1124941D03*
Y1128288D03*
Y1148366D03*
Y1141674D03*
Y1155059D03*
Y1161752D03*
Y1165099D03*
Y1171792D03*
Y1178485D03*
Y1185177D03*
Y1191870D03*
Y1208603D03*
Y1198563D03*
Y1201910D03*
Y1215296D03*
Y1221988D03*
Y1228681D03*
Y1235374D03*
Y1238721D03*
Y1245414D03*
Y1252107D03*
X1066107Y756831D03*
X1066157Y766870D03*
X1061607Y776910D03*
X1066107Y763524D03*
X1066157Y770217D03*
X1061607Y783603D03*
Y790296D03*
Y800335D03*
Y807028D03*
Y793642D03*
Y813721D03*
Y820414D03*
Y837146D03*
Y830453D03*
Y827107D03*
Y843839D03*
Y850532D03*
Y857225D03*
Y863918D03*
Y873957D03*
Y880650D03*
Y867264D03*
Y887343D03*
Y894036D03*
Y910768D03*
Y904075D03*
Y900729D03*
Y924154D03*
Y917461D03*
Y930847D03*
Y940886D03*
Y937540D03*
Y947579D03*
Y954272D03*
Y960965D03*
Y967658D03*
Y974351D03*
Y981044D03*
Y987736D03*
Y994429D03*
Y1001122D03*
Y1027894D03*
Y1034587D03*
Y1041280D03*
Y1047973D03*
Y1054666D03*
Y1061359D03*
Y1071398D03*
Y1064705D03*
Y1078091D03*
Y1088130D03*
Y1084784D03*
Y1094823D03*
Y1101516D03*
Y1108209D03*
Y1114902D03*
Y1131634D03*
Y1124941D03*
Y1121595D03*
Y1138327D03*
Y1145020D03*
Y1151713D03*
Y1161752D03*
Y1158406D03*
Y1168445D03*
Y1175138D03*
Y1181831D03*
Y1188524D03*
Y1205256D03*
Y1198563D03*
Y1195217D03*
Y1211949D03*
Y1218642D03*
Y1225335D03*
Y1235374D03*
Y1232028D03*
Y1242067D03*
Y1248760D03*
X1070666Y756831D03*
Y760177D03*
X1079716Y763765D03*
X1070616Y763524D03*
X1075166Y780256D03*
Y786949D03*
Y803681D03*
Y793642D03*
Y796988D03*
Y817067D03*
Y810374D03*
Y823760D03*
Y830453D03*
Y833799D03*
Y840492D03*
Y847185D03*
Y853878D03*
Y860571D03*
Y877303D03*
Y867264D03*
Y870610D03*
Y883996D03*
Y890689D03*
Y897382D03*
Y904075D03*
Y907422D03*
Y914114D03*
Y920807D03*
Y927500D03*
Y934193D03*
Y940886D03*
Y950925D03*
Y944233D03*
Y964311D03*
Y957618D03*
Y971004D03*
Y977697D03*
Y984390D03*
Y1001122D03*
Y997776D03*
Y991083D03*
Y1031240D03*
Y1037933D03*
Y1044626D03*
Y1058012D03*
Y1051319D03*
Y1074744D03*
Y1068051D03*
Y1064705D03*
Y1081437D03*
Y1088130D03*
Y1098170D03*
Y1104862D03*
Y1091477D03*
Y1111555D03*
Y1118248D03*
Y1134981D03*
Y1124941D03*
Y1128288D03*
Y1148366D03*
Y1141674D03*
Y1155059D03*
Y1161752D03*
Y1165099D03*
Y1171792D03*
Y1178485D03*
Y1185177D03*
Y1191870D03*
Y1208603D03*
Y1198563D03*
Y1201910D03*
Y1215296D03*
Y1221988D03*
Y1228681D03*
Y1235374D03*
Y1238721D03*
Y1245414D03*
Y1252107D03*
X1095808Y756831D03*
X1095858Y766870D03*
X1091308Y776910D03*
X1095808Y763524D03*
X1095858Y770217D03*
X1091308Y783603D03*
Y790296D03*
Y800335D03*
Y807028D03*
Y793642D03*
Y813721D03*
Y820414D03*
Y837146D03*
Y830453D03*
Y827107D03*
Y843839D03*
Y850532D03*
Y857225D03*
Y863918D03*
Y873957D03*
Y880650D03*
Y867264D03*
Y887343D03*
Y894036D03*
Y910768D03*
Y904075D03*
Y900729D03*
Y924154D03*
Y917461D03*
Y930847D03*
Y940886D03*
Y937540D03*
Y947579D03*
Y954272D03*
Y960965D03*
Y967658D03*
Y974351D03*
Y981044D03*
Y987736D03*
Y994429D03*
Y1001122D03*
Y1027894D03*
Y1034587D03*
Y1041280D03*
Y1047973D03*
Y1054666D03*
Y1061359D03*
Y1071398D03*
Y1064705D03*
Y1078091D03*
Y1088130D03*
Y1084784D03*
Y1094823D03*
Y1101516D03*
Y1108209D03*
Y1114902D03*
Y1131634D03*
Y1124941D03*
Y1121595D03*
Y1138327D03*
Y1145020D03*
Y1151713D03*
Y1161752D03*
Y1158406D03*
Y1168445D03*
Y1175138D03*
Y1181831D03*
Y1188524D03*
Y1205256D03*
Y1198563D03*
Y1195217D03*
Y1211949D03*
Y1218642D03*
Y1225335D03*
Y1235374D03*
Y1232028D03*
Y1242067D03*
Y1248760D03*
X1100366Y756831D03*
Y760177D03*
X1109416Y763765D03*
X1100316Y763524D03*
X1104866Y1068051D03*
Y1064705D03*
X1125508Y756831D03*
X1125558Y766870D03*
X1125508Y763524D03*
X1125558Y770217D03*
X1121008Y960965D03*
X1130067Y756831D03*
Y760177D03*
X1139117Y763765D03*
X1130017Y763524D03*
X1126508Y960965D03*
X1134567Y1068051D03*
Y1064705D03*
X1155209Y756831D03*
Y763524D03*
X1155259Y770217D03*
X1150709Y960965D03*
X1159768Y756831D03*
Y760177D03*
X1168818Y763765D03*
X1159718Y763524D03*
X1164268Y780256D03*
Y786949D03*
Y803681D03*
Y793642D03*
Y796988D03*
Y817067D03*
Y810374D03*
Y823760D03*
Y830453D03*
Y833799D03*
Y840492D03*
Y847185D03*
Y853878D03*
Y860571D03*
Y877303D03*
Y867264D03*
Y870610D03*
Y883996D03*
Y890689D03*
Y897382D03*
Y904075D03*
Y907422D03*
Y914114D03*
Y920807D03*
Y927500D03*
Y934193D03*
Y940886D03*
Y950925D03*
Y944233D03*
Y964311D03*
Y957618D03*
Y971004D03*
X1156209Y960965D03*
X1164268Y977697D03*
Y984390D03*
Y1001122D03*
Y997776D03*
Y991083D03*
Y1031240D03*
Y1037933D03*
Y1044626D03*
Y1058012D03*
Y1051319D03*
Y1074744D03*
Y1068051D03*
Y1064705D03*
Y1081437D03*
Y1088130D03*
Y1098170D03*
Y1104862D03*
Y1091477D03*
Y1111555D03*
Y1118248D03*
Y1134981D03*
Y1124941D03*
Y1128288D03*
Y1148366D03*
Y1141674D03*
Y1155059D03*
Y1161752D03*
Y1165099D03*
Y1171792D03*
Y1178485D03*
Y1185177D03*
Y1191870D03*
Y1208603D03*
Y1198563D03*
Y1201910D03*
Y1215296D03*
Y1221988D03*
Y1228681D03*
Y1235374D03*
Y1238721D03*
Y1245414D03*
Y1252107D03*
X1184910Y756831D03*
X1180410Y776910D03*
X1184910Y763524D03*
X1184960Y770217D03*
X1180410Y783603D03*
Y790296D03*
Y800335D03*
Y807028D03*
Y793642D03*
Y813721D03*
Y820414D03*
Y837146D03*
Y830453D03*
Y827107D03*
Y843839D03*
Y850532D03*
Y857225D03*
Y863918D03*
Y873957D03*
Y880650D03*
Y867264D03*
Y887343D03*
Y894036D03*
Y910768D03*
Y904075D03*
Y900729D03*
Y924154D03*
Y917461D03*
Y930847D03*
Y940886D03*
Y937540D03*
Y947579D03*
Y954272D03*
Y960965D03*
Y967658D03*
Y974351D03*
Y981044D03*
Y987736D03*
Y994429D03*
Y1001122D03*
Y1027894D03*
Y1034587D03*
Y1041280D03*
Y1047973D03*
Y1054666D03*
Y1061359D03*
Y1071398D03*
Y1064705D03*
Y1078091D03*
Y1088130D03*
Y1084784D03*
Y1094823D03*
Y1101516D03*
Y1108209D03*
Y1114902D03*
Y1131634D03*
Y1124941D03*
Y1121595D03*
Y1138327D03*
Y1145020D03*
Y1151713D03*
Y1161752D03*
Y1158406D03*
Y1168445D03*
Y1175138D03*
Y1181831D03*
Y1188524D03*
Y1205256D03*
Y1198563D03*
Y1195217D03*
Y1211949D03*
Y1218642D03*
Y1225335D03*
Y1235374D03*
Y1232028D03*
Y1242067D03*
Y1248760D03*
X1189469Y760177D03*
Y756831D03*
X1198519Y763765D03*
X1188805Y766870D03*
X1189419Y763524D03*
X1194403Y1556953D03*
X1199678Y1559353D03*
X1194954D03*
X1199127Y1556953D03*
X1196127Y1577997D03*
Y1581397D03*
X1196039Y1657292D03*
X1199439D03*
X1214600Y759562D03*
X1205448Y769914D03*
X1214661Y766870D03*
X1214611Y763524D03*
X1214841Y772277D03*
X1210111Y960965D03*
X1203682D03*
X1208576Y1556953D03*
X1204403Y1559353D03*
X1209127D03*
X1203852Y1556953D03*
X1213300D03*
X1213851Y1559353D03*
X1200851Y1577997D03*
X1205576D03*
X1210300D03*
X1215025D03*
X1200851Y1581397D03*
X1205576D03*
X1210300D03*
X1215025D03*
X1208099Y1657292D03*
X1211499D03*
X1218025Y1556953D03*
X1218576Y1559353D03*
X1227474Y1556953D03*
X1228025Y1559353D03*
X1222749Y1556953D03*
X1223300Y1559353D03*
X1219749Y1577997D03*
X1224474D03*
X1229198D03*
X1219749Y1581397D03*
X1224474D03*
X1229198D03*
X1220159Y1657292D03*
X1223559D03*
X1241647Y1556953D03*
X1242198Y1559353D03*
X1232198Y1556953D03*
X1232749Y1559353D03*
X1236922Y1556953D03*
X1237473Y1559353D03*
X1243372Y1577997D03*
X1233923D03*
X1238647D03*
X1243372Y1581397D03*
X1233923D03*
X1238647D03*
X1232219Y1657292D03*
X1244279D03*
X1235619D03*
X1251647Y1559353D03*
X1251096Y1556953D03*
X1255820D03*
X1256371Y1559353D03*
X1246371Y1556953D03*
X1246922Y1559353D03*
X1248096Y1577997D03*
X1252820D03*
X1257544D03*
X1248096Y1581397D03*
X1252820D03*
X1257544D03*
X1256339Y1657292D03*
X1247679D03*
X1259739D03*
X1265269Y1556953D03*
X1265820Y1559353D03*
X1261096D03*
X1260545Y1556953D03*
X1262269Y1577997D03*
X1266993D03*
X1262269Y1581397D03*
X1266993D03*
X1268399Y1657292D03*
X1271799D03*
X1280459D03*
X1283859D03*
X1292519D03*
X1304579D03*
X1295919D03*
X1316639D03*
X1320039D03*
X1307979D03*
X1332465Y1559353D03*
X1331914Y1556953D03*
X1322465D03*
X1327189D03*
X1323016Y1559353D03*
X1327740D03*
X1324189Y1577997D03*
X1328913D03*
X1333638D03*
X1324189Y1581397D03*
X1328913D03*
X1333638D03*
X1328699Y1657292D03*
X1332099D03*
X1346087Y1556953D03*
X1346638Y1559353D03*
X1336638Y1556953D03*
X1337189Y1559353D03*
X1341913D03*
X1341362Y1556953D03*
X1338362Y1577997D03*
X1343087D03*
X1347811D03*
X1338362Y1581397D03*
X1343087D03*
X1347811D03*
X1340759Y1657292D03*
X1344159D03*
X1360260Y1556953D03*
X1360811Y1559353D03*
X1350811Y1556953D03*
X1351362Y1559353D03*
X1356087D03*
X1355536Y1556953D03*
X1352536Y1577997D03*
X1357260D03*
X1361985D03*
X1352536Y1581397D03*
X1357260D03*
X1361985D03*
X1352819Y1657292D03*
X1356219D03*
X1369709Y1556953D03*
X1370260Y1559353D03*
X1379158Y1556953D03*
X1374984Y1559353D03*
X1374433Y1556953D03*
X1365535Y1559353D03*
X1364984Y1556953D03*
X1371434Y1577997D03*
X1376158D03*
X1366709D03*
X1371434Y1581397D03*
X1376158D03*
X1366709D03*
X1364879Y1657292D03*
X1376939D03*
X1368279D03*
X1388607Y1556953D03*
X1384433Y1559353D03*
X1383882Y1556953D03*
X1379709Y1559353D03*
X1393882D03*
X1389158D03*
X1393331Y1556953D03*
X1380882Y1577997D03*
X1385606D03*
X1390331D03*
X1380882Y1581397D03*
X1385606D03*
X1390331D03*
X1380339Y1657292D03*
X1395055Y1577997D03*
Y1581397D03*
X1458577Y1556953D03*
X1468577Y1559353D03*
X1463852D03*
X1459128D03*
X1463301Y1556953D03*
X1468026D03*
X1460301Y1577997D03*
X1465025D03*
X1460301Y1581397D03*
X1465025D03*
X1460213Y1657292D03*
X1463613D03*
X1482199Y1556953D03*
X1482750Y1559353D03*
X1472750Y1556953D03*
X1473301Y1559353D03*
X1477474Y1556953D03*
X1478025Y1559353D03*
X1469750Y1577997D03*
X1474474D03*
X1479199D03*
X1483923D03*
X1469750Y1581397D03*
X1474474D03*
X1479199D03*
X1483923D03*
X1472273Y1657292D03*
X1475673D03*
X1496372Y1556953D03*
X1491648D03*
X1496923Y1559353D03*
X1492199D03*
X1486923Y1556953D03*
X1487474Y1559353D03*
X1488648Y1577997D03*
X1493372D03*
X1498097D03*
X1488648Y1581397D03*
X1493372D03*
X1498097D03*
X1484333Y1657292D03*
X1496393D03*
X1487733D03*
X1505821Y1556953D03*
X1506372Y1559353D03*
X1511096D03*
X1510545Y1556953D03*
X1501096D03*
X1501647Y1559353D03*
X1507546Y1577997D03*
X1512270D03*
X1502821D03*
X1507546Y1581397D03*
X1512270D03*
X1502821D03*
X1508453Y1657292D03*
X1499793D03*
X1511853D03*
X1515821Y1559353D03*
X1515270Y1556953D03*
X1519994D03*
X1520545Y1559353D03*
X1525270D03*
X1524719Y1556953D03*
X1516994Y1577997D03*
X1521718D03*
X1526443D03*
X1516994Y1581397D03*
X1521718D03*
X1526443D03*
X1520513Y1657292D03*
X1523913D03*
X1529443Y1556953D03*
X1529994Y1559353D03*
X1531167Y1577997D03*
Y1581397D03*
X1532573Y1657292D03*
X1535973D03*
X1544633D03*
X1556693D03*
X1548033D03*
X1568753D03*
X1560093D03*
X1572153D03*
X1586639Y1556953D03*
X1587190Y1559353D03*
X1588363Y1577997D03*
Y1581397D03*
X1580813Y1657292D03*
X1584213D03*
X1600812Y1556953D03*
X1596639Y1559353D03*
X1596088Y1556953D03*
X1601363Y1559353D03*
X1591363Y1556953D03*
X1591914Y1559353D03*
X1593087Y1577997D03*
X1597812D03*
X1602536D03*
X1593087Y1581397D03*
X1597812D03*
X1602536D03*
X1592873Y1657292D03*
X1596273D03*
X1610261Y1556953D03*
X1610812Y1559353D03*
X1606087D03*
X1605536Y1556953D03*
X1614985D03*
X1615536Y1559353D03*
X1607261Y1577997D03*
X1611985D03*
X1616710D03*
X1607261Y1581397D03*
X1611985D03*
X1616710D03*
X1604933Y1657292D03*
X1616993D03*
X1608333D03*
X1618996Y760177D03*
Y756831D03*
X1618946Y763524D03*
X1624434Y1556953D03*
X1624985Y1559353D03*
X1620261D03*
X1619710Y1556953D03*
X1629709Y1559353D03*
X1629158Y1556953D03*
X1621434Y1577997D03*
X1626159D03*
X1630883D03*
X1621434Y1581397D03*
X1626159D03*
X1630883D03*
X1629053Y1657292D03*
X1620393D03*
X1632453D03*
X1644138Y756831D03*
Y763524D03*
X1644188Y770217D03*
X1639638Y960965D03*
X1634138D03*
X1633883Y1556953D03*
X1634434Y1559353D03*
X1643332Y1556953D03*
X1643883Y1559353D03*
X1639158D03*
X1638607Y1556953D03*
X1635608Y1577997D03*
X1640332D03*
X1645056D03*
X1635608Y1581397D03*
X1640332D03*
X1645056D03*
X1641113Y1657292D03*
X1644513D03*
X1648697Y760177D03*
Y756831D03*
X1657747Y763765D03*
X1648647Y766870D03*
Y763524D03*
X1653197Y780256D03*
Y786949D03*
Y803681D03*
Y793642D03*
Y796988D03*
Y817067D03*
Y810374D03*
Y823760D03*
Y830453D03*
Y833799D03*
Y840492D03*
Y847185D03*
Y853878D03*
Y860571D03*
Y877303D03*
Y867264D03*
Y870610D03*
Y883996D03*
Y890689D03*
Y897382D03*
Y904075D03*
Y907422D03*
Y914114D03*
Y920807D03*
Y927500D03*
Y934193D03*
Y940886D03*
Y950925D03*
Y944233D03*
Y964311D03*
Y957618D03*
Y971004D03*
Y977697D03*
Y984390D03*
Y1001122D03*
Y997776D03*
Y991083D03*
Y1031240D03*
Y1037933D03*
Y1044626D03*
Y1058012D03*
Y1051319D03*
Y1074744D03*
Y1068051D03*
Y1064705D03*
Y1081437D03*
Y1088130D03*
Y1098170D03*
Y1104862D03*
Y1091477D03*
Y1111555D03*
Y1118248D03*
Y1134981D03*
Y1124941D03*
Y1128288D03*
Y1148366D03*
Y1141674D03*
Y1155059D03*
Y1161752D03*
Y1165099D03*
Y1171792D03*
Y1178485D03*
Y1185177D03*
Y1191870D03*
Y1208603D03*
Y1198563D03*
Y1201910D03*
Y1215296D03*
Y1221988D03*
Y1228681D03*
Y1235374D03*
Y1238721D03*
Y1245414D03*
Y1252107D03*
X1652781Y1556953D03*
X1648607Y1559353D03*
X1648056Y1556953D03*
X1658056Y1559353D03*
X1653332D03*
X1657505Y1556953D03*
X1649780Y1577997D03*
X1654505D03*
X1659229D03*
X1649780Y1581397D03*
X1654505D03*
X1659229D03*
X1673839Y756831D03*
X1669339Y776910D03*
X1673839Y763524D03*
X1673889Y770217D03*
X1669339Y783603D03*
Y790296D03*
Y800335D03*
Y807028D03*
Y793642D03*
Y813721D03*
Y820414D03*
Y837146D03*
Y830453D03*
Y827107D03*
Y843839D03*
Y850532D03*
Y857225D03*
Y863918D03*
Y873957D03*
Y880650D03*
Y867264D03*
Y887343D03*
Y894036D03*
Y910768D03*
Y904075D03*
Y900729D03*
Y924154D03*
Y917461D03*
Y930847D03*
Y940886D03*
Y937540D03*
Y947579D03*
Y954272D03*
Y960965D03*
Y967658D03*
Y974351D03*
Y981044D03*
Y987736D03*
Y994429D03*
Y1001122D03*
Y1027894D03*
Y1034587D03*
Y1041280D03*
Y1047973D03*
Y1054666D03*
Y1061359D03*
Y1071398D03*
Y1064705D03*
Y1078091D03*
Y1088130D03*
Y1084784D03*
Y1094823D03*
Y1101516D03*
Y1108209D03*
Y1114902D03*
Y1131634D03*
Y1124941D03*
Y1121595D03*
Y1138327D03*
Y1145020D03*
Y1151713D03*
Y1161752D03*
Y1158406D03*
Y1168445D03*
Y1175138D03*
Y1181831D03*
Y1188524D03*
Y1205256D03*
Y1198563D03*
Y1195217D03*
Y1211949D03*
Y1218642D03*
Y1225335D03*
Y1235374D03*
Y1232028D03*
Y1242067D03*
Y1248760D03*
X1678398Y760177D03*
Y756831D03*
X1687448Y763765D03*
X1678348Y766870D03*
Y763524D03*
X1682898Y1068051D03*
Y1064705D03*
X1703540Y756831D03*
X1703590Y766870D03*
X1703540Y763524D03*
X1703590Y770217D03*
X1699040Y960965D03*
X1693540D03*
X1708099Y760177D03*
Y756831D03*
X1717149Y763765D03*
X1708049Y763524D03*
X1712599Y1068051D03*
Y1064705D03*
X1736986Y109723D03*
Y112223D03*
X1733241Y756831D03*
X1733727Y766870D03*
X1733241Y763524D03*
X1733291Y770217D03*
X1728741Y960965D03*
X1723241D03*
X1740529Y112223D03*
Y109723D03*
X1744072Y112223D03*
Y109723D03*
X1747616Y112223D03*
Y109723D03*
X1737800Y756831D03*
Y760177D03*
X1746850Y763765D03*
X1737750Y763524D03*
X1742300Y780256D03*
Y786949D03*
Y803681D03*
Y793642D03*
Y796988D03*
Y817067D03*
Y810374D03*
Y823760D03*
Y830453D03*
Y833799D03*
Y840492D03*
Y847185D03*
Y853878D03*
Y860571D03*
Y877303D03*
Y867264D03*
Y870610D03*
Y883996D03*
Y890689D03*
Y897382D03*
Y904075D03*
Y907422D03*
Y914114D03*
Y920807D03*
Y927500D03*
Y934193D03*
Y940886D03*
Y950925D03*
Y944233D03*
Y964311D03*
Y957618D03*
Y971004D03*
Y977697D03*
Y984390D03*
Y1001122D03*
Y997776D03*
Y991083D03*
Y1031240D03*
Y1037933D03*
Y1044626D03*
Y1058012D03*
Y1051319D03*
Y1074744D03*
Y1068051D03*
Y1064705D03*
Y1081437D03*
Y1088130D03*
Y1098170D03*
Y1104862D03*
Y1091477D03*
Y1111555D03*
Y1118248D03*
Y1134981D03*
Y1124941D03*
Y1128288D03*
Y1148366D03*
Y1141674D03*
Y1155059D03*
Y1161752D03*
Y1165099D03*
Y1171792D03*
Y1178485D03*
Y1185177D03*
Y1191870D03*
Y1208603D03*
Y1198563D03*
Y1201910D03*
Y1215296D03*
Y1221988D03*
Y1228681D03*
Y1235374D03*
Y1238721D03*
Y1245414D03*
Y1252107D03*
X1762942Y756831D03*
X1762992Y766870D03*
X1758442Y776910D03*
X1762942Y763524D03*
X1762992Y770217D03*
X1758442Y783603D03*
Y790296D03*
Y800335D03*
Y807028D03*
Y793642D03*
Y813721D03*
Y820414D03*
Y837146D03*
Y830453D03*
Y827107D03*
Y843839D03*
Y850532D03*
Y857225D03*
Y863918D03*
Y873957D03*
Y880650D03*
Y867264D03*
Y887343D03*
Y894036D03*
Y910768D03*
Y904075D03*
Y900729D03*
Y924154D03*
Y917461D03*
Y930847D03*
Y940886D03*
Y937540D03*
Y947579D03*
Y954272D03*
Y960965D03*
Y967658D03*
Y974351D03*
Y981044D03*
Y987736D03*
Y994429D03*
Y1001122D03*
Y1027894D03*
Y1034587D03*
Y1041280D03*
Y1047973D03*
Y1054666D03*
Y1061359D03*
Y1071398D03*
Y1064705D03*
Y1078091D03*
Y1088130D03*
Y1084784D03*
Y1094823D03*
Y1101516D03*
Y1108209D03*
Y1114902D03*
Y1131634D03*
Y1124941D03*
Y1121595D03*
Y1138327D03*
Y1145020D03*
Y1151713D03*
Y1161752D03*
Y1158406D03*
Y1168445D03*
Y1175138D03*
Y1181831D03*
Y1188524D03*
Y1205256D03*
Y1198563D03*
Y1195217D03*
Y1211949D03*
Y1218642D03*
Y1225335D03*
Y1235374D03*
Y1232028D03*
Y1242067D03*
Y1248760D03*
X1767500Y760177D03*
Y756831D03*
X1767450Y763524D03*
X1772000Y780256D03*
Y786949D03*
Y803681D03*
Y793642D03*
Y796988D03*
Y817067D03*
Y810374D03*
Y823760D03*
Y830453D03*
Y833799D03*
Y840492D03*
Y847185D03*
Y853878D03*
Y860571D03*
Y877303D03*
Y867264D03*
Y870610D03*
Y883996D03*
Y890689D03*
Y897382D03*
Y904075D03*
Y907422D03*
Y914114D03*
Y920807D03*
Y927500D03*
Y934193D03*
Y940886D03*
Y950925D03*
Y944233D03*
Y964311D03*
Y957618D03*
Y971004D03*
Y977697D03*
Y984390D03*
Y1001122D03*
Y997776D03*
Y991083D03*
Y1031240D03*
Y1037933D03*
Y1044626D03*
Y1058012D03*
Y1051319D03*
Y1074744D03*
Y1068051D03*
Y1064705D03*
Y1081437D03*
Y1088130D03*
Y1098170D03*
Y1104862D03*
Y1091477D03*
Y1111555D03*
Y1118248D03*
Y1134981D03*
Y1124941D03*
Y1128288D03*
Y1148366D03*
Y1141674D03*
Y1155059D03*
Y1161752D03*
Y1165099D03*
Y1171792D03*
Y1178485D03*
Y1185177D03*
Y1191870D03*
Y1208603D03*
Y1198563D03*
Y1201910D03*
Y1215296D03*
Y1221988D03*
Y1228681D03*
Y1235374D03*
Y1238721D03*
Y1245414D03*
Y1252107D03*
X1792642Y756831D03*
X1788142Y776910D03*
X1792642Y763524D03*
X1792692Y770217D03*
X1788142Y783603D03*
Y790296D03*
Y800335D03*
Y807028D03*
Y793642D03*
Y813721D03*
Y820414D03*
Y837146D03*
Y830453D03*
Y827107D03*
Y843839D03*
Y850532D03*
Y857225D03*
Y863918D03*
Y873957D03*
Y880650D03*
Y867264D03*
Y887343D03*
Y894036D03*
Y910768D03*
Y904075D03*
Y900729D03*
Y924154D03*
Y917461D03*
Y930847D03*
Y940886D03*
Y937540D03*
Y947579D03*
Y954272D03*
Y960965D03*
Y967658D03*
Y974351D03*
Y981044D03*
Y987736D03*
Y994429D03*
Y1001122D03*
Y1027894D03*
Y1034587D03*
Y1041280D03*
Y1047973D03*
Y1054666D03*
Y1061359D03*
Y1071398D03*
Y1064705D03*
Y1078091D03*
Y1088130D03*
Y1084784D03*
Y1094823D03*
Y1101516D03*
Y1108209D03*
Y1114902D03*
Y1131634D03*
Y1124941D03*
Y1121595D03*
Y1138327D03*
Y1145020D03*
Y1151713D03*
Y1161752D03*
Y1158406D03*
Y1168445D03*
Y1175138D03*
Y1181831D03*
Y1188524D03*
Y1205256D03*
Y1198563D03*
Y1195217D03*
Y1211949D03*
Y1218642D03*
Y1225335D03*
Y1235374D03*
Y1232028D03*
Y1242067D03*
Y1248760D03*
G54D42*
X373673Y-28871D03*
Y-18871D03*
D03*
Y-8871D03*
X398673Y-28871D03*
Y-18871D03*
D03*
Y-8871D03*
X718093Y-28871D03*
Y-18871D03*
D03*
Y-8871D03*
X743093Y-28871D03*
Y-18871D03*
D03*
Y-8871D03*
X825152Y-35011D03*
Y-25011D03*
Y-15011D03*
Y-25011D03*
Y-15011D03*
Y-5011D03*
D03*
Y4989D03*
Y14989D03*
D03*
Y4989D03*
Y24989D03*
X850152Y-35011D03*
Y-25011D03*
Y-15011D03*
Y-25011D03*
Y-15011D03*
Y-5011D03*
D03*
Y4989D03*
Y14989D03*
D03*
Y4989D03*
Y24989D03*
X1169572Y-35011D03*
Y-15011D03*
Y-25011D03*
D03*
Y-15011D03*
Y-5011D03*
D03*
Y4989D03*
Y14989D03*
Y4989D03*
Y14989D03*
Y24989D03*
X1194572Y-35011D03*
Y-15011D03*
Y-25011D03*
D03*
Y-15011D03*
Y-5011D03*
D03*
Y4989D03*
Y14989D03*
Y4989D03*
Y14989D03*
Y24989D03*
X1228672Y-35011D03*
Y-25011D03*
Y-15011D03*
Y-25011D03*
Y-15011D03*
Y-5011D03*
D03*
Y4989D03*
Y14989D03*
D03*
Y4989D03*
Y24989D03*
X1253672Y-35011D03*
Y-25011D03*
Y-15011D03*
Y-25011D03*
Y-15011D03*
Y-5011D03*
D03*
Y4989D03*
Y14989D03*
D03*
Y4989D03*
Y24989D03*
X1428431Y-35011D03*
Y-15011D03*
Y-25011D03*
D03*
Y-15011D03*
Y-5011D03*
D03*
Y4989D03*
Y14989D03*
Y4989D03*
Y14989D03*
Y24989D03*
X1453431Y-35011D03*
Y-15011D03*
Y-25011D03*
D03*
Y-15011D03*
Y-5011D03*
D03*
Y4989D03*
Y14989D03*
Y4989D03*
Y14989D03*
Y24989D03*
X1521966Y-29212D03*
D03*
Y-39212D03*
Y-19212D03*
X1546966Y-29212D03*
D03*
Y-39212D03*
Y-19212D03*
X1721725Y-29212D03*
Y-39212D03*
Y-29212D03*
Y-19212D03*
X1746725Y-29212D03*
Y-39212D03*
Y-29212D03*
Y-19212D03*
G54D53*
X793879Y194881D03*
X789942Y204724D03*
X793879Y214567D03*
X805690Y188976D03*
Y220472D03*
X817501Y194881D03*
X821438Y204724D03*
X817501Y214567D03*
X828390Y1420331D03*
X841240Y1407481D03*
X832154Y1411245D03*
Y1429417D03*
X841240Y1433181D03*
X850326Y1411245D03*
Y1429417D03*
X854090Y1420331D03*
X1007154Y1411245D03*
X1003390Y1420331D03*
X1007154Y1429417D03*
X1016240Y1407481D03*
Y1433181D03*
X1025326Y1411245D03*
Y1429417D03*
X1029090Y1420331D03*
X1045848Y194881D03*
X1041911Y204724D03*
X1045848Y214567D03*
X1057659Y188976D03*
Y220472D03*
X1069470Y194881D03*
X1073407Y204724D03*
X1069470Y214567D03*
G54D10*
X3001Y61178D03*
Y127178D03*
Y149178D03*
Y171178D03*
Y193178D03*
Y215178D03*
Y237178D03*
Y259178D03*
Y281178D03*
Y303178D03*
X10875Y323721D03*
Y345721D03*
Y367721D03*
Y389721D03*
Y411721D03*
Y433721D03*
Y455721D03*
Y477721D03*
Y499721D03*
Y521721D03*
X20587Y523970D03*
X16342Y516951D03*
X16512Y533155D03*
X10875Y543721D03*
Y565721D03*
Y587721D03*
Y609721D03*
Y653721D03*
Y675721D03*
Y697721D03*
Y719721D03*
Y741721D03*
Y763721D03*
Y785721D03*
Y807721D03*
Y829721D03*
Y851721D03*
Y873721D03*
Y895721D03*
Y917721D03*
Y939721D03*
Y961721D03*
Y983721D03*
Y1005721D03*
Y1027721D03*
Y1049721D03*
Y1071721D03*
Y1093721D03*
Y1115721D03*
Y1137721D03*
Y1159721D03*
Y1181721D03*
Y1203721D03*
Y1225721D03*
Y1247721D03*
Y1269721D03*
Y1291721D03*
Y1445721D03*
Y1467721D03*
Y1489721D03*
Y1511721D03*
Y1533721D03*
Y1555721D03*
Y1577721D03*
X33184Y523285D03*
X36402Y528675D03*
X33257Y540370D03*
X26887Y541805D03*
X35133Y1603396D03*
X35167Y1610521D03*
X28592Y1617961D03*
X35233Y1623196D03*
X28592Y1639961D03*
Y1661961D03*
Y1683961D03*
X44600Y280357D03*
X50500Y311100D03*
X47602Y1622414D03*
X51333Y1640996D03*
X54584Y8335D03*
Y30335D03*
X58633Y1641388D03*
X85133Y1616396D03*
Y1620896D03*
Y1625396D03*
X85167Y1629905D03*
X101939Y1657742D03*
Y1662728D03*
X120891Y521216D03*
X144610Y429560D03*
X163113Y1486190D03*
X160513Y1479500D03*
Y1484280D03*
X165713Y1479500D03*
Y1484280D03*
X160513Y1501300D03*
Y1506080D03*
X165713D03*
X163113Y1507982D03*
X165713Y1501300D03*
X173488Y1510800D03*
Y1514420D03*
Y1518040D03*
X224055Y127146D03*
X262886Y147391D03*
X274201Y579478D03*
X280621Y1486682D03*
X291175Y1486190D03*
X288575Y1484280D03*
Y1479500D03*
X280621Y1500082D03*
X288575Y1506080D03*
Y1501300D03*
X291175Y1507990D03*
X301747Y121469D03*
Y127469D03*
Y124469D03*
X293775Y1484280D03*
Y1479500D03*
Y1506080D03*
Y1501300D03*
X304606Y1546333D03*
X297323Y1659772D03*
X311754Y121472D03*
Y124472D03*
Y127472D03*
X311476Y1552567D03*
X307255Y1649750D03*
X326475Y182855D03*
X349676Y276708D03*
X349695Y286712D03*
X380181Y236674D03*
X390461Y270694D03*
Y267694D03*
Y275194D03*
X387184Y494382D03*
X390082Y1549178D03*
X404743Y494451D03*
X408683Y1486682D03*
Y1500082D03*
X425555Y92014D03*
Y82014D03*
X412715Y254165D03*
X423730Y249570D03*
X412715Y262165D03*
Y270165D03*
X418543Y494374D03*
X418918Y1006025D03*
Y1013505D03*
Y1009765D03*
Y1024726D03*
Y1020986D03*
Y1028466D03*
Y1017245D03*
X415318Y1032206D03*
X424686Y1484280D03*
Y1479500D03*
Y1506080D03*
Y1501300D03*
X431299Y204145D03*
X432343Y494297D03*
X427286Y1486190D03*
X429886Y1484280D03*
Y1479500D03*
Y1506080D03*
Y1501300D03*
X427286Y1507990D03*
X438732Y1546977D03*
X444090Y116007D03*
X443400Y247880D03*
X448852Y283318D03*
X441159Y1055141D03*
X447587Y1552567D03*
X468228Y70016D03*
X457931Y212703D03*
X465699Y282833D03*
X469323Y306273D03*
X462093Y310123D03*
X467943Y311563D03*
X465153Y310123D03*
X467893Y308643D03*
X458873Y310173D03*
X455813D03*
X462365Y1006025D03*
Y1009765D03*
Y1013505D03*
Y1020986D03*
Y1028466D03*
Y1024726D03*
Y1017245D03*
Y1032206D03*
X462500Y1733500D03*
X480323Y291023D03*
X474691Y306073D03*
X471743Y304923D03*
X473643Y308683D03*
X471003Y311563D03*
X470953Y308643D03*
X484063Y313956D03*
X498776Y209285D03*
Y213285D03*
X500269Y225071D03*
X488908Y242754D03*
X503161Y149895D03*
X514418Y141171D03*
X515151Y220166D03*
X501718Y240558D03*
X508723Y280721D03*
X510223Y289035D03*
X507698D03*
Y297090D03*
X510223D03*
X507698Y305145D03*
X510223D03*
X510606Y314124D03*
X508081D03*
X523831Y95445D03*
Y102931D03*
X519579Y207435D03*
X530418Y141171D03*
X538567Y294777D03*
X542813Y319173D03*
X544794Y1486682D03*
Y1500082D03*
X549800Y147000D03*
X553300Y164500D03*
X556811Y152742D03*
X552699Y291833D03*
X556323Y315273D03*
X558743Y313923D03*
X545873Y319173D03*
X549093Y319123D03*
X558003Y320563D03*
X554943D03*
X552153Y319123D03*
X554893Y317643D03*
X557953D03*
X555348Y1486190D03*
X552748Y1484280D03*
Y1479500D03*
X557948Y1484280D03*
Y1479500D03*
X552748Y1506080D03*
Y1501300D03*
X557948Y1506080D03*
Y1501300D03*
X555348Y1507990D03*
X568472Y149226D03*
X563951Y160644D03*
X567323Y300023D03*
X561691Y315073D03*
X560643Y317683D03*
X568573Y321993D03*
X568779Y1546333D03*
X585685Y178125D03*
X578172Y231393D03*
X587140Y257630D03*
X575524Y261171D03*
X575649Y1552567D03*
X599678Y175534D03*
X595723Y289721D03*
X594698Y298035D03*
X597223D03*
X594698Y314145D03*
X597223D03*
X594698Y306090D03*
X597223D03*
Y322200D03*
X594698D03*
X600520Y401728D03*
X616654Y1382864D03*
X633805Y302289D03*
X642816Y574185D03*
X634529Y674890D03*
X640129D03*
X643649Y674781D03*
X649936Y574185D03*
X660062Y672761D03*
X654676Y674806D03*
X654005Y1548999D03*
X670000Y465844D03*
X672856Y1486682D03*
Y1500082D03*
X719195Y172873D03*
Y177865D03*
X714203Y172873D03*
Y177865D03*
X719195Y196373D03*
X714203D03*
X719195Y184873D03*
Y189865D03*
X714203Y184873D03*
Y189865D03*
Y208207D03*
X719195D03*
Y201365D03*
X714203D03*
Y213199D03*
X719195D03*
X744911Y166887D03*
X749261Y1628208D03*
X754286Y266319D03*
X754291Y269322D03*
X756692Y278942D03*
X765285Y276374D03*
X761510Y1638434D03*
X762030Y1668583D03*
X755408Y1672381D03*
X757557Y1684444D03*
X773457Y249792D03*
X774485Y286879D03*
X791341Y264848D03*
X784261Y1482049D03*
Y1534963D03*
X784277Y1528191D03*
X808469Y1356745D03*
Y1359245D03*
X811272Y1382752D03*
X811767Y1388154D03*
X836163Y279355D03*
X856397Y344669D03*
X865132Y333317D03*
X860152D03*
X861377Y344669D03*
X869406Y753541D03*
X874617Y1084657D03*
X877817D03*
Y1088057D03*
X874617D03*
X881217Y1084657D03*
Y1088057D03*
X874617Y1100957D03*
X877817D03*
Y1097557D03*
X874617D03*
X881217Y1100957D03*
Y1097557D03*
X889057Y1053133D03*
X897754Y1156119D03*
X916268Y277859D03*
X928224Y264072D03*
X942763Y272340D03*
X944820Y1156119D03*
X957421Y157699D03*
X960421D03*
X962243Y179917D03*
X947748Y1146553D03*
X964743Y179917D03*
X963985Y177154D03*
X965520Y1567570D03*
X962520D03*
X968520D03*
X965520Y1582570D03*
X962520D03*
Y1579570D03*
X965520D03*
Y1576570D03*
X962520D03*
X965520Y1573570D03*
X962520D03*
Y1570570D03*
X965520D03*
X968520Y1582570D03*
Y1579570D03*
Y1576570D03*
Y1573570D03*
Y1570570D03*
X965520Y1588570D03*
X962520D03*
Y1585570D03*
X965520D03*
X968520Y1588570D03*
Y1585570D03*
X991553Y216809D03*
X988460Y354725D03*
X992233Y373679D03*
X986356Y1087508D03*
X983156D03*
Y1084108D03*
X986356D03*
X989556Y1087508D03*
Y1084108D03*
X986356Y1097008D03*
X983156D03*
Y1100408D03*
X986356D03*
X989556Y1097008D03*
Y1100408D03*
X1002736Y157943D03*
X999736D03*
X993306Y174953D03*
X993206Y178053D03*
X1006436Y176843D03*
X999916Y184548D03*
X996416D03*
X992506Y184553D03*
X993460Y354725D03*
X998460D03*
X997488Y370287D03*
X994160Y1567710D03*
X997160D03*
X1000160D03*
X994160Y1582710D03*
X997160D03*
Y1579710D03*
X994160D03*
X997160Y1570710D03*
X994160D03*
Y1573710D03*
X997160D03*
X994160Y1576710D03*
X997160D03*
X1000160Y1582710D03*
Y1579710D03*
Y1570710D03*
Y1573710D03*
Y1576710D03*
X994160Y1588710D03*
X997160D03*
Y1585710D03*
X994160D03*
X1000160Y1588710D03*
Y1585710D03*
X1021899Y61590D03*
Y127590D03*
X1011358Y195324D03*
X1008068Y198387D03*
X1019936Y207333D03*
Y210463D03*
X1013306Y528942D03*
X1032354Y538201D03*
X1022686D03*
X1027520Y552724D03*
X1025750Y1567710D03*
X1031750D03*
X1028750D03*
X1025750Y1576710D03*
Y1573710D03*
Y1570710D03*
Y1579710D03*
Y1582710D03*
X1028750Y1576710D03*
Y1573710D03*
Y1570710D03*
Y1579710D03*
Y1582710D03*
X1031750Y1576710D03*
Y1573710D03*
Y1570710D03*
Y1579710D03*
Y1582710D03*
X1025750Y1585710D03*
Y1588710D03*
X1028750Y1585710D03*
Y1588710D03*
X1031750Y1585710D03*
Y1588710D03*
X1059055Y492537D03*
X1057219Y1567883D03*
X1060219D03*
X1063219D03*
X1066219D03*
X1057219Y1576883D03*
Y1573883D03*
Y1570883D03*
Y1579883D03*
Y1582883D03*
X1060219Y1576883D03*
Y1573883D03*
Y1570883D03*
Y1579883D03*
Y1582883D03*
X1063219Y1576883D03*
Y1573883D03*
Y1570883D03*
X1066219Y1576883D03*
Y1573883D03*
Y1570883D03*
Y1579883D03*
X1063219D03*
Y1582883D03*
X1066219D03*
X1057219Y1585883D03*
Y1588883D03*
X1060219Y1585883D03*
Y1588883D03*
X1066219Y1585883D03*
X1063219D03*
Y1588883D03*
X1066219D03*
X1094399Y1568043D03*
X1091399D03*
X1085399D03*
X1088399D03*
X1091399Y1580043D03*
X1094399D03*
Y1571043D03*
Y1574043D03*
Y1577043D03*
X1091399Y1571043D03*
Y1574043D03*
Y1577043D03*
X1088399Y1580043D03*
X1085399D03*
X1088399Y1571043D03*
X1085399D03*
Y1574043D03*
X1088399D03*
X1085399Y1577043D03*
X1088399D03*
X1094399Y1583043D03*
X1091399D03*
X1085399D03*
X1088399D03*
X1094399Y1589043D03*
X1091399D03*
Y1586043D03*
X1094399D03*
X1085399Y1589043D03*
X1088399D03*
Y1586043D03*
X1085399D03*
X1092030Y1715841D03*
Y1725991D03*
X1097399Y1568043D03*
Y1580043D03*
Y1571043D03*
Y1574043D03*
Y1577043D03*
Y1583043D03*
Y1589043D03*
Y1586043D03*
X1170986Y1519190D03*
X1168386Y1517280D03*
Y1512500D03*
Y1534300D03*
Y1539080D03*
X1170986Y1540990D03*
X1173586Y1517280D03*
Y1512500D03*
Y1534300D03*
Y1539080D03*
X1181361Y1543800D03*
Y1547420D03*
Y1551040D03*
X1172603Y1554561D03*
X1188472Y80165D03*
X1197980Y1688270D03*
X1213072Y1682899D03*
X1207770Y1717011D03*
Y1731011D03*
X1226094Y297066D03*
X1288494Y1519682D03*
Y1533082D03*
X1304705Y79807D03*
X1303266Y533713D03*
Y530413D03*
X1300200Y590600D03*
X1299048Y1519190D03*
X1296448Y1517280D03*
Y1512500D03*
X1301648Y1517280D03*
Y1512500D03*
X1296448Y1534300D03*
X1301648D03*
X1296448Y1539080D03*
X1301648D03*
X1299048Y1540990D03*
X1309185Y74748D03*
X1316266Y564514D03*
X1317266Y589522D03*
X1318300Y640000D03*
Y643000D03*
Y649000D03*
Y646000D03*
X1318363Y1411404D03*
X1312700Y1579596D03*
X1319349Y1585567D03*
X1330820Y525165D03*
X1330758Y521749D03*
X1330820Y518265D03*
X1330658Y538749D03*
X1330758Y528649D03*
X1330773Y531776D03*
X1330758Y535449D03*
X1329673Y552509D03*
X1332673D03*
X1326673Y544909D03*
X1329673Y545909D03*
Y549309D03*
X1330658Y542949D03*
X1332673Y545909D03*
Y549309D03*
X1329673Y558709D03*
Y555709D03*
X1332673D03*
X1325366Y589522D03*
X1321300Y643000D03*
Y640000D03*
Y649000D03*
Y646000D03*
X1326433Y1214334D03*
X1335260Y236594D03*
Y246594D03*
Y241594D03*
Y251594D03*
X1348611Y1212963D03*
Y1218463D03*
X1364239Y1207949D03*
X1391460Y1032205D03*
X1388918Y1687878D03*
X1382045Y1712038D03*
Y1708038D03*
X1384604Y1728318D03*
X1393179Y1733118D03*
X1404917Y109037D03*
X1395060Y1009764D03*
Y1006024D03*
Y1013504D03*
Y1020985D03*
Y1024725D03*
Y1028465D03*
Y1017244D03*
X1397955Y1582178D03*
X1405058Y1639607D03*
X1417301Y1055140D03*
X1416556Y1519682D03*
Y1533082D03*
X1418740Y1622902D03*
X1427973Y60409D03*
X1438507Y1006024D03*
Y1009764D03*
Y1013504D03*
Y1024725D03*
Y1020985D03*
Y1017244D03*
Y1028465D03*
Y1032205D03*
X1435160Y1519190D03*
X1432560Y1517280D03*
Y1512500D03*
X1437760Y1517280D03*
Y1512500D03*
X1432560Y1534300D03*
X1437760D03*
X1432560Y1539080D03*
X1437760D03*
X1435160Y1540990D03*
X1433979Y1655655D03*
X1441141Y53699D03*
X1448505Y1579725D03*
X1455461Y1585567D03*
X1528993Y4115D03*
Y26115D03*
X1534067Y1582178D03*
X1552668Y1519682D03*
Y1533082D03*
X1568176Y568423D03*
X1570676D03*
X1565676D03*
X1561376Y572258D03*
X1566010Y673210D03*
X1562730Y675180D03*
X1563222Y1519190D03*
X1560622Y1517280D03*
Y1512500D03*
X1565822Y1517280D03*
Y1512500D03*
X1560622Y1534300D03*
X1565822D03*
X1560622Y1539080D03*
X1565822D03*
X1563222Y1540990D03*
X1586291Y306746D03*
X1584160Y558973D03*
X1576653Y1579333D03*
X1583523Y1585567D03*
X1606535Y553297D03*
X1607369Y561330D03*
X1631889Y521480D03*
X1618884Y533388D03*
X1632798Y544564D03*
X1622391Y564169D03*
X1627242Y1436148D03*
X1627181Y1448016D03*
X1636929Y524690D03*
Y528190D03*
Y531690D03*
Y535190D03*
Y538690D03*
X1639868Y542444D03*
X1636783Y542604D03*
X1635798Y545564D03*
X1638798D03*
Y548964D03*
Y552164D03*
X1635798D03*
Y548964D03*
Y555364D03*
X1638798D03*
X1635798Y558364D03*
X1648029Y1718759D03*
Y1733909D03*
X1652525Y141762D03*
X1662129Y1582178D03*
X1673100Y126762D03*
X1676971Y1668582D03*
X1686154Y434160D03*
X1685298Y1451231D03*
X1680730Y1519682D03*
Y1533082D03*
X1688243Y1663802D03*
X1682724Y1717701D03*
X1704444Y407045D03*
X1707444D03*
X1697914Y427155D03*
X1698014Y424055D03*
X1701124Y433650D03*
X1697214Y433655D03*
X1704624Y433650D03*
X1704822Y1694243D03*
X1702985Y1700328D03*
X1711144Y425945D03*
X1722149Y1715265D03*
X1719149Y1703190D03*
X1722149Y1730415D03*
X1724263Y1681465D03*
X1752250Y303850D03*
X1749329Y1662956D03*
X1743329Y1668956D03*
X1743153Y1662956D03*
X1749329Y1674956D03*
X1743329D03*
X1754850Y303930D03*
X1755329Y1668956D03*
Y1662956D03*
Y1674956D03*
X1763463Y1691465D03*
X1758963Y1691565D03*
X1787390Y161834D03*
X1800040Y164393D03*
X1797719Y186610D03*
X1811668Y218900D03*
X1811606Y222513D03*
X1808429Y218837D03*
X1811606Y226438D03*
X1808367Y222450D03*
X1810479Y211850D03*
X1810509Y214660D03*
X1808260Y213232D03*
X1808367Y226375D03*
X1825111Y164393D03*
X1813079Y211850D03*
X1813109Y214660D03*
G54D17*
X18960Y1598181D03*
X440029Y240381D03*
X434420Y239930D03*
X934302Y578318D03*
X1769420Y19506D03*
X1777420D03*
Y24506D03*
G54D19*
X35852Y673010D03*
Y675510D03*
Y697322D03*
Y694822D03*
Y705728D03*
X50138Y425810D03*
X45182D03*
X45022Y449106D03*
X50002D03*
X48626Y552365D03*
X50880Y1412563D03*
X51358Y1647717D03*
Y1650217D03*
X52052Y1684027D03*
X67257Y69340D03*
X62930Y282866D03*
Y312866D03*
X62833Y409597D03*
X62808Y418675D03*
X65380Y427810D03*
X60393D03*
X58349Y1403331D03*
X54449Y1641722D03*
X61415Y1661695D03*
X61374Y1669931D03*
X70127Y1687362D03*
X73015Y28406D03*
X80101D03*
X73015Y40020D03*
X80101D03*
X78253Y75343D03*
X74773Y790297D03*
Y800336D03*
Y827108D03*
Y837147D03*
Y863919D03*
Y873958D03*
Y900730D03*
Y910769D03*
Y937541D03*
Y947580D03*
Y1084785D03*
Y1094824D03*
Y1121596D03*
Y1131635D03*
Y1158407D03*
Y1168446D03*
Y1195218D03*
Y1205257D03*
Y1232029D03*
Y1242068D03*
X71511Y1444379D03*
X69486Y1661828D03*
X69589Y1669878D03*
X78127Y1687362D03*
X74127D03*
X94274Y28406D03*
X87188D03*
Y40020D03*
X94274D03*
X89257Y69340D03*
X90150Y1314560D03*
X86127Y1687362D03*
X92192Y1713741D03*
X92596Y1737117D03*
X108448Y28406D03*
X101361D03*
Y40020D03*
X108448D03*
X100257Y75340D03*
X111257Y69340D03*
X104474Y790297D03*
Y800336D03*
Y827108D03*
Y837147D03*
Y863919D03*
Y873958D03*
Y900730D03*
Y910769D03*
Y937541D03*
Y947580D03*
Y1084785D03*
Y1094824D03*
Y1121596D03*
Y1131635D03*
Y1158407D03*
Y1168446D03*
Y1195218D03*
Y1205257D03*
Y1232029D03*
Y1242068D03*
X112355Y1426064D03*
Y1433564D03*
Y1441064D03*
X110144Y1597831D03*
X110996Y1592018D03*
X122621Y28406D03*
X115534D03*
Y40020D03*
X122621D03*
X122257Y75340D03*
X119855Y1426064D03*
X127355Y1433564D03*
Y1426064D03*
X119855Y1441064D03*
X127355D03*
X127374Y1572749D03*
X127392Y1575524D03*
X125768Y1568744D03*
X127246Y1585801D03*
X127264Y1588576D03*
X113496Y1592018D03*
X116353Y1646612D03*
X120353D03*
X124353D03*
X123278Y1658587D03*
X119353Y1695941D03*
X115353D03*
X125107Y1702666D03*
X124461Y1726116D03*
X114596Y1737117D03*
X129708Y28406D03*
Y40020D03*
X133257Y69343D03*
X141642Y491434D03*
X134174Y790297D03*
Y800336D03*
Y837147D03*
Y827108D03*
Y863919D03*
Y873958D03*
Y900730D03*
Y910769D03*
Y937541D03*
Y947580D03*
Y1084785D03*
Y1094824D03*
Y1121596D03*
Y1131635D03*
Y1158407D03*
Y1168446D03*
Y1195218D03*
Y1205257D03*
Y1232029D03*
Y1242068D03*
X128617Y1561022D03*
X129892Y1575524D03*
X129874Y1572749D03*
X128268Y1568744D03*
X129764Y1588576D03*
X129746Y1585801D03*
X128353Y1646612D03*
X140353D03*
X136048Y1666851D03*
X133548Y1677351D03*
X131353Y1696062D03*
X135353D03*
X139353D03*
X136596Y1737117D03*
X151400Y28406D03*
Y40020D03*
X144257Y75340D03*
X155253Y69343D03*
X148353Y1646612D03*
X144353D03*
X155328Y1670087D03*
X146928Y1685087D03*
X143353Y1696062D03*
X158487Y28406D03*
X165574D03*
X158487Y40020D03*
X165574D03*
X167461Y75340D03*
X163875Y790297D03*
Y800336D03*
Y837147D03*
Y827108D03*
Y863919D03*
Y873958D03*
Y900730D03*
Y910769D03*
Y937541D03*
Y947580D03*
Y1084785D03*
Y1094824D03*
Y1121596D03*
Y1131635D03*
Y1158407D03*
Y1168446D03*
Y1195218D03*
Y1205257D03*
Y1232029D03*
Y1242068D03*
X163421Y1425171D03*
Y1427671D03*
Y1430171D03*
Y1432671D03*
X158596Y1737117D03*
X172660Y28406D03*
X179747D03*
X172660Y40020D03*
X179747D03*
X178461Y69340D03*
X173960Y400560D03*
X172721Y1425171D03*
Y1430171D03*
Y1427671D03*
Y1432671D03*
X175351Y1462595D03*
X182051Y1452895D03*
X181760Y1731351D03*
X180596Y1737117D03*
X195534Y28406D03*
Y40020D03*
X189457Y75343D03*
X200461Y69340D03*
X193576Y790297D03*
Y800336D03*
Y827108D03*
Y837147D03*
Y863919D03*
Y873958D03*
Y900730D03*
Y910769D03*
Y937541D03*
Y947580D03*
Y1084785D03*
Y1094824D03*
Y1121596D03*
Y1131635D03*
Y1158407D03*
Y1168446D03*
Y1205257D03*
Y1195218D03*
Y1232029D03*
Y1242068D03*
X202151Y1462595D03*
X195451Y1472295D03*
X202621Y28406D03*
X216794D03*
X209708D03*
X202621Y40020D03*
X209708D03*
X216794D03*
X211595Y75340D03*
X208851Y1452895D03*
X202596Y1737117D03*
X223881Y28406D03*
X230967D03*
X223881Y40020D03*
X230967D03*
X222591Y69343D03*
X223277Y790297D03*
Y800336D03*
Y837147D03*
Y827108D03*
Y863919D03*
Y873958D03*
Y900730D03*
Y910769D03*
Y937541D03*
Y947580D03*
Y1084785D03*
Y1094824D03*
Y1121596D03*
Y1131635D03*
Y1158407D03*
Y1168446D03*
Y1205257D03*
Y1195218D03*
Y1232029D03*
Y1242068D03*
X228951Y1462595D03*
X222251Y1472295D03*
X224596Y1737117D03*
X233595Y75340D03*
X242215Y151788D03*
X234727Y584030D03*
Y571211D03*
X245815Y672746D03*
X244565Y677846D03*
Y680446D03*
Y675246D03*
X242543Y691115D03*
X239443Y691015D03*
X239843Y709715D03*
X235651Y1452895D03*
X252996Y28365D03*
X256496D03*
X249496D03*
X259996D03*
X252195Y144320D03*
X259475Y657245D03*
X259426Y644830D03*
X259475Y662845D03*
X250312Y670080D03*
Y667180D03*
X250835Y672692D03*
X253279Y672708D03*
X258379Y666644D03*
Y669601D03*
Y672708D03*
X255779D03*
X260979Y666644D03*
Y669601D03*
Y672708D03*
X247165Y677846D03*
Y680446D03*
Y675246D03*
X254448Y692050D03*
X255751Y1462595D03*
X249051Y1472295D03*
X266601Y586578D03*
X271571Y644796D03*
X264335Y657245D03*
X261905D03*
Y662845D03*
X264335D03*
X263579Y669601D03*
X266179D03*
Y672708D03*
X263579D03*
X270857Y668515D03*
X263839Y692049D03*
X275851Y1452895D03*
X262451D03*
X266596Y1737117D03*
X278979Y28406D03*
X286066D03*
X279273Y99186D03*
X289553Y121806D03*
X291109Y700885D03*
X283062Y700979D03*
X279895Y709487D03*
X283565Y706933D03*
X286009Y706949D03*
X278545Y706987D03*
X279895Y712087D03*
Y714687D03*
X291109Y703842D03*
Y706949D03*
X288509D03*
X277295Y709487D03*
Y712087D03*
Y714687D03*
X283062Y703936D03*
X277055Y722649D03*
X279171Y724988D03*
X281992Y1342705D03*
X292705Y580275D03*
X292156Y679071D03*
X304301Y679037D03*
X292205Y691486D03*
X297065D03*
X294635D03*
X293709Y700885D03*
X297065Y697086D03*
X303657Y702815D03*
X292205Y697086D03*
X294635D03*
X293709Y703842D03*
Y706949D03*
X298909Y703842D03*
Y706949D03*
X296309Y703842D03*
Y706949D03*
X303413Y1462595D03*
X315912Y721039D03*
Y723996D03*
X321279Y727099D03*
X312665Y729637D03*
Y732237D03*
X310065Y729637D03*
Y732237D03*
X316335Y727083D03*
X311315Y727137D03*
X318779Y727099D03*
X313255Y746279D03*
X312665Y734837D03*
X310065D03*
X310113Y1452895D03*
X312596Y1737117D03*
X328966Y548030D03*
X324926Y699221D03*
X329835Y711636D03*
X324975D03*
X329835Y717236D03*
X327405Y711636D03*
X324975Y717236D03*
X327405D03*
X326479Y721035D03*
X323879D03*
Y727099D03*
X326479D03*
X329079D03*
X331679D03*
X323879Y723992D03*
X326479D03*
X329079D03*
X331679D03*
X330213Y1462595D03*
X323513Y1472295D03*
X334596Y1737117D03*
X350817Y558248D03*
X343182Y586415D03*
Y591335D03*
X348449Y720827D03*
Y723784D03*
X345725Y729369D03*
X343125D03*
X345725Y731969D03*
X343125D03*
X344375Y726869D03*
X349395Y726815D03*
X336457Y722815D03*
X339825Y746269D03*
X342425D03*
X349625D03*
X345725Y734569D03*
X343125D03*
X336913Y1452895D03*
X350313Y1472295D03*
X352418Y225329D03*
Y222329D03*
X355733Y275059D03*
X357986Y698953D03*
X362895Y716968D03*
X360465Y711368D03*
X362895D03*
X358035D03*
Y716968D03*
X360465D03*
X359539Y720767D03*
X356939D03*
X351839Y726831D03*
X354339D03*
X356939D03*
X362139D03*
X359539D03*
X364739D03*
X356939Y723724D03*
X362139D03*
X359539D03*
X364739D03*
X352225Y746269D03*
X360025D03*
X362625D03*
X352943Y1214510D03*
X363713Y1452895D03*
X357013Y1462595D03*
X356596Y1737117D03*
X379023Y225149D03*
X371318Y218629D03*
X379023Y228649D03*
X379028Y232559D03*
X369428Y231759D03*
X372528Y231859D03*
X369171Y562380D03*
X376671D03*
X369100Y577400D03*
X369171Y569880D03*
X376600Y577400D03*
X376165Y729437D03*
X378765D03*
X376165Y732037D03*
X378765D03*
X377415Y726937D03*
X369557Y722615D03*
X373425Y746169D03*
X370825D03*
X376165Y734637D03*
X378765D03*
X367836Y1209506D03*
X377190Y1387697D03*
X377113Y1472295D03*
X393287Y-9234D03*
X391635Y161091D03*
X384259Y562426D03*
X384301Y577446D03*
X385443Y597279D03*
X391026Y699021D03*
X395935Y717036D03*
Y711436D03*
X393505D03*
X391075D03*
Y717036D03*
X393505D03*
X392579Y720835D03*
X389979D03*
X381802Y720789D03*
Y723746D03*
X387379Y726899D03*
X384879D03*
X389979D03*
Y723792D03*
X382435Y726883D03*
X392579Y726899D03*
X395179D03*
X392579Y723792D03*
X395179D03*
X389981Y1015474D03*
Y1022560D03*
Y1019017D03*
X383813Y1462595D03*
X390513Y1452895D03*
X406243Y100076D03*
X402184Y507101D03*
X403133Y565415D03*
X403157Y569415D03*
X410415Y709137D03*
X409165Y711637D03*
Y714237D03*
Y716837D03*
X397779Y726899D03*
Y723792D03*
X402457Y722615D03*
X397461Y1015474D03*
X404941D03*
X397461Y1022560D03*
X404941Y1019017D03*
Y1022560D03*
X397461Y1019017D03*
X403913Y1452895D03*
X417617Y79073D03*
X423376Y96664D03*
X411952Y132751D03*
Y123051D03*
X422936Y228147D03*
Y232793D03*
X420288Y244184D03*
X415984Y507024D03*
X424026Y681221D03*
X424075Y693636D03*
X425579Y703035D03*
X422979D03*
X424075Y699236D03*
X414682Y703139D03*
X411765Y711637D03*
Y714237D03*
Y716837D03*
X415435Y709083D03*
X417879Y709099D03*
X425579D03*
X422979D03*
X420379D03*
X425579Y705992D03*
X422979D03*
X414682Y706096D03*
X423811Y1009400D03*
Y1028831D03*
X417098Y1533764D03*
Y1531264D03*
X422596Y1737117D03*
X429685Y88657D03*
X436090Y116007D03*
Y124007D03*
Y132007D03*
X440591Y684518D03*
X436130Y683281D03*
X426505Y693636D03*
X428935D03*
Y699236D03*
X426505D03*
X430779Y709099D03*
Y705992D03*
X428179Y709099D03*
Y705992D03*
X435457Y704915D03*
X439411Y733527D03*
X436811D03*
X439411Y736147D03*
X436811D03*
X436411Y738717D03*
X439011D03*
X436411Y743917D03*
X439011D03*
X436411Y741317D03*
X439011D03*
X431291Y1009400D03*
X438316Y1014745D03*
X427551Y1009400D03*
X435031D03*
X438771D03*
X428473Y1014745D03*
X438771Y1028831D03*
X438316Y1023013D03*
X427551Y1028831D03*
X435031D03*
X438316Y1018879D03*
X428473D03*
Y1023013D03*
X431291Y1028831D03*
X427251Y1291747D03*
X439524Y1462595D03*
X448090Y116007D03*
X444090Y132007D03*
X452480Y273420D03*
X441320Y298170D03*
X452565Y652837D03*
X455379Y678435D03*
X450279Y684499D03*
X455379D03*
X452779D03*
X455379Y681392D03*
X444165Y687037D03*
X441565D03*
X443235Y684637D03*
X447835Y684483D03*
X447162Y678409D03*
Y681366D03*
X444325Y702449D03*
X441725D03*
X444165Y689637D03*
Y692237D03*
X441565D03*
Y689637D03*
X446591Y716837D03*
X443991D03*
X446591Y719437D03*
X443991D03*
X441959Y993766D03*
Y997766D03*
X442034Y989766D03*
X442511Y1009400D03*
X449992D03*
X446252D03*
X453732D03*
X441959Y1001766D03*
X447174Y1014745D03*
X446252Y1028831D03*
X453732D03*
X449992D03*
X447174Y1023013D03*
X442511Y1028831D03*
X447174Y1018879D03*
X446224Y1452895D03*
X444596Y1737117D03*
X463402Y229970D03*
X457731Y237588D03*
X463653Y237390D03*
X462703Y242342D03*
X467644Y353417D03*
X469046Y657062D03*
X456426Y656621D03*
X458905Y669036D03*
X456475D03*
X461335D03*
X457979Y678435D03*
X460579Y684499D03*
X457979D03*
X460579Y681392D03*
X457979D03*
X467957Y680315D03*
X463179Y684499D03*
Y681392D03*
X461335Y674636D03*
X456475D03*
X458905D03*
X457472Y1009400D03*
X457410Y1014745D03*
Y1018879D03*
Y1023013D03*
X457472Y1028831D03*
X466324Y1462595D03*
X459624Y1472295D03*
X466596Y1737117D03*
X486682Y197516D03*
X483800Y270440D03*
X475415Y658037D03*
X482879Y657999D03*
X480435Y657983D03*
X485379Y657999D03*
X479822Y651989D03*
Y654946D03*
X476765Y660537D03*
X474165D03*
X476765Y663137D03*
X474165D03*
X476765Y665737D03*
X474165D03*
X473024Y1452895D03*
X495232Y189516D03*
X486600Y200800D03*
X495232Y197516D03*
X491635Y212577D03*
X487541Y226527D03*
X488076Y350420D03*
X501171Y630087D03*
X493935Y642536D03*
X489075D03*
X491505D03*
X489026Y630121D03*
X493935Y648136D03*
X487979Y651935D03*
X490579D03*
X493179Y654892D03*
Y657999D03*
X487979Y654892D03*
X490579D03*
Y657999D03*
X487979D03*
X495779Y654892D03*
Y657999D03*
X489075Y648136D03*
X491505D03*
X499824Y1452895D03*
X493124Y1462595D03*
X486424Y1472295D03*
X488596Y1737117D03*
X510810Y49193D03*
X510065Y626437D03*
X508715Y623937D03*
X507465Y626437D03*
X513735Y623883D03*
X513012Y620706D03*
Y617749D03*
X510065Y629037D03*
X507465D03*
X510065Y631637D03*
X507465D03*
X514771Y643138D03*
X500457Y653715D03*
X513224Y1472295D03*
X517915Y42257D03*
X525001D03*
X517896Y49193D03*
X524763Y49189D03*
X522418Y137171D03*
X526418D03*
X517973Y211998D03*
X522326Y596021D03*
X524805Y608436D03*
X522375D03*
X527235D03*
X526479Y620792D03*
Y623899D03*
X523879Y620792D03*
X521279D03*
X523879Y623899D03*
X521279D03*
X518679D03*
X516179D03*
X529079Y620792D03*
Y623899D03*
X523879Y617835D03*
X521279D03*
X527235Y614036D03*
X522375D03*
X524805D03*
X521771Y643138D03*
X528771D03*
X519924Y1462595D03*
X526624Y1452895D03*
X532070Y49193D03*
X539156D03*
X530418Y137171D03*
X541013Y222441D03*
X534471Y595987D03*
X533857Y619615D03*
X534271Y643138D03*
X540024Y1452895D03*
X532596Y1737117D03*
X557091Y114382D03*
X550505D03*
X553100Y227700D03*
X551200Y377650D03*
X551171Y1167678D03*
X554596Y1737117D03*
X564431Y45132D03*
X562475Y242721D03*
X571271Y1259488D03*
X567586Y1462595D03*
X574286Y1452895D03*
X578621Y45112D03*
X585296Y222954D03*
X586000Y808862D03*
X578830Y1218588D03*
X585501Y1229536D03*
X587686Y1472295D03*
X576596Y1737117D03*
X595682Y44842D03*
X603064Y44523D03*
X599284Y32866D03*
X593920Y49193D03*
X600793Y193185D03*
X596661Y188775D03*
X590300Y190660D03*
X595563Y239128D03*
X603283Y419744D03*
X597071Y799268D03*
X592761Y1220688D03*
X594386Y1462595D03*
X601086Y1452895D03*
X598596Y1737117D03*
X618427Y43432D03*
X615180Y49193D03*
X618600Y160750D03*
X613207Y182229D03*
X615464Y347522D03*
X607871Y359262D03*
X613761Y790418D03*
X605771Y1267098D03*
X614486Y1472295D03*
X624937Y44019D03*
X620390Y36794D03*
X630900Y118920D03*
X632695Y1366157D03*
Y1372257D03*
Y1378257D03*
X627886Y1452895D03*
X621186Y1462595D03*
X620596Y1737117D03*
X648487Y44106D03*
X638695Y1366157D03*
X644795D03*
X643395Y1372857D03*
X638695Y1378257D03*
X644795D03*
X647986Y1462595D03*
X641286Y1472295D03*
X642596Y1737117D03*
X654590Y49193D03*
X661676D03*
X652804Y790297D03*
Y800336D03*
Y837147D03*
Y827108D03*
Y863919D03*
Y873958D03*
Y900730D03*
Y910769D03*
Y937541D03*
Y947580D03*
Y1084785D03*
Y1094824D03*
Y1121596D03*
Y1131635D03*
Y1158407D03*
Y1168446D03*
Y1205257D03*
Y1195218D03*
Y1232029D03*
Y1242068D03*
X661685Y1367283D03*
X654686Y1452895D03*
X662153Y1727718D03*
X675849Y49193D03*
X668763D03*
X668086Y1452895D03*
X664596Y1737117D03*
X682505Y790297D03*
Y800336D03*
Y837147D03*
Y827108D03*
Y863919D03*
Y873958D03*
Y900730D03*
Y910769D03*
Y937541D03*
Y947580D03*
Y1084785D03*
Y1094824D03*
Y1121596D03*
Y1131635D03*
Y1158407D03*
Y1168446D03*
Y1205257D03*
Y1195218D03*
Y1232029D03*
Y1242068D03*
X688540Y1455140D03*
X697400Y345761D03*
X697300Y1454140D03*
X722581Y49182D03*
X713420Y102060D03*
X712206Y790297D03*
Y800336D03*
Y827108D03*
Y837147D03*
Y863919D03*
Y873958D03*
Y900730D03*
Y910769D03*
Y937541D03*
Y947580D03*
Y1084785D03*
Y1094824D03*
Y1121596D03*
Y1131635D03*
Y1158407D03*
Y1168446D03*
Y1195218D03*
Y1205257D03*
Y1232029D03*
Y1242068D03*
X731743Y-30584D03*
X734996Y-30570D03*
X731758Y-28069D03*
X735011Y-28055D03*
X728718Y-29264D03*
X735041Y-23025D03*
X735026Y-25540D03*
X731555Y83685D03*
X737009Y83169D03*
X724134Y141288D03*
X728500Y533862D03*
X736500D03*
X732500D03*
X738260Y553625D03*
X747637Y534874D03*
X740638Y549900D03*
X741907Y790297D03*
Y800336D03*
Y827108D03*
Y837147D03*
Y863919D03*
Y873958D03*
Y900730D03*
Y910769D03*
Y937541D03*
Y947580D03*
Y1084785D03*
Y1094824D03*
Y1121596D03*
Y1131635D03*
Y1158407D03*
Y1168446D03*
Y1195218D03*
Y1205257D03*
Y1232029D03*
Y1242068D03*
X751521Y1659158D03*
X752596Y1737117D03*
X762199Y126684D03*
Y129684D03*
X758111Y172636D03*
X762300Y188910D03*
X764500Y534424D03*
X760500Y534352D03*
X781242Y489574D03*
X771608Y790297D03*
Y800336D03*
Y837147D03*
Y827108D03*
Y863919D03*
Y873958D03*
Y900730D03*
Y910769D03*
Y937541D03*
Y947580D03*
Y1084785D03*
Y1094824D03*
Y1121596D03*
Y1131635D03*
Y1158407D03*
Y1168446D03*
Y1195218D03*
Y1205257D03*
Y1232029D03*
Y1242068D03*
X778030Y1310259D03*
X780530D03*
X773974Y1731920D03*
X796333Y439344D03*
X786030Y1310259D03*
X794030D03*
X796530D03*
X788530D03*
X791823Y1527404D03*
X795926Y1731918D03*
X807451Y763765D03*
X801308Y790297D03*
Y800336D03*
Y837147D03*
Y827108D03*
Y863919D03*
Y873958D03*
Y900730D03*
Y910769D03*
Y937541D03*
Y947580D03*
Y1084785D03*
Y1094824D03*
Y1121596D03*
Y1131635D03*
Y1158407D03*
Y1168446D03*
Y1195218D03*
Y1205257D03*
Y1232029D03*
Y1242068D03*
X802030Y1310259D03*
X804530D03*
X807601Y1307191D03*
X810246Y1351988D03*
X817974Y1731920D03*
X839974D03*
X844766Y-15374D03*
Y-5374D03*
Y24626D03*
X849711Y212062D03*
X845221Y216532D03*
X854707Y229878D03*
X852207D03*
X874295Y163862D03*
X863488Y176332D03*
X861974Y1731920D03*
X883974D03*
X898000Y1112336D03*
Y1109736D03*
Y1116544D03*
Y1119144D03*
Y1130160D03*
Y1132760D03*
Y1123352D03*
Y1125952D03*
X916880Y1138969D03*
X906473Y1158574D03*
X903980Y1268420D03*
X904024Y1272692D03*
X903947Y1276968D03*
X903899Y1281203D03*
X903945Y1285420D03*
X903923Y1289630D03*
X903651Y1293853D03*
X903690Y1298027D03*
X905974Y1731920D03*
X921477Y1134647D03*
X925525Y1135172D03*
X919880Y1146569D03*
Y1139969D03*
Y1143369D03*
Y1149769D03*
X922880Y1146569D03*
Y1139969D03*
Y1143369D03*
Y1149769D03*
X919077Y1136521D03*
X923125Y1137046D03*
X919880Y1152769D03*
X928751Y1266347D03*
X928901Y1270408D03*
X928852Y1274591D03*
X928979Y1278713D03*
X928827Y1283048D03*
X928928Y1287193D03*
X928906Y1291676D03*
X928983Y1295957D03*
X927974Y1731920D03*
X935497Y195925D03*
Y210098D03*
Y203012D03*
Y224272D03*
Y217185D03*
Y231358D03*
X935783Y634051D03*
X941000Y1110557D03*
Y1107957D03*
Y1117557D03*
Y1114957D03*
Y1124557D03*
Y1121957D03*
Y1131557D03*
Y1128957D03*
X953498Y1158574D03*
X949974Y1731920D03*
X967315Y1135550D03*
X972109Y1135149D03*
X966905Y1146569D03*
X969905D03*
X966905Y1139969D03*
Y1143369D03*
X969905Y1139969D03*
Y1143369D03*
X966905Y1149769D03*
X969905D03*
X963012Y1139511D03*
X964915Y1137424D03*
X969709Y1137023D03*
X966905Y1152769D03*
X968594Y1288193D03*
X971974Y1731920D03*
X991031Y528574D03*
X998056Y518214D03*
Y523874D03*
X999031Y528574D03*
X999894Y1267126D03*
X993974Y1731920D03*
X1021220Y243638D03*
X1012220D03*
X1007669Y268884D03*
Y258222D03*
X1007587Y767480D03*
Y769980D03*
Y780880D03*
Y778380D03*
Y789484D03*
Y791984D03*
X1010894Y1271743D03*
X1010865Y1275768D03*
X1010944Y1279751D03*
X1010650Y1310500D03*
X1015974Y1731920D03*
X1025493Y758819D03*
X1044012Y268659D03*
X1051495Y265133D03*
X1040097Y529508D03*
X1050915Y790296D03*
Y800335D03*
Y827107D03*
Y837146D03*
Y863918D03*
Y873957D03*
Y910768D03*
Y900729D03*
Y937540D03*
Y947579D03*
Y1084784D03*
Y1094823D03*
Y1131634D03*
Y1121595D03*
Y1158406D03*
Y1168445D03*
Y1205256D03*
Y1195217D03*
Y1232028D03*
Y1242067D03*
X1037974Y1731920D03*
X1054355Y258698D03*
X1065552Y271441D03*
X1056517Y512787D03*
X1061837Y519703D03*
X1060721Y1313954D03*
X1061974Y1731920D03*
X1080616Y790296D03*
Y800335D03*
Y827107D03*
Y837146D03*
Y863918D03*
Y873957D03*
Y910768D03*
Y900729D03*
Y937540D03*
Y947579D03*
Y1084784D03*
Y1094823D03*
Y1131634D03*
Y1121595D03*
Y1158406D03*
Y1168445D03*
Y1205256D03*
Y1195217D03*
Y1232028D03*
Y1242067D03*
X1081857Y269856D03*
X1089030Y1691229D03*
X1092980Y1696029D03*
X1095489Y1708519D03*
X1081974Y1731920D03*
X1110316Y790296D03*
Y800335D03*
Y827107D03*
Y837146D03*
Y863918D03*
Y873957D03*
Y910768D03*
Y900729D03*
Y937540D03*
Y947579D03*
Y1084784D03*
Y1094823D03*
Y1131634D03*
Y1121595D03*
Y1158406D03*
Y1168445D03*
Y1205256D03*
Y1195217D03*
Y1232028D03*
Y1242067D03*
X1103351Y1737117D03*
X1112001Y1718991D03*
X1125351Y1737117D03*
X1140017Y790296D03*
Y800335D03*
Y827107D03*
Y837146D03*
Y863918D03*
Y873957D03*
Y910768D03*
Y900729D03*
Y937540D03*
Y947579D03*
Y1084784D03*
Y1094823D03*
Y1131634D03*
Y1121595D03*
Y1158406D03*
Y1168445D03*
Y1205256D03*
Y1195217D03*
Y1232028D03*
Y1242067D03*
X1169718Y790296D03*
Y800335D03*
Y837146D03*
Y827107D03*
Y863918D03*
Y873957D03*
Y900729D03*
Y910768D03*
Y937540D03*
Y947579D03*
Y1084784D03*
Y1094823D03*
Y1121595D03*
Y1131634D03*
Y1158406D03*
Y1168445D03*
Y1205256D03*
Y1195217D03*
Y1232028D03*
Y1242067D03*
X1183050Y-20074D03*
Y-10074D03*
Y-74D03*
Y9926D03*
X1183224Y1495595D03*
X1186312Y-20074D03*
Y-10074D03*
Y-74D03*
Y9926D03*
X1200037Y164987D03*
Y160987D03*
X1189727Y177187D03*
X1200012Y185187D03*
X1199419Y790296D03*
Y800335D03*
Y837146D03*
Y827107D03*
Y863918D03*
Y873957D03*
Y900729D03*
Y910768D03*
Y937540D03*
Y947579D03*
Y1084784D03*
Y1094823D03*
Y1121595D03*
Y1131634D03*
Y1158406D03*
Y1168445D03*
Y1195217D03*
Y1205256D03*
Y1232028D03*
Y1242067D03*
X1189924Y1485895D03*
X1199612Y1700334D03*
X1199294Y1721143D03*
X1191351Y1737117D03*
X1215581Y91346D03*
X1202711Y87651D03*
X1215581Y94846D03*
X1213355Y1412564D03*
Y1427564D03*
Y1420064D03*
X1203324Y1505295D03*
X1210024Y1495595D03*
X1214954Y1700343D03*
X1204447Y1707143D03*
X1213351Y1737117D03*
X1223455Y91346D03*
X1230312Y88635D03*
X1215931Y141530D03*
X1218431D03*
X1231118Y142125D03*
X1228355Y1412564D03*
X1220855D03*
X1228355Y1427564D03*
Y1420064D03*
X1220855Y1427564D03*
X1216724Y1485895D03*
X1230124Y1505295D03*
X1235546Y75293D03*
X1232812Y88635D03*
X1239218Y128239D03*
Y137239D03*
Y132739D03*
Y123739D03*
X1238094Y280573D03*
X1233345Y300157D03*
X1242429Y443255D03*
Y447255D03*
X1243524Y1485895D03*
X1236824Y1495595D03*
X1235351Y1737117D03*
X1248286Y-15374D03*
Y-25374D03*
Y14626D03*
X1252561Y72675D03*
X1255185Y140053D03*
Y142553D03*
X1255175Y137553D03*
X1246094Y280573D03*
X1246748Y785752D03*
X1258121Y1342686D03*
X1256924Y1505295D03*
X1257351Y1737117D03*
X1270324Y1485895D03*
X1263624Y1495595D03*
X1278677Y808988D03*
X1283724Y1485895D03*
X1279351Y1737117D03*
X1295532Y539513D03*
X1301666Y555413D03*
X1301351Y1737117D03*
X1319667Y87587D03*
Y105227D03*
X1307857Y111353D03*
X1317986Y1485895D03*
X1311286Y1495595D03*
X1333878Y637721D03*
X1331386Y1505295D03*
X1323351Y1737117D03*
X1344958Y85358D03*
X1336558Y637721D03*
X1339238D03*
X1344438D03*
X1341838D03*
X1344786Y1485895D03*
X1338086Y1495595D03*
X1345351Y1737117D03*
X1356868Y85324D03*
X1360629Y120380D03*
X1363831Y642042D03*
X1361387Y642026D03*
X1356367Y642080D03*
X1352527Y638278D03*
X1360944Y638999D03*
Y636042D03*
X1357717Y647180D03*
Y649780D03*
X1355117D03*
Y647180D03*
X1357717Y644580D03*
X1355117D03*
X1364317Y661368D03*
X1357057Y661328D03*
X1364886Y1495595D03*
X1358186Y1505295D03*
X1369808Y87587D03*
X1382123Y614130D03*
X1374887Y626579D03*
X1372457D03*
X1370027D03*
X1369978Y614164D03*
X1366331Y642042D03*
X1376731Y638935D03*
Y642042D03*
X1371531Y638935D03*
Y642042D03*
Y635978D03*
X1374887Y632179D03*
X1374131Y638935D03*
Y642042D03*
X1368931Y638935D03*
Y642042D03*
Y635978D03*
X1370027Y632179D03*
X1372457D03*
X1371847Y661328D03*
X1366123Y1015473D03*
X1373603D03*
Y1019016D03*
Y1022559D03*
X1366123D03*
Y1019016D03*
X1371586Y1485895D03*
X1367351Y1737117D03*
X1381457Y637865D03*
X1380306Y664816D03*
X1380256Y667466D03*
X1393664Y671949D03*
Y668992D03*
X1390417Y677480D03*
X1389067Y674980D03*
X1387817Y677480D03*
X1394087Y674926D03*
X1390417Y680080D03*
X1387817D03*
X1390417Y682680D03*
X1387817D03*
X1388757Y693397D03*
Y690897D03*
X1381083Y1015473D03*
Y1022559D03*
Y1019016D03*
X1384986Y1505295D03*
X1391686Y1495595D03*
X1389351Y1737117D03*
X1403207Y118938D03*
X1402678Y647064D03*
X1404231Y671835D03*
X1406831D03*
X1409431D03*
X1404231Y668878D03*
X1407587Y665079D03*
X1405157Y659479D03*
X1407587D03*
X1401631Y671835D03*
Y668878D03*
X1402727Y659479D03*
Y665079D03*
X1405157D03*
X1404231Y674942D03*
X1409431D03*
X1406831D03*
X1396531D03*
X1399031D03*
X1401631D03*
X1403693Y1009399D03*
X1407433D03*
X1399953D03*
X1404615Y1014744D03*
X1399953Y1028830D03*
X1407433D03*
X1404615Y1023012D03*
Y1018878D03*
X1403693Y1028830D03*
X1406608Y1282606D03*
X1398386Y1485895D03*
X1414823Y647030D03*
X1414157Y670665D03*
X1416241Y700281D03*
X1416291Y697631D03*
X1420417Y712660D03*
Y715260D03*
Y710060D03*
X1423017Y712660D03*
Y715260D03*
Y710060D03*
X1421667Y707560D03*
X1422757Y726097D03*
Y723597D03*
X1418101Y997765D03*
Y993765D03*
X1418176Y989765D03*
X1418653Y1009399D03*
X1418101Y1001765D03*
X1422394Y1009399D03*
X1414913D03*
X1411173D03*
X1423316Y1014744D03*
X1414458D03*
Y1023012D03*
X1418653Y1028830D03*
X1411173D03*
X1414913D03*
X1423316Y1023012D03*
Y1018878D03*
X1422394Y1028830D03*
X1414458Y1018878D03*
X1411786Y1485895D03*
X1413199Y1643920D03*
X1411351Y1737117D03*
X1438883Y-15050D03*
Y-25050D03*
Y-5050D03*
Y14950D03*
Y4950D03*
X1438312Y152166D03*
X1435278Y679644D03*
X1436257Y676265D03*
X1436831Y701458D03*
X1435327Y692059D03*
X1437757D03*
X1434231Y701458D03*
X1435327Y697659D03*
X1437757D03*
X1426264Y701572D03*
X1436831Y704415D03*
Y707522D03*
X1439431Y704415D03*
Y707522D03*
X1431631D03*
X1429131D03*
X1426687Y707506D03*
X1434231Y704415D03*
Y707522D03*
X1426264Y704529D03*
X1433614Y1009399D03*
X1426134D03*
X1429874D03*
X1433552Y1014744D03*
X1429874Y1028830D03*
X1433552Y1018878D03*
Y1023012D03*
X1426134Y1028830D03*
X1433614D03*
X1433351Y1737117D03*
X1441908Y-26370D03*
X1445161Y-26356D03*
X1441908Y-16370D03*
X1441923Y-13855D03*
X1445161Y-16356D03*
X1445176Y-13841D03*
X1441923Y-23855D03*
X1445176Y-23841D03*
X1441908Y-6370D03*
X1441923Y-3855D03*
X1445161Y-6356D03*
X1445176Y-3841D03*
X1441908Y3630D03*
X1445161Y3644D03*
X1441908Y13630D03*
X1441923Y16145D03*
X1445161Y13644D03*
X1445176Y16159D03*
X1441923Y6145D03*
X1445176Y6159D03*
X1440871Y130118D03*
X1453667Y152166D03*
X1447423Y679610D03*
X1440187Y697659D03*
X1446757Y703265D03*
X1440187Y692059D03*
X1442031Y704415D03*
Y707522D03*
X1453335Y729637D03*
Y732237D03*
Y734837D03*
X1453757Y743597D03*
Y746097D03*
X1454098Y1485895D03*
X1447398Y1495595D03*
X1459177Y163796D03*
X1456282Y568977D03*
Y572977D03*
Y576977D03*
Y580977D03*
X1468196Y699221D03*
X1468245Y711636D03*
Y717236D03*
X1467149Y721035D03*
X1458599Y721045D03*
Y724002D03*
X1455935Y729637D03*
Y732237D03*
X1454585Y727137D03*
X1459605Y727083D03*
X1462049Y727099D03*
X1464549D03*
X1467149Y723992D03*
Y727099D03*
X1455935Y734837D03*
X1467498Y1505295D03*
X1455579Y1636114D03*
X1473105Y717236D03*
X1470675Y711636D03*
X1473105D03*
X1470675Y717236D03*
X1469749Y721035D03*
X1479757Y722865D03*
X1469749Y723992D03*
X1474949D03*
X1472349D03*
Y727099D03*
X1469749D03*
X1474949D03*
X1481665Y745809D03*
X1477177Y803488D03*
X1478177Y817013D03*
X1480898Y1485895D03*
X1474198Y1495595D03*
X1498543Y587841D03*
X1492264Y721149D03*
X1486417Y729637D03*
Y732237D03*
X1489017Y729687D03*
Y732237D03*
X1492264Y724106D03*
X1487667Y727137D03*
X1492687Y727083D03*
X1495131Y727099D03*
X1497631D03*
X1486417Y734837D03*
X1489017D03*
X1484265Y745809D03*
X1489177Y803488D03*
X1498177Y817013D03*
X1494298Y1505295D03*
X1501278Y699221D03*
X1506187Y717236D03*
Y711636D03*
X1501327D03*
X1503757D03*
X1501327Y717404D03*
X1503757D03*
X1502831Y721035D03*
X1500231D03*
X1512757Y722897D03*
X1500231Y723992D03*
X1502831D03*
X1505431D03*
X1508031D03*
X1500231Y727099D03*
X1502831D03*
X1505431D03*
X1508031D03*
X1505905Y746119D03*
X1508505D03*
X1507698Y1485895D03*
X1500998Y1495595D03*
X1499351Y1737117D03*
X1519930Y543470D03*
X1516357Y555318D03*
X1516257Y559977D03*
X1525064Y721149D03*
Y724106D03*
X1521817Y729637D03*
Y732237D03*
X1525487Y727083D03*
X1527931Y727099D03*
X1519217Y729637D03*
Y732237D03*
X1520467Y727137D03*
X1521817Y734837D03*
X1519217D03*
X1515895Y746119D03*
X1518495D03*
X1521098Y1505295D03*
X1527798Y1495595D03*
X1521351Y1737117D03*
X1541580Y-19575D03*
X1541666Y69340D03*
X1532853Y560264D03*
X1534078Y699221D03*
X1536557Y711636D03*
X1534127D03*
X1538987Y717236D03*
Y711636D03*
X1534127Y717236D03*
X1536557D03*
X1535631Y721035D03*
X1533031D03*
X1538231Y723992D03*
X1540831D03*
X1538231Y727099D03*
X1540831D03*
X1530431D03*
X1533031Y723992D03*
X1535631D03*
X1533031Y727099D03*
X1535631D03*
X1543563Y757803D03*
X1543585Y762919D03*
X1543574Y760361D03*
X1534317Y1216828D03*
X1531227Y1227648D03*
X1540227D03*
X1534498Y1485895D03*
X1543351Y1737117D03*
X1554510Y28406D03*
X1547424D03*
X1554510Y40020D03*
X1547424D03*
X1552662Y75343D03*
X1546257Y701097D03*
X1558194Y702166D03*
Y699209D03*
X1552347Y712897D03*
X1554947D03*
X1552347Y710297D03*
Y707697D03*
X1554947Y710297D03*
Y707697D03*
X1553597Y705197D03*
X1558617Y705143D03*
X1551250Y723840D03*
X1553750D03*
X1545557Y722897D03*
X1556555Y740617D03*
X1556544Y738059D03*
X1554055Y740617D03*
X1554044Y738059D03*
X1546965Y746119D03*
X1546954Y743561D03*
X1548119Y751952D03*
X1545619D03*
X1548119Y754832D03*
X1545619D03*
X1546063Y757803D03*
X1546085Y762919D03*
X1546074Y760361D03*
X1549877Y1217288D03*
Y1221288D03*
X1547898Y1485895D03*
X1561597Y28406D03*
X1568683D03*
Y40020D03*
X1561597D03*
X1563666Y69340D03*
X1567208Y677281D03*
X1572117Y695296D03*
X1568761Y702052D03*
X1571361D03*
X1568761Y699095D03*
X1566161Y702052D03*
Y699095D03*
X1569687Y689696D03*
X1572117D03*
X1567257D03*
Y695296D03*
X1569687D03*
X1563561Y705159D03*
X1561061D03*
X1568761D03*
X1571361D03*
X1566161D03*
X1568660Y1283460D03*
X1572036Y1306083D03*
X1565351Y1737117D03*
X1575770Y28406D03*
X1582857D03*
Y40020D03*
X1575770D03*
X1574666Y75340D03*
X1585666Y69340D03*
X1579748Y536344D03*
X1576843Y674425D03*
X1579807Y671268D03*
X1586367Y671428D03*
X1587717Y676528D03*
Y673928D03*
X1585117Y676528D03*
Y673928D03*
Y679128D03*
X1587717D03*
X1578757Y700965D03*
X1573961Y702052D03*
X1586070Y696830D03*
Y694330D03*
X1573961Y705159D03*
X1578904Y721340D03*
Y723840D03*
X1584849Y793506D03*
X1587028Y1307137D03*
X1582160Y1485895D03*
X1575460Y1495595D03*
X1587351Y1737117D03*
X1589943Y28406D03*
X1597030D03*
Y40020D03*
X1589943D03*
X1596666Y75340D03*
X1599837Y295328D03*
X1593214Y531226D03*
X1599978Y643512D03*
X1600027Y655927D03*
X1602457D03*
X1591387Y671374D03*
X1593831Y671390D03*
X1596331D03*
X1601531D03*
Y668283D03*
Y665326D03*
X1598931Y671390D03*
Y668283D03*
Y665326D03*
X1600027Y661527D03*
X1602457D03*
X1590964Y668397D03*
Y665440D03*
X1594539Y1295288D03*
X1595560Y1505295D03*
X1602260Y1495595D03*
X1604117Y28406D03*
Y40020D03*
X1607666Y69343D03*
X1609355Y592794D03*
X1615677Y648488D03*
X1604887Y655927D03*
X1618117Y657528D03*
Y654928D03*
X1611557Y667165D03*
X1606731Y671390D03*
Y668283D03*
X1604131Y671390D03*
Y668283D03*
X1604887Y661527D03*
X1618117Y660128D03*
X1613154Y688238D03*
Y690738D03*
X1605447Y1288748D03*
X1608960Y1485895D03*
X1609351Y1737117D03*
X1632896Y28406D03*
X1625809D03*
X1632896Y40020D03*
X1625809D03*
X1618666Y75340D03*
X1631558Y588513D03*
X1628756Y588591D03*
X1624067Y588474D03*
X1621187Y588591D03*
X1632978Y624512D03*
X1633027Y636927D03*
Y642527D03*
X1620717Y657528D03*
X1631931Y652390D03*
Y649283D03*
X1626831Y652390D03*
X1629331D03*
X1631931Y646326D03*
X1624387Y652374D03*
X1619367Y652428D03*
X1620717Y654928D03*
X1623964Y649397D03*
Y646440D03*
X1621050Y671768D03*
X1623550D03*
X1620717Y660128D03*
X1628946Y790296D03*
Y800335D03*
Y827107D03*
Y837146D03*
Y863918D03*
Y873957D03*
Y900729D03*
Y910768D03*
Y937540D03*
Y947579D03*
Y1084784D03*
Y1094823D03*
Y1121595D03*
Y1131634D03*
Y1158406D03*
Y1168445D03*
Y1195217D03*
Y1205256D03*
Y1232028D03*
Y1242067D03*
X1629060Y1495595D03*
X1622360Y1505295D03*
X1631351Y1737117D03*
X1647069Y28406D03*
X1639983D03*
X1647069Y40020D03*
X1639983D03*
X1641870Y75340D03*
X1645123Y624478D03*
X1637887Y642527D03*
Y636927D03*
X1635457D03*
Y642527D03*
X1644457Y648265D03*
X1639731Y652390D03*
X1634531D03*
X1637131D03*
X1639731Y649283D03*
X1634531D03*
X1637131D03*
X1634531Y646326D03*
X1643183Y1419441D03*
X1643283Y1431541D03*
X1635760Y1485895D03*
X1654156Y28406D03*
Y40020D03*
X1652870Y69340D03*
X1650917Y657528D03*
Y654928D03*
X1653517Y657528D03*
X1652167Y652428D03*
X1653517Y654928D03*
X1648604Y671768D03*
X1650917Y660128D03*
X1659618Y659021D03*
X1662298D03*
X1651104Y671768D03*
X1653517Y660128D03*
X1656938Y659021D03*
X1651959Y689800D03*
X1658647Y790296D03*
Y800335D03*
Y827107D03*
Y837146D03*
Y863918D03*
Y873957D03*
Y900729D03*
Y910768D03*
Y937540D03*
Y947579D03*
Y1084784D03*
Y1094823D03*
Y1121595D03*
Y1131634D03*
Y1158406D03*
Y1168445D03*
Y1205256D03*
Y1195217D03*
Y1232028D03*
Y1242067D03*
X1649283Y1419441D03*
Y1431541D03*
X1655383D03*
Y1419441D03*
X1655957Y1445116D03*
X1662560Y1485895D03*
X1649160Y1505295D03*
X1655860Y1495595D03*
X1653351Y1737117D03*
X1677030Y28406D03*
X1669943D03*
X1677030Y40020D03*
X1669943D03*
X1663866Y75343D03*
X1674870Y69340D03*
X1668516Y599956D03*
X1674516D03*
X1668516Y609450D03*
X1671516Y599956D03*
X1674516Y609450D03*
X1677516Y599956D03*
X1671516Y609450D03*
X1677516D03*
X1667498Y659021D03*
X1664898D03*
X1675960Y1485895D03*
X1668000Y1711759D03*
Y1726909D03*
X1675351Y1737117D03*
X1684117Y28406D03*
X1691203D03*
Y40020D03*
X1684117D03*
X1686004Y75340D03*
X1688348Y790296D03*
Y800335D03*
Y827107D03*
Y837146D03*
Y863918D03*
Y873957D03*
Y910768D03*
Y900729D03*
Y937540D03*
Y947579D03*
Y1084784D03*
Y1094823D03*
Y1131634D03*
Y1121595D03*
Y1158406D03*
Y1168445D03*
Y1205256D03*
Y1195217D03*
Y1232028D03*
Y1242067D03*
X1684677Y1440258D03*
X1687357Y1440268D03*
X1698290Y28406D03*
X1705376D03*
X1698290Y40020D03*
X1697000Y69343D03*
X1701121Y641658D03*
X1706101D03*
X1695529Y1545193D03*
X1703000Y1711759D03*
X1697351Y1737117D03*
X1708004Y75340D03*
X1708305Y679720D03*
X1718049Y790296D03*
Y800335D03*
Y827107D03*
Y837146D03*
Y863918D03*
Y873957D03*
Y910768D03*
Y900729D03*
Y937540D03*
Y947579D03*
Y1084784D03*
Y1094823D03*
Y1131634D03*
Y1121595D03*
Y1158406D03*
Y1168445D03*
Y1195217D03*
Y1205256D03*
Y1232028D03*
Y1242067D03*
X1719351Y1737117D03*
X1735375Y-40925D03*
X1732350Y-39605D03*
X1735390Y-38410D03*
X1738628Y-40911D03*
X1738658Y-35881D03*
X1738673Y-33366D03*
X1738643Y-38396D03*
X1749571Y255317D03*
Y252317D03*
X1745502Y660088D03*
X1747750Y790296D03*
Y800335D03*
Y827107D03*
Y837146D03*
Y863918D03*
Y873957D03*
Y910768D03*
Y900729D03*
Y937540D03*
Y947579D03*
Y1084784D03*
Y1094823D03*
Y1131634D03*
Y1121595D03*
Y1158406D03*
Y1168445D03*
Y1205256D03*
Y1195217D03*
Y1232028D03*
Y1242067D03*
X1742120Y1708265D03*
Y1723415D03*
X1741351Y1737117D03*
X1753388Y28406D03*
X1760475D03*
X1754364Y100353D03*
X1764644Y122973D03*
X1755969Y251524D03*
Y248524D03*
X1763509Y251341D03*
Y248341D03*
X1763351Y1737117D03*
X1771881Y128439D03*
Y125939D03*
Y123439D03*
X1781966Y128501D03*
Y126001D03*
Y123501D03*
X1775984Y253779D03*
Y256779D03*
X1777450Y790296D03*
Y800335D03*
Y827107D03*
Y837146D03*
Y863918D03*
Y873957D03*
Y910768D03*
Y900729D03*
Y937540D03*
Y947579D03*
Y1084784D03*
Y1094823D03*
Y1131634D03*
Y1121595D03*
Y1158406D03*
Y1168445D03*
Y1205256D03*
Y1195217D03*
Y1232028D03*
Y1242067D03*
X1785072Y53161D03*
X1789811Y178083D03*
X1794629Y193323D03*
X1791645Y193397D03*
X1795219Y185910D03*
X1795949Y205580D03*
X1795909Y209128D03*
X1795365Y197567D03*
X1796019Y202030D03*
X1791445Y197497D03*
X1783592Y763765D03*
X1804111Y178083D03*
X1807711D03*
Y175083D03*
X1803165Y196127D03*
X1797621Y193373D03*
X1800389Y193424D03*
X1803045Y193397D03*
X1798943Y204744D03*
Y209044D03*
X1802276Y209013D03*
X1805235Y208950D03*
X1802276Y204713D03*
X1800125Y201857D03*
X1805235Y204650D03*
X1799629Y198870D03*
X1803145Y198697D03*
X1817674Y188699D03*
X1829732Y367359D03*
G54D24*
X67725Y1538946D03*
X74912D03*
X72585D03*
X70155D03*
X103468D03*
X105898D03*
X108328D03*
X110655D03*
X1757438Y1571982D03*
X1755008D03*
X1762195D03*
X1759868D03*
X1793181D03*
X1790751D03*
X1795611D03*
X1797938D03*
G54D28*
X130000Y1719450D03*
X543277Y88632D03*
X538620Y93289D03*
G54D63*
X1156378Y133866D03*
X1183858Y207205D03*
X1173858D03*
X1193858D03*
X1351260Y164213D03*
Y174213D03*
X1361260Y164213D03*
Y174213D03*
X1371260Y164213D03*
X1381260D03*
X1371260Y174213D03*
X1381260D03*
X1391260Y164213D03*
Y174213D03*
G54D20*
X35852Y670445D03*
Y667045D03*
Y681410D03*
Y678010D03*
Y692316D03*
Y703222D03*
Y688916D03*
Y699822D03*
X78265Y26477D03*
X74865D03*
X81970Y19541D03*
X85370D03*
X92438Y26477D03*
X89038D03*
X96143Y19541D03*
X90965Y960966D03*
X99543Y19541D03*
X106611Y26477D03*
X103211D03*
X110316Y19541D03*
X112473Y1660235D03*
X109073D03*
X107569Y1685763D03*
X110969D03*
X113716Y19541D03*
X120785Y26477D03*
X117385D03*
X124490Y19541D03*
X120666Y960966D03*
X127890Y19541D03*
X128724Y780257D03*
Y786950D03*
Y803682D03*
Y793643D03*
Y796989D03*
Y817068D03*
Y810375D03*
Y823761D03*
Y830454D03*
Y833800D03*
Y840493D03*
Y847186D03*
Y853879D03*
Y860572D03*
Y877304D03*
Y867265D03*
Y870611D03*
Y883997D03*
Y890690D03*
Y897383D03*
Y904076D03*
Y907423D03*
Y914115D03*
Y920808D03*
Y927501D03*
Y934194D03*
Y940887D03*
Y950926D03*
Y944234D03*
Y964312D03*
Y957619D03*
Y971005D03*
Y977698D03*
Y984391D03*
Y1001123D03*
Y997777D03*
Y991084D03*
Y1031241D03*
Y1037934D03*
Y1044627D03*
Y1058013D03*
Y1051320D03*
Y1074745D03*
Y1081438D03*
Y1088131D03*
Y1098171D03*
Y1104863D03*
Y1091478D03*
Y1111556D03*
Y1118249D03*
Y1134982D03*
Y1124942D03*
Y1128289D03*
Y1148367D03*
Y1141675D03*
Y1155060D03*
Y1161753D03*
Y1165100D03*
Y1171793D03*
Y1178486D03*
Y1185178D03*
Y1191871D03*
Y1208604D03*
Y1198564D03*
Y1201911D03*
Y1215297D03*
Y1221989D03*
Y1228682D03*
Y1235375D03*
Y1238722D03*
Y1245415D03*
Y1252108D03*
X156651Y26477D03*
X153251D03*
X144866Y776911D03*
Y783604D03*
Y790297D03*
Y800336D03*
Y807029D03*
Y793643D03*
Y813722D03*
Y820415D03*
Y837147D03*
Y830454D03*
Y827108D03*
Y843840D03*
Y850533D03*
Y857226D03*
Y863919D03*
Y873958D03*
Y880651D03*
Y867265D03*
Y887344D03*
Y894037D03*
Y910769D03*
Y904076D03*
Y900730D03*
Y924155D03*
Y917462D03*
Y930848D03*
Y940887D03*
Y937541D03*
Y947580D03*
Y954273D03*
Y967659D03*
Y974352D03*
Y981045D03*
Y987737D03*
Y994430D03*
Y1001123D03*
Y1027895D03*
Y1034588D03*
Y1041281D03*
Y1047974D03*
Y1054667D03*
Y1061360D03*
Y1071399D03*
Y1064706D03*
Y1078092D03*
Y1088131D03*
Y1084785D03*
Y1094824D03*
Y1101517D03*
Y1108210D03*
Y1114903D03*
Y1131635D03*
Y1124942D03*
Y1121596D03*
Y1138328D03*
Y1145021D03*
Y1151714D03*
Y1161753D03*
Y1158407D03*
Y1168446D03*
Y1175139D03*
Y1181832D03*
Y1188525D03*
Y1205257D03*
Y1198564D03*
Y1195218D03*
Y1211950D03*
Y1218643D03*
Y1225336D03*
Y1235375D03*
Y1232029D03*
Y1242068D03*
Y1248761D03*
X154945Y1624350D03*
Y1627750D03*
X170824Y26477D03*
X163756Y19541D03*
X167424Y26477D03*
X160356Y19541D03*
X158425Y780257D03*
Y786950D03*
Y803682D03*
Y793643D03*
Y796989D03*
Y817068D03*
Y810375D03*
Y823761D03*
Y830454D03*
Y833800D03*
Y840493D03*
Y847186D03*
Y853879D03*
Y860572D03*
Y877304D03*
Y867265D03*
Y870611D03*
Y883997D03*
Y890690D03*
Y897383D03*
Y904076D03*
Y907423D03*
Y914115D03*
Y920808D03*
Y927501D03*
Y934194D03*
Y940887D03*
Y950926D03*
Y944234D03*
Y964312D03*
Y957619D03*
Y971005D03*
Y977698D03*
Y984391D03*
Y1001123D03*
Y997777D03*
Y991084D03*
Y1031241D03*
Y1037934D03*
Y1044627D03*
Y1058013D03*
Y1051320D03*
Y1074745D03*
Y1081438D03*
Y1088131D03*
Y1098171D03*
Y1104863D03*
Y1091478D03*
Y1111556D03*
Y1118249D03*
Y1134982D03*
Y1124942D03*
Y1128289D03*
Y1148367D03*
Y1141675D03*
Y1155060D03*
Y1161753D03*
Y1165100D03*
Y1171793D03*
Y1178486D03*
Y1185178D03*
Y1191871D03*
Y1208604D03*
Y1198564D03*
Y1201911D03*
Y1215297D03*
Y1221989D03*
Y1228682D03*
Y1235375D03*
Y1238722D03*
Y1245415D03*
Y1252108D03*
X163735Y1635369D03*
Y1631969D03*
X177929Y19541D03*
X174529D03*
X174567Y776911D03*
Y783604D03*
Y790297D03*
Y800336D03*
Y807029D03*
Y793643D03*
Y813722D03*
Y820415D03*
Y837147D03*
Y830454D03*
Y827108D03*
Y843840D03*
Y850533D03*
Y857226D03*
Y863919D03*
Y873958D03*
Y880651D03*
Y867265D03*
Y887344D03*
Y894037D03*
Y910769D03*
Y904076D03*
Y900730D03*
Y924155D03*
Y917462D03*
Y930848D03*
Y940887D03*
Y937541D03*
Y947580D03*
Y954273D03*
Y967659D03*
Y974352D03*
Y981045D03*
Y987737D03*
Y994430D03*
Y1001123D03*
Y1027895D03*
Y1034588D03*
Y1041281D03*
Y1047974D03*
Y1054667D03*
Y1061360D03*
Y1071399D03*
Y1064706D03*
Y1078092D03*
Y1088131D03*
Y1084785D03*
Y1094824D03*
Y1101517D03*
Y1108210D03*
Y1114903D03*
Y1131635D03*
Y1124942D03*
Y1121596D03*
Y1138328D03*
Y1145021D03*
Y1151714D03*
Y1161753D03*
Y1158407D03*
Y1168446D03*
Y1175139D03*
Y1181832D03*
Y1188525D03*
Y1205257D03*
Y1198564D03*
Y1195218D03*
Y1211950D03*
Y1218643D03*
Y1225336D03*
Y1235375D03*
Y1232029D03*
Y1242068D03*
Y1248761D03*
X200785Y26477D03*
X197385D03*
X194196Y1602380D03*
X197596D03*
X194196Y1614292D03*
X197596D03*
X207890Y19541D03*
X214958Y26477D03*
X204490Y19541D03*
X211558Y26477D03*
X209768Y960966D03*
X206256Y1602380D03*
X209656D03*
X206256Y1614292D03*
X209656D03*
X222063Y19541D03*
X218663D03*
X218316Y1602380D03*
X230376D03*
X221716D03*
X218316Y1614292D03*
X230376D03*
X221716D03*
X242436Y1602380D03*
X233776D03*
X245836D03*
X242436Y1614292D03*
X233776D03*
X245836D03*
X254496Y1602380D03*
X257896D03*
X254496Y1614292D03*
X257896D03*
X266556Y1602380D03*
X269956D03*
X266556Y1614292D03*
X269956D03*
X291175Y1483590D03*
Y1480190D03*
Y1501990D03*
Y1505390D03*
X278616Y1602380D03*
X290676D03*
X282016D03*
X278616Y1614292D03*
X290676D03*
X282016D03*
X300813Y1462595D03*
X297413D03*
X304113Y1452895D03*
X302736Y1602380D03*
X294076D03*
X306136D03*
X302736Y1614292D03*
X294076D03*
X306136D03*
X307513Y1452895D03*
X320913Y1472295D03*
X317513D03*
X314796Y1602380D03*
X318196D03*
X314796Y1614292D03*
X318196D03*
X327613Y1462595D03*
X334313Y1452895D03*
X324213Y1462595D03*
X330913Y1452895D03*
X326856Y1602380D03*
X330256D03*
X326856Y1614292D03*
X330256D03*
X351013Y1462595D03*
X347713Y1472295D03*
X344313D03*
X338916Y1602380D03*
X350976D03*
X342316D03*
X338916Y1614292D03*
X350976D03*
X342316D03*
X354413Y1462595D03*
X361113Y1452895D03*
X357713D03*
X363036Y1602380D03*
X354376D03*
X363036Y1614292D03*
X354376D03*
X377813Y1462595D03*
X374513Y1472295D03*
X371113D03*
X375096Y1602380D03*
X366436D03*
X378496D03*
X375096Y1614292D03*
X366436D03*
X378496D03*
X390841Y-25571D03*
Y-22171D03*
Y-15571D03*
Y-12171D03*
X381213Y1462595D03*
X387913Y1452895D03*
X384513D03*
X401313D03*
X397913D03*
X408683Y1480682D03*
Y1484082D03*
Y1497482D03*
Y1494082D03*
X455502Y88711D03*
X452102D03*
X452339Y1592380D03*
X464399D03*
X455739D03*
X467799D03*
X458369Y1602380D03*
X461769D03*
X458369Y1614292D03*
X461769D03*
X476295Y130020D03*
X472895D03*
X476459Y1592380D03*
X479859D03*
X470429Y1602380D03*
X482489D03*
X473829D03*
X470429Y1614292D03*
X482489D03*
X473829D03*
X488519Y1592380D03*
X491919D03*
X494549Y1602380D03*
X485889D03*
X497949D03*
X494549Y1614292D03*
X485889D03*
X497949D03*
X500579Y1592380D03*
X512639D03*
X503979D03*
X506609Y1602380D03*
X510009D03*
X506609Y1614292D03*
X510009D03*
X524699Y1592380D03*
X516039D03*
X528099D03*
X518669Y1602380D03*
X522069D03*
X518669Y1614292D03*
X522069D03*
X536759Y1592380D03*
X540159D03*
X530729Y1602380D03*
X542789D03*
X534129D03*
X530729Y1614292D03*
X542789D03*
X534129D03*
X548819Y1592380D03*
X552219D03*
X554849Y1602380D03*
X546189D03*
X558249D03*
X554849Y1614292D03*
X546189D03*
X558249D03*
X572939Y1592380D03*
X560879D03*
X564279D03*
X566909Y1602380D03*
X570309D03*
X566909Y1614292D03*
X570309D03*
X584999Y1592380D03*
X576339D03*
X588399D03*
X578969Y1602380D03*
X582369D03*
X578969Y1614292D03*
X582369D03*
X597059Y1592380D03*
X600459D03*
X591029Y1602380D03*
X603089D03*
X594429D03*
X591029Y1614292D03*
X603089D03*
X594429D03*
X609119Y1592380D03*
X612519D03*
X615149Y1602380D03*
X606489D03*
X618549D03*
X615149Y1614292D03*
X606489D03*
X618549D03*
X621179Y1592380D03*
X633239D03*
X624579D03*
X627209Y1602380D03*
X630609D03*
X627209Y1614292D03*
X630609D03*
X636639Y1592380D03*
X639269Y1602380D03*
X642669D03*
X639269Y1614292D03*
X642669D03*
X653999Y1426757D03*
Y1423357D03*
X687697Y960966D03*
X691276Y1455112D03*
X704771Y179599D03*
Y182999D03*
Y194810D03*
Y191410D03*
Y206621D03*
Y203221D03*
Y218432D03*
Y215032D03*
X706756Y780257D03*
Y786950D03*
Y803682D03*
Y793643D03*
Y796989D03*
Y817068D03*
Y810375D03*
Y823761D03*
Y830454D03*
Y833800D03*
Y840493D03*
Y847186D03*
Y853879D03*
Y860572D03*
Y877304D03*
Y867265D03*
Y870611D03*
Y883997D03*
Y890690D03*
Y897383D03*
Y904076D03*
Y907423D03*
Y914115D03*
Y920808D03*
Y927501D03*
Y934194D03*
Y940887D03*
Y950926D03*
Y944234D03*
Y964312D03*
Y957619D03*
Y971005D03*
Y977698D03*
Y984391D03*
Y1001123D03*
Y997777D03*
Y991084D03*
Y1031241D03*
Y1037934D03*
Y1044627D03*
Y1058013D03*
Y1051320D03*
Y1074745D03*
Y1081438D03*
Y1088131D03*
Y1098171D03*
Y1104863D03*
Y1091478D03*
Y1111556D03*
Y1118249D03*
Y1134982D03*
Y1124942D03*
Y1128289D03*
Y1148367D03*
Y1141675D03*
Y1155060D03*
Y1161753D03*
Y1165100D03*
Y1171793D03*
Y1178486D03*
Y1185178D03*
Y1191871D03*
Y1208604D03*
Y1198564D03*
Y1201911D03*
Y1215297D03*
Y1221989D03*
Y1228682D03*
Y1235375D03*
Y1238722D03*
Y1245415D03*
Y1252108D03*
X694676Y1455112D03*
X722898Y776911D03*
Y783604D03*
Y790297D03*
Y800336D03*
Y807029D03*
Y793643D03*
Y813722D03*
Y820415D03*
Y837147D03*
Y830454D03*
Y827108D03*
Y843840D03*
Y850533D03*
Y857226D03*
Y863919D03*
Y873958D03*
Y880651D03*
Y867265D03*
Y887344D03*
Y894037D03*
Y910769D03*
Y904076D03*
Y900730D03*
Y924155D03*
Y917462D03*
Y930848D03*
Y940887D03*
Y937541D03*
Y947580D03*
Y954273D03*
Y967659D03*
Y974352D03*
Y981045D03*
Y987737D03*
Y994430D03*
Y1001123D03*
Y1027895D03*
Y1034588D03*
Y1041281D03*
Y1047974D03*
Y1054667D03*
Y1061360D03*
Y1071399D03*
Y1064706D03*
Y1078092D03*
Y1088131D03*
Y1084785D03*
Y1094824D03*
Y1101517D03*
Y1108210D03*
Y1114903D03*
Y1131635D03*
Y1124942D03*
Y1121596D03*
Y1138328D03*
Y1145021D03*
Y1151714D03*
Y1161753D03*
Y1158407D03*
Y1168446D03*
Y1175139D03*
Y1181832D03*
Y1188525D03*
Y1205257D03*
Y1198564D03*
Y1195218D03*
Y1211950D03*
Y1218643D03*
Y1225336D03*
Y1235375D03*
Y1232029D03*
Y1242068D03*
Y1248761D03*
X725925Y-25571D03*
Y-22171D03*
Y-15571D03*
Y-12171D03*
X736457Y780257D03*
Y786950D03*
Y803682D03*
Y793643D03*
Y796989D03*
Y817068D03*
Y810375D03*
Y823761D03*
Y830454D03*
Y833800D03*
Y840493D03*
Y847186D03*
Y853879D03*
Y860572D03*
Y877304D03*
Y867265D03*
Y870611D03*
Y883997D03*
Y890690D03*
Y897383D03*
Y904076D03*
Y907423D03*
Y914115D03*
Y920808D03*
Y927501D03*
Y934194D03*
Y940887D03*
Y950926D03*
Y944234D03*
Y964312D03*
Y957619D03*
Y971005D03*
Y977698D03*
Y984391D03*
Y1001123D03*
Y997777D03*
Y991084D03*
Y1031241D03*
Y1037934D03*
Y1044627D03*
Y1058013D03*
Y1051320D03*
Y1074745D03*
Y1081438D03*
Y1088131D03*
Y1098171D03*
Y1104863D03*
Y1091478D03*
Y1111556D03*
Y1118249D03*
Y1134982D03*
Y1124942D03*
Y1128289D03*
Y1148367D03*
Y1141675D03*
Y1155060D03*
Y1161753D03*
Y1165100D03*
Y1171793D03*
Y1178486D03*
Y1185178D03*
Y1191871D03*
Y1208604D03*
Y1198564D03*
Y1201911D03*
Y1215297D03*
Y1221989D03*
Y1228682D03*
Y1235375D03*
Y1238722D03*
Y1245415D03*
Y1252108D03*
X752599Y776911D03*
Y783604D03*
Y790297D03*
Y800336D03*
Y807029D03*
Y793643D03*
Y813722D03*
Y820415D03*
Y837147D03*
Y830454D03*
Y827108D03*
Y843840D03*
Y850533D03*
Y857226D03*
Y863919D03*
Y873958D03*
Y880651D03*
Y867265D03*
Y887344D03*
Y894037D03*
Y910769D03*
Y904076D03*
Y900730D03*
Y924155D03*
Y917462D03*
Y930848D03*
Y940887D03*
Y937541D03*
Y947580D03*
Y954273D03*
Y967659D03*
Y974352D03*
Y981045D03*
Y987737D03*
Y994430D03*
Y1001123D03*
Y1027895D03*
Y1034588D03*
Y1041281D03*
Y1047974D03*
Y1054667D03*
Y1061360D03*
Y1071399D03*
Y1064706D03*
Y1078092D03*
Y1088131D03*
Y1084785D03*
Y1094824D03*
Y1101517D03*
Y1108210D03*
Y1114903D03*
Y1131635D03*
Y1124942D03*
Y1121596D03*
Y1138328D03*
Y1145021D03*
Y1151714D03*
Y1161753D03*
Y1158407D03*
Y1168446D03*
Y1175139D03*
Y1181832D03*
Y1188525D03*
Y1205257D03*
Y1198564D03*
Y1195218D03*
Y1211950D03*
Y1218643D03*
Y1225336D03*
Y1235375D03*
Y1232029D03*
Y1242068D03*
Y1248761D03*
X776800Y960966D03*
X806500D03*
X814296Y1384045D03*
Y1387445D03*
X842320Y-11711D03*
Y-8311D03*
Y11689D03*
Y8289D03*
Y18289D03*
Y21689D03*
X1007587Y805418D03*
Y816352D03*
Y819752D03*
Y808818D03*
Y827354D03*
Y830754D03*
Y838356D03*
Y841756D03*
X1067107Y960965D03*
X1104866Y780256D03*
Y786949D03*
Y803681D03*
Y793642D03*
Y796988D03*
Y817067D03*
Y810374D03*
Y823760D03*
Y830453D03*
Y833799D03*
Y840492D03*
Y847185D03*
Y853878D03*
Y860571D03*
Y877303D03*
Y867264D03*
Y870610D03*
Y883996D03*
Y890689D03*
Y897382D03*
Y904075D03*
Y907422D03*
Y914114D03*
Y920807D03*
Y927500D03*
Y934193D03*
Y940886D03*
Y950925D03*
Y944233D03*
Y964311D03*
Y957618D03*
Y971004D03*
X1096808Y960965D03*
X1104866Y977697D03*
Y984390D03*
Y1001122D03*
Y997776D03*
Y991083D03*
Y1031240D03*
Y1037933D03*
Y1044626D03*
Y1058012D03*
Y1051319D03*
Y1074744D03*
Y1081437D03*
Y1088130D03*
Y1098170D03*
Y1104862D03*
Y1091477D03*
Y1111555D03*
Y1118248D03*
Y1134981D03*
Y1124941D03*
Y1128288D03*
Y1148366D03*
Y1141674D03*
Y1155059D03*
Y1161752D03*
Y1165099D03*
Y1171792D03*
Y1178485D03*
Y1185177D03*
Y1191870D03*
Y1208603D03*
Y1198563D03*
Y1201910D03*
Y1215296D03*
Y1221988D03*
Y1228681D03*
Y1235374D03*
Y1238721D03*
Y1245414D03*
Y1252107D03*
X1121008Y776910D03*
Y783603D03*
Y790296D03*
Y800335D03*
Y807028D03*
Y793642D03*
Y813721D03*
Y820414D03*
Y837146D03*
Y830453D03*
Y827107D03*
Y843839D03*
Y850532D03*
Y857225D03*
Y863918D03*
Y873957D03*
Y880650D03*
Y867264D03*
Y887343D03*
Y894036D03*
Y910768D03*
Y904075D03*
Y900729D03*
Y924154D03*
Y917461D03*
Y930847D03*
Y940886D03*
Y937540D03*
Y947579D03*
Y954272D03*
Y967658D03*
Y974351D03*
Y981044D03*
Y987736D03*
Y994429D03*
Y1001122D03*
Y1027894D03*
Y1034587D03*
Y1041280D03*
Y1047973D03*
Y1054666D03*
Y1061359D03*
Y1071398D03*
Y1064705D03*
Y1078091D03*
Y1088130D03*
Y1084784D03*
Y1094823D03*
Y1101516D03*
Y1108209D03*
Y1114902D03*
Y1131634D03*
Y1124941D03*
Y1121595D03*
Y1138327D03*
Y1145020D03*
Y1151713D03*
Y1161752D03*
Y1158406D03*
Y1168445D03*
Y1175138D03*
Y1181831D03*
Y1188524D03*
Y1205256D03*
Y1198563D03*
Y1195217D03*
Y1211949D03*
Y1218642D03*
Y1225335D03*
Y1235374D03*
Y1232028D03*
Y1242067D03*
Y1248760D03*
X1134567Y780256D03*
Y786949D03*
Y803681D03*
Y793642D03*
Y796988D03*
Y817067D03*
Y810374D03*
Y823760D03*
Y830453D03*
Y833799D03*
Y840492D03*
Y847185D03*
Y853878D03*
Y860571D03*
Y877303D03*
Y867264D03*
Y870610D03*
Y883996D03*
Y890689D03*
Y897382D03*
Y904075D03*
Y907422D03*
Y914114D03*
Y920807D03*
Y927500D03*
Y934193D03*
Y940886D03*
Y950925D03*
Y944233D03*
Y964311D03*
Y957618D03*
Y971004D03*
Y977697D03*
Y984390D03*
Y1001122D03*
Y997776D03*
Y991083D03*
Y1031240D03*
Y1037933D03*
Y1044626D03*
Y1058012D03*
Y1051319D03*
Y1074744D03*
Y1081437D03*
Y1088130D03*
Y1098170D03*
Y1104862D03*
Y1091477D03*
Y1111555D03*
Y1118248D03*
Y1134981D03*
Y1124941D03*
Y1128288D03*
Y1148366D03*
Y1141674D03*
Y1155059D03*
Y1161752D03*
Y1165099D03*
Y1171792D03*
Y1178485D03*
Y1185177D03*
Y1191870D03*
Y1208603D03*
Y1198563D03*
Y1201910D03*
Y1215296D03*
Y1221988D03*
Y1228681D03*
Y1235374D03*
Y1238721D03*
Y1245414D03*
Y1252107D03*
X1150709Y776910D03*
Y783603D03*
Y790296D03*
Y800335D03*
Y807028D03*
Y793642D03*
Y813721D03*
Y820414D03*
Y837146D03*
Y830453D03*
Y827107D03*
Y843839D03*
Y850532D03*
Y857225D03*
Y863918D03*
Y873957D03*
Y880650D03*
Y867264D03*
Y887343D03*
Y894036D03*
Y910768D03*
Y904075D03*
Y900729D03*
Y924154D03*
Y917461D03*
Y930847D03*
Y940886D03*
Y937540D03*
Y947579D03*
Y954272D03*
Y967658D03*
Y974351D03*
Y981044D03*
Y987736D03*
Y994429D03*
Y1001122D03*
Y1027894D03*
Y1034587D03*
Y1041280D03*
Y1047973D03*
Y1054666D03*
Y1061359D03*
Y1071398D03*
Y1064705D03*
Y1078091D03*
Y1088130D03*
Y1084784D03*
Y1094823D03*
Y1101516D03*
Y1108209D03*
Y1114902D03*
Y1131634D03*
Y1124941D03*
Y1121595D03*
Y1138327D03*
Y1145020D03*
Y1151713D03*
Y1161752D03*
Y1158406D03*
Y1168445D03*
Y1175138D03*
Y1181831D03*
Y1188524D03*
Y1205256D03*
Y1198563D03*
Y1195217D03*
Y1211949D03*
Y1218642D03*
Y1225335D03*
Y1235374D03*
Y1232028D03*
Y1242067D03*
Y1248760D03*
X1177404Y-11711D03*
Y-8311D03*
Y11689D03*
Y8289D03*
Y18289D03*
Y21689D03*
X1185910Y960965D03*
X1196039Y1625380D03*
X1199439D03*
X1208099D03*
X1211499D03*
X1202069Y1635380D03*
X1214129D03*
X1205469D03*
X1202069Y1647292D03*
X1214129D03*
X1205469D03*
X1220159Y1625380D03*
X1223559D03*
X1226189Y1635380D03*
X1217529D03*
X1229589D03*
X1226189Y1647292D03*
X1217529D03*
X1229589D03*
X1232219Y1625380D03*
X1244279D03*
X1235619D03*
X1238249Y1635380D03*
X1241649D03*
X1238249Y1647292D03*
X1241649D03*
X1245840Y-28311D03*
Y-31711D03*
Y-18311D03*
Y-21711D03*
Y11689D03*
Y8289D03*
X1256339Y1625380D03*
X1247679D03*
X1259739D03*
X1250309Y1635380D03*
X1253709D03*
X1250309Y1647292D03*
X1253709D03*
X1268399Y1625380D03*
X1271799D03*
X1262369Y1635380D03*
X1274429D03*
X1265769D03*
X1262369Y1647292D03*
X1274429D03*
X1265769D03*
X1280459Y1625380D03*
X1283859D03*
X1286489Y1635380D03*
X1277829D03*
X1289889D03*
X1286489Y1647292D03*
X1277829D03*
X1289889D03*
X1305286Y1495595D03*
X1299048Y1516590D03*
Y1513190D03*
Y1534990D03*
Y1538390D03*
X1292519Y1625380D03*
X1304579D03*
X1295919D03*
X1298549Y1635380D03*
X1301949D03*
X1298549Y1647292D03*
X1301949D03*
X1315386Y1485895D03*
X1311986D03*
X1308686Y1495595D03*
X1316639Y1625380D03*
X1320039D03*
X1307979D03*
X1310609Y1635380D03*
X1314009D03*
X1310609Y1647292D03*
X1314009D03*
X1328786Y1505295D03*
X1325386D03*
X1332086Y1495595D03*
X1328699Y1625380D03*
X1332099D03*
X1322669Y1635380D03*
X1334729D03*
X1326069D03*
X1322669Y1647292D03*
X1334729D03*
X1326069D03*
X1342186Y1485895D03*
X1338786D03*
X1335486Y1495595D03*
X1340759Y1625380D03*
X1344159D03*
X1346789Y1635380D03*
X1338129D03*
X1346789Y1647292D03*
X1338129D03*
X1355586Y1505295D03*
X1362286Y1495595D03*
X1352186Y1505295D03*
X1358886Y1495595D03*
X1352819Y1625380D03*
X1356219D03*
X1358849Y1635380D03*
X1350189D03*
X1362249D03*
X1358849Y1647292D03*
X1350189D03*
X1362249D03*
X1368986Y1485895D03*
X1365586D03*
X1378986Y1505295D03*
X1364879Y1625380D03*
X1376939D03*
X1368279D03*
X1370909Y1635380D03*
X1374309D03*
X1370909Y1647292D03*
X1374309D03*
X1392386Y1485895D03*
X1382386Y1505295D03*
X1389086Y1495595D03*
X1385686D03*
X1380339Y1625380D03*
X1382969Y1635380D03*
X1386369D03*
X1382969Y1647292D03*
X1386369D03*
X1395786Y1485895D03*
X1409186D03*
X1405786D03*
X1416556Y1513682D03*
Y1517082D03*
Y1530482D03*
Y1527082D03*
X1436263Y-28311D03*
Y-31711D03*
Y-18311D03*
Y-21711D03*
Y11689D03*
Y8289D03*
X1460213Y1625380D03*
X1463613D03*
X1466243Y1635380D03*
Y1647292D03*
X1472273Y1625380D03*
X1475673D03*
X1478303Y1635380D03*
X1469643D03*
X1481703D03*
X1478303Y1647292D03*
X1469643D03*
X1481703D03*
X1484333Y1625380D03*
X1496393D03*
X1487733D03*
X1490363Y1635380D03*
X1493763D03*
X1490363Y1647292D03*
X1493763D03*
X1508453Y1625380D03*
X1499793D03*
X1511853D03*
X1502423Y1635380D03*
X1505823D03*
X1502423Y1647292D03*
X1505823D03*
X1520513Y1625380D03*
X1523913D03*
X1514483Y1635380D03*
X1526543D03*
X1517883D03*
X1514483Y1647292D03*
X1526543D03*
X1517883D03*
X1539134Y-35912D03*
Y-32512D03*
Y-22512D03*
Y-25912D03*
X1535566Y69340D03*
X1538966D03*
X1532573Y1625380D03*
X1535973D03*
X1538603Y1635380D03*
X1529943D03*
X1542003D03*
X1538603Y1647292D03*
X1529943D03*
X1542003D03*
X1557566Y69340D03*
X1546562Y75343D03*
X1549962D03*
X1544633Y1625380D03*
X1556693D03*
X1548033D03*
X1550663Y1635380D03*
X1554063D03*
X1550663Y1647292D03*
X1554063D03*
X1568566Y75340D03*
X1571966D03*
X1560966Y69340D03*
X1568753Y1625380D03*
X1560093D03*
X1572153D03*
X1562723Y1635380D03*
X1566123D03*
X1562723Y1647292D03*
X1566123D03*
X1579566Y69340D03*
X1582966D03*
X1580813Y1625380D03*
X1584213D03*
X1586843Y1635380D03*
X1574783D03*
X1578183D03*
X1586843Y1647292D03*
X1574783D03*
X1578183D03*
X1590566Y75340D03*
X1601562Y69343D03*
X1593966Y75340D03*
X1592873Y1625380D03*
X1596273D03*
X1598903Y1635380D03*
X1590243D03*
X1602303D03*
X1598903Y1647292D03*
X1590243D03*
X1602303D03*
X1612566Y75340D03*
X1615966D03*
X1604962Y69343D03*
X1604933Y1625380D03*
X1616993D03*
X1608333D03*
X1610963Y1635380D03*
X1614363D03*
X1610963Y1647292D03*
X1614363D03*
X1623562Y69343D03*
X1626962D03*
X1629053Y1625380D03*
X1620393D03*
X1632453D03*
X1623023Y1635380D03*
X1626423D03*
X1623023Y1647292D03*
X1626423D03*
X1646770Y69340D03*
X1635770Y75340D03*
X1639170D03*
X1641113Y1625380D03*
X1644513D03*
X1635083Y1635380D03*
X1647143D03*
X1638483D03*
X1635083Y1647292D03*
X1647143D03*
X1638483D03*
X1657766Y75343D03*
X1661166D03*
X1650170Y69340D03*
X1650543Y1635380D03*
Y1647292D03*
X1668770Y69340D03*
X1672170D03*
X1663839Y960965D03*
X1690900Y69343D03*
X1679904Y75340D03*
X1683304D03*
X1682898Y780256D03*
Y786949D03*
Y803681D03*
Y793642D03*
Y796988D03*
Y817067D03*
Y810374D03*
Y823760D03*
Y830453D03*
Y833799D03*
Y840492D03*
Y847185D03*
Y853878D03*
Y860571D03*
Y877303D03*
Y867264D03*
Y870610D03*
Y883996D03*
Y890689D03*
Y897382D03*
Y904075D03*
Y907422D03*
Y914114D03*
Y920807D03*
Y927500D03*
Y934193D03*
Y940886D03*
Y950925D03*
Y944233D03*
Y964311D03*
Y957618D03*
Y971004D03*
Y977697D03*
Y984390D03*
Y1001122D03*
Y997776D03*
Y991083D03*
Y1031240D03*
Y1037933D03*
Y1044626D03*
Y1058012D03*
Y1051319D03*
Y1074744D03*
Y1081437D03*
Y1088130D03*
Y1098170D03*
Y1104862D03*
Y1091477D03*
Y1111555D03*
Y1118248D03*
Y1134981D03*
Y1124941D03*
Y1128288D03*
Y1148366D03*
Y1141674D03*
Y1155059D03*
Y1161752D03*
Y1165099D03*
Y1171792D03*
Y1178485D03*
Y1185177D03*
Y1191870D03*
Y1208603D03*
Y1198563D03*
Y1201910D03*
Y1215296D03*
Y1221988D03*
Y1228681D03*
Y1235374D03*
Y1238721D03*
Y1245414D03*
Y1252107D03*
X1701904Y75340D03*
X1705304D03*
X1694300Y69343D03*
X1699040Y776910D03*
Y783603D03*
Y790296D03*
Y800335D03*
Y807028D03*
Y793642D03*
Y813721D03*
Y820414D03*
Y837146D03*
Y830453D03*
Y827107D03*
Y843839D03*
Y850532D03*
Y857225D03*
Y863918D03*
Y873957D03*
Y880650D03*
Y867264D03*
Y887343D03*
Y894036D03*
Y910768D03*
Y904075D03*
Y900729D03*
Y924154D03*
Y917461D03*
Y930847D03*
Y940886D03*
Y937540D03*
Y947579D03*
Y954272D03*
Y967658D03*
Y974351D03*
Y981044D03*
Y987736D03*
Y994429D03*
Y1001122D03*
Y1027894D03*
Y1034587D03*
Y1041280D03*
Y1047973D03*
Y1054666D03*
Y1061359D03*
Y1071398D03*
Y1064705D03*
Y1078091D03*
Y1088130D03*
Y1084784D03*
Y1094823D03*
Y1101516D03*
Y1108209D03*
Y1114902D03*
Y1131634D03*
Y1124941D03*
Y1121595D03*
Y1138327D03*
Y1145020D03*
Y1151713D03*
Y1161752D03*
Y1158406D03*
Y1168445D03*
Y1175138D03*
Y1181831D03*
Y1188524D03*
Y1205256D03*
Y1198563D03*
Y1195217D03*
Y1211949D03*
Y1218642D03*
Y1225335D03*
Y1235374D03*
Y1232028D03*
Y1242067D03*
Y1248760D03*
X1712599Y780256D03*
Y786949D03*
Y803681D03*
Y793642D03*
Y796988D03*
Y817067D03*
Y810374D03*
Y823760D03*
Y830453D03*
Y833799D03*
Y840492D03*
Y847185D03*
Y853878D03*
Y860571D03*
Y877303D03*
Y867264D03*
Y870610D03*
Y883996D03*
Y890689D03*
Y897382D03*
Y904075D03*
Y907422D03*
Y914114D03*
Y920807D03*
Y927500D03*
Y934193D03*
Y940886D03*
Y950925D03*
Y944233D03*
Y964311D03*
Y957618D03*
Y971004D03*
Y977697D03*
Y984390D03*
Y1001122D03*
Y997776D03*
Y991083D03*
Y1031240D03*
Y1037933D03*
Y1044626D03*
Y1058012D03*
Y1051319D03*
Y1074744D03*
Y1081437D03*
Y1088130D03*
Y1098170D03*
Y1104862D03*
Y1091477D03*
Y1111555D03*
Y1118248D03*
Y1134981D03*
Y1124941D03*
Y1128288D03*
Y1148366D03*
Y1141674D03*
Y1155059D03*
Y1161752D03*
Y1165099D03*
Y1171792D03*
Y1178485D03*
Y1185177D03*
Y1191870D03*
Y1208603D03*
Y1198563D03*
Y1201910D03*
Y1215296D03*
Y1221988D03*
Y1228681D03*
Y1235374D03*
Y1238721D03*
Y1245414D03*
Y1252107D03*
X1729557Y-35912D03*
Y-32512D03*
Y-22512D03*
Y-25912D03*
X1728741Y776910D03*
Y783603D03*
Y790296D03*
Y800335D03*
Y807028D03*
Y793642D03*
Y813721D03*
Y820414D03*
Y837146D03*
Y830453D03*
Y827107D03*
Y843839D03*
Y850532D03*
Y857225D03*
Y863918D03*
Y873957D03*
Y880650D03*
Y867264D03*
Y887343D03*
Y894036D03*
Y910768D03*
Y904075D03*
Y900729D03*
Y924154D03*
Y917461D03*
Y930847D03*
Y940886D03*
Y937540D03*
Y947579D03*
Y954272D03*
Y967658D03*
Y974351D03*
Y981044D03*
Y987736D03*
Y994429D03*
Y1001122D03*
Y1027894D03*
Y1034587D03*
Y1041280D03*
Y1047973D03*
Y1054666D03*
Y1061359D03*
Y1071398D03*
Y1064705D03*
Y1078091D03*
Y1088130D03*
Y1084784D03*
Y1094823D03*
Y1101516D03*
Y1108209D03*
Y1114902D03*
Y1131634D03*
Y1124941D03*
Y1121595D03*
Y1138327D03*
Y1145020D03*
Y1151713D03*
Y1161752D03*
Y1158406D03*
Y1168445D03*
Y1175138D03*
Y1181831D03*
Y1188524D03*
Y1205256D03*
Y1198563D03*
Y1195217D03*
Y1211949D03*
Y1218642D03*
Y1225335D03*
Y1235374D03*
Y1232028D03*
Y1242067D03*
Y1248760D03*
X1752942Y960965D03*
X1782642D03*
G54D22*
X60303Y20354D03*
X312921Y24291D03*
X505185Y41141D03*
X757803Y45078D03*
X929331Y160413D03*
X922441Y237697D03*
X1534712Y20354D03*
X1787330Y24291D03*
G54D31*
X205478Y1536063D03*
X210202D03*
X219651D03*
X229100D03*
X233824D03*
X243273D03*
X253002Y1514243D03*
X252722Y1536063D03*
X302413Y906182D03*
Y912560D03*
Y918938D03*
Y925316D03*
Y931694D03*
Y938072D03*
Y944450D03*
Y950828D03*
Y957206D03*
Y963584D03*
Y969962D03*
Y976340D03*
Y982718D03*
Y989096D03*
Y995474D03*
Y1008230D03*
Y1001852D03*
X303594Y1030198D03*
Y1036576D03*
Y1042954D03*
Y1055710D03*
Y1049332D03*
Y1062088D03*
Y1074844D03*
Y1068466D03*
Y1081222D03*
Y1087600D03*
Y1093978D03*
Y1100356D03*
Y1106734D03*
Y1113112D03*
Y1119490D03*
Y1125868D03*
Y1132246D03*
Y1138623D03*
Y1145001D03*
Y1157757D03*
Y1151379D03*
X333540Y1536063D03*
X338264D03*
X347713D03*
X357162D03*
X361886D03*
X380784D03*
X371335D03*
X381064Y1514243D03*
X408614Y997608D03*
X410464Y1007175D03*
X404923Y1010366D03*
X423417Y997608D03*
X416015D03*
X430819D03*
X445622D03*
X453023D03*
X467826D03*
X460425D03*
X469651Y1536063D03*
X483824D03*
X474375D03*
X497997D03*
X493273D03*
X507446D03*
X526370Y1165290D03*
X515268D03*
X518969D03*
X522670D03*
X517175Y1514243D03*
X516895Y1536063D03*
X533772Y1165290D03*
X530071D03*
X602437Y1536063D03*
X597713D03*
X611886D03*
X626059D03*
X621335D03*
X645237Y1514243D03*
X644957Y1536063D03*
X635508D03*
X1213351Y1569063D03*
X1227524D03*
X1218075D03*
X1241697D03*
X1236973D03*
X1251146D03*
X1260875Y1547243D03*
X1260595Y1569063D03*
X1278555Y906181D03*
Y912559D03*
Y918937D03*
Y925315D03*
Y931693D03*
Y938071D03*
Y950827D03*
Y944449D03*
Y957205D03*
Y963583D03*
Y969961D03*
Y976339D03*
Y982717D03*
Y995473D03*
Y989095D03*
Y1008229D03*
Y1001851D03*
X1279736Y1030197D03*
Y1042953D03*
Y1036575D03*
Y1055709D03*
Y1049331D03*
Y1062087D03*
Y1068465D03*
Y1074843D03*
Y1081221D03*
Y1087599D03*
Y1093977D03*
Y1100355D03*
Y1106733D03*
Y1113111D03*
Y1119489D03*
Y1125867D03*
Y1132245D03*
Y1138622D03*
Y1145000D03*
Y1151378D03*
Y1157756D03*
X1346137Y1569063D03*
X1341413D03*
X1355586D03*
X1379208D03*
X1369759D03*
X1365035D03*
X1384756Y997607D03*
X1392157D03*
X1386606Y1007174D03*
X1381065Y1010365D03*
X1388937Y1547243D03*
X1388657Y1569063D03*
X1406961Y997607D03*
X1399559D03*
X1421764D03*
X1436567D03*
X1429165D03*
X1443968D03*
X1482249Y1569063D03*
X1477525D03*
X1491698D03*
X1502512Y1165289D03*
X1505871Y1569063D03*
X1501147D03*
X1525049Y1547243D03*
X1524769Y1569063D03*
X1515320D03*
X1610311D03*
X1605587D03*
X1629209D03*
X1619760D03*
X1643382D03*
X1633933D03*
X1653111Y1547243D03*
X1652831Y1569063D03*
G54D43*
X381770Y-30570D03*
X385023Y-30584D03*
X388048Y-29264D03*
X381755Y-28055D03*
X385008Y-28069D03*
X381740Y-25540D03*
X381725Y-23025D03*
X723479Y-19234D03*
Y-9234D03*
X833421Y-36647D03*
X839699Y-35341D03*
X833406Y-34132D03*
X836674Y-36661D03*
X836659Y-34146D03*
X833391Y-31617D03*
X833376Y-29102D03*
X836644Y-31631D03*
X836629Y-29116D03*
X1174958Y-15374D03*
Y-5374D03*
Y24626D03*
X1433817Y-25374D03*
Y-15374D03*
Y14626D03*
X1530063Y-40911D03*
X1530033Y-35881D03*
X1530018Y-33366D03*
X1530048Y-38396D03*
X1533316Y-40925D03*
X1536341Y-39605D03*
X1533301Y-38410D03*
X1727111Y-19575D03*
G54D81*
X1898799Y1198198D03*
X1908799D03*
X1921395Y-39963D03*
X1931395D03*
X1942395Y572417D03*
X1940886Y1198170D03*
X1963362Y-39821D03*
X1952395Y572417D03*
X1950886Y1198170D03*
X1973362Y-39821D03*
X1984482Y572389D03*
X1982856Y1198350D03*
X1992856D03*
X2005452Y-39811D03*
X1994482Y572389D03*
X2015452Y-39811D03*
X2026452Y572569D03*
X2036452D03*
X2047419Y-39669D03*
X2057419D03*
X2068539Y572541D03*
X2078539D03*
G54D47*
X539016Y274272D03*
X559016D03*
X569016D03*
X579016D03*
X589016D03*
X599016D03*
X609016D03*
G54D61*
X918780Y1684890D03*
Y1694890D03*
Y1714890D03*
X928780Y1684890D03*
Y1694890D03*
Y1704890D03*
Y1714890D03*
X938780Y1684890D03*
Y1694890D03*
Y1704890D03*
Y1714890D03*
G54D66*
X1225530Y67471D03*
X1454797Y80345D03*
G54D79*
X1900275Y-29973D03*
Y562227D03*
X1898799Y1208198D03*
Y1800398D03*
X1910275Y-29973D03*
Y562227D03*
X1908799Y1208198D03*
Y1800398D03*
X1921395Y-29963D03*
X1931395D03*
Y562237D03*
X1921395D03*
X1931395Y582237D03*
X1921395D03*
Y1174437D03*
X1931395D03*
X1929766Y1208160D03*
X1919766D03*
Y1800360D03*
X1929766D03*
X1942395Y-29783D03*
Y562417D03*
Y582417D03*
Y1174617D03*
X1940886Y1208170D03*
Y1800370D03*
X1952395Y-29783D03*
Y562417D03*
Y582417D03*
Y1174617D03*
X1950886Y1208170D03*
X1961856D03*
X1950886Y1800370D03*
X1961856D03*
X1963362Y-29821D03*
X1973362D03*
Y562379D03*
X1963362D03*
X1973362Y582379D03*
X1963362D03*
Y1174579D03*
X1973362D03*
X1971856Y1208170D03*
Y1800370D03*
X1984482Y-29811D03*
Y562389D03*
Y582389D03*
Y1174589D03*
X1982856Y1208350D03*
Y1800550D03*
X1994482Y-29811D03*
X2005452D03*
X1994482Y562389D03*
X2005452D03*
Y582389D03*
X1994482D03*
Y1174589D03*
X2005452D03*
X1992856Y1208350D03*
X2003823Y1208312D03*
X1992856Y1800550D03*
X2003823Y1800512D03*
X2015452Y-29811D03*
Y562389D03*
Y582389D03*
Y1174589D03*
X2013823Y1208312D03*
Y1800512D03*
X2036452Y-29631D03*
X2026452D03*
Y562569D03*
X2036452D03*
X2026452Y582569D03*
X2036452D03*
Y1174769D03*
X2026452D03*
X2047419Y-29669D03*
Y562531D03*
Y582531D03*
Y1174731D03*
X2057419Y-29669D03*
Y562531D03*
Y582531D03*
Y1174731D03*
X2068539Y582541D03*
X2078539D03*
Y1174741D03*
X2068539D03*
G54D80*
X1900275Y572227D03*
X1910275D03*
X1921395Y1184437D03*
X1931395D03*
X1919766Y1810360D03*
X1929766D03*
X1942395Y572417D03*
X1952395D03*
X1963362Y1184579D03*
X1961856Y1810370D03*
X1973362Y1184579D03*
X1971856Y1810370D03*
X1984482Y572389D03*
X1994482D03*
X2005452Y1184589D03*
X2003823Y1810512D03*
X2015452Y1184589D03*
X2013823Y1810512D03*
X2026452Y572569D03*
X2036452D03*
X2047419Y1184731D03*
X2057419D03*
G54D50*
X676509Y224606D03*
G54D41*
X358665Y886002D03*
X364217Y889191D03*
X356815D03*
X362366Y892380D03*
X356815Y895569D03*
X364217D03*
X358665Y892380D03*
X356815Y908325D03*
X362366Y911513D03*
X358665Y898758D03*
X364217Y901947D03*
X356815D03*
X362366Y905135D03*
X358665D03*
X364217Y908325D03*
X358665Y911513D03*
X362366Y898758D03*
X358665Y917891D03*
X364217Y921080D03*
X356815D03*
X362366Y924269D03*
X358665D03*
X356815Y914702D03*
X364217D03*
X362366Y917891D03*
X364217Y927458D03*
X356815D03*
X362366Y930647D03*
X358665Y937025D03*
X364217Y940214D03*
X356815D03*
Y933836D03*
X364217D03*
X358665Y930647D03*
X362366Y937025D03*
Y943403D03*
X358665D03*
X364217Y946592D03*
X356815D03*
X362366Y949781D03*
X358665Y956159D03*
X356815Y952970D03*
X364217D03*
X358665Y949781D03*
X362366Y956159D03*
X358665Y962537D03*
X364217Y965726D03*
X356815D03*
X362366Y968915D03*
X364217Y959348D03*
X356815D03*
X362366Y962537D03*
X358665Y968915D03*
X364217Y984860D03*
X358665Y975293D03*
X364217Y978482D03*
X356815D03*
X362366Y981671D03*
X356815Y972104D03*
X364217D03*
X362366Y975293D03*
Y988049D03*
X358665Y994427D03*
X356815Y997616D03*
X364217D03*
X362366Y1000805D03*
X358665D03*
X356815Y991238D03*
X362366Y994427D03*
X356815Y1010372D03*
X358665Y1007183D03*
X356815Y1003994D03*
X364217D03*
X362366Y1007183D03*
X363547Y1031245D03*
X365398Y1034434D03*
X357996D03*
X359847Y1037623D03*
X363547D03*
X365398Y1040812D03*
X357996D03*
X359847Y1044001D03*
X363547Y1050379D03*
X357996Y1059946D03*
X365398Y1047190D03*
X359847Y1050379D03*
X357996Y1053568D03*
Y1072702D03*
X363547Y1063135D03*
X359847D03*
X365398Y1066324D03*
X363547Y1069513D03*
X359847D03*
X365398Y1072702D03*
X357996Y1066324D03*
X363547Y1075891D03*
X359847D03*
X365398Y1079080D03*
X357996D03*
X363547Y1082269D03*
X359847D03*
X365398Y1085458D03*
X359847Y1088647D03*
X363547D03*
X357996Y1085458D03*
X359847Y1101403D03*
X365398Y1104592D03*
X357996Y1091836D03*
X363547Y1095025D03*
X359847D03*
X365398Y1098214D03*
X357996D03*
X363547Y1101403D03*
X357996Y1104592D03*
X365398Y1091836D03*
X357996Y1110970D03*
X363547Y1114159D03*
X359847D03*
X365398Y1117348D03*
X357996D03*
X359847Y1107781D03*
X363547D03*
X365398Y1110970D03*
X363547Y1120537D03*
X359847D03*
X365398Y1123726D03*
X357996Y1130103D03*
X363547Y1133293D03*
X359847D03*
Y1126915D03*
X363547D03*
X357996Y1123726D03*
X365398Y1130103D03*
Y1136481D03*
X357996D03*
X363547Y1139670D03*
X359847D03*
X365398Y1142859D03*
X357996Y1149237D03*
X359847Y1146048D03*
X363547D03*
X357996Y1142859D03*
X365398Y1149237D03*
X363547Y1152426D03*
X359847D03*
X357996Y1155615D03*
X369768Y886002D03*
X375319Y889191D03*
X371618D03*
X377169Y892380D03*
X371618Y895569D03*
X375319D03*
X369768Y892380D03*
X371618Y908325D03*
X377169Y911513D03*
X369768Y898758D03*
X375319Y901947D03*
X371618D03*
X377169Y905135D03*
X369768D03*
X375319Y908325D03*
X369768Y911513D03*
X377169Y898758D03*
X369768Y917891D03*
X375319Y921080D03*
X371618D03*
X377169Y924269D03*
X369768D03*
X371618Y914702D03*
X375319D03*
X377169Y917891D03*
X375319Y927458D03*
X371618D03*
X377169Y930647D03*
X369768Y937025D03*
X375319Y940214D03*
X371618D03*
Y933836D03*
X375319D03*
X369768Y930647D03*
X377169Y937025D03*
Y943403D03*
X369768D03*
X375319Y946592D03*
X371618D03*
X377169Y949781D03*
X369768Y956159D03*
X371618Y952970D03*
X375319D03*
X369768Y949781D03*
X377169Y956159D03*
X369768Y962537D03*
X375319Y965726D03*
X371618D03*
X377169Y968915D03*
X375319Y959348D03*
X371618D03*
X377169Y962537D03*
X369768Y968915D03*
X375319Y984860D03*
X369768Y975293D03*
X375319Y978482D03*
X371618D03*
X377169Y981671D03*
X371618Y972104D03*
X375319D03*
X377169Y975293D03*
Y988049D03*
X369768Y994427D03*
X371618Y997616D03*
X375319D03*
X377169Y1000805D03*
X369768D03*
X371618Y991238D03*
X377169Y994427D03*
X371618Y1010372D03*
X369768Y1007183D03*
X371618Y1003994D03*
X375319D03*
X377169Y1007183D03*
X378351Y1031245D03*
X376500Y1034434D03*
X372799D03*
X370949Y1037623D03*
X378351D03*
X376500Y1040812D03*
X372799D03*
X370949Y1044001D03*
X378351Y1050379D03*
X372799Y1059946D03*
X376500Y1047190D03*
X370949Y1050379D03*
X372799Y1053568D03*
Y1072702D03*
X378351Y1063135D03*
X370949D03*
X376500Y1066324D03*
X378351Y1069513D03*
X370949D03*
X376500Y1072702D03*
X372799Y1066324D03*
X378351Y1075891D03*
X370949D03*
X376500Y1079080D03*
X372799D03*
X378351Y1082269D03*
X370949D03*
X376500Y1085458D03*
X370949Y1088647D03*
X378351D03*
X372799Y1085458D03*
X370949Y1101403D03*
X376500Y1104592D03*
X372799Y1091836D03*
X378351Y1095025D03*
X370949D03*
X376500Y1098214D03*
X372799D03*
X378351Y1101403D03*
X372799Y1104592D03*
X376500Y1091836D03*
X372799Y1110970D03*
X378351Y1114159D03*
X370949D03*
X376500Y1117348D03*
X372799D03*
X370949Y1107781D03*
X378351D03*
X376500Y1110970D03*
X378351Y1120537D03*
X370949D03*
X376500Y1123726D03*
X372799Y1130103D03*
X378351Y1133293D03*
X370949D03*
Y1126915D03*
X378351D03*
X372799Y1123726D03*
X376500Y1130103D03*
Y1136481D03*
X372799D03*
X378351Y1139670D03*
X370949D03*
X376500Y1142859D03*
X372799Y1149237D03*
X370949Y1146048D03*
X378351D03*
X372799Y1142859D03*
X376500Y1149237D03*
X378351Y1152426D03*
X370949D03*
X376500Y1155615D03*
X388272Y892380D03*
X384571D03*
X395673D03*
X388272Y911513D03*
Y898758D03*
Y905135D03*
X384571Y911513D03*
Y898758D03*
Y905135D03*
X395673Y898758D03*
Y905135D03*
Y911513D03*
X388272Y924269D03*
Y917891D03*
X384571Y924269D03*
Y917891D03*
X395673Y924269D03*
Y917891D03*
X388272Y930647D03*
X384571D03*
X395673D03*
X389453Y1126915D03*
Y1133293D03*
X385752Y1126915D03*
Y1133293D03*
X389453Y1139670D03*
Y1146048D03*
X385752Y1139670D03*
Y1146048D03*
Y1158804D03*
X382051D03*
X393154D03*
X389453Y1152426D03*
X385752D03*
X399374Y892380D03*
X410477D03*
X406776D03*
X399374Y898758D03*
Y905135D03*
X410477Y898758D03*
Y905135D03*
X406776Y898758D03*
Y905135D03*
X399374Y911513D03*
X410477D03*
X406776D03*
X399374Y924269D03*
Y917891D03*
X410477D03*
Y924269D03*
X406776Y917891D03*
Y924269D03*
X399374Y930647D03*
X400555Y1133293D03*
X396855D03*
X407957D03*
X400555Y1139670D03*
Y1146048D03*
X396855Y1139670D03*
Y1146048D03*
X407957Y1139670D03*
Y1146048D03*
X396855Y1158804D03*
X407957D03*
X404256D03*
X400555Y1152426D03*
X396855D03*
X407957D03*
X421579Y892380D03*
X417878D03*
X421579Y898758D03*
Y905135D03*
X417878Y898758D03*
Y905135D03*
X421579Y911513D03*
X417878D03*
X421579Y917891D03*
Y924269D03*
X417878Y917891D03*
Y924269D03*
X422760Y1133293D03*
X411658D03*
X419059D03*
X422760Y1139670D03*
Y1146048D03*
X411658Y1139670D03*
Y1146048D03*
X419059Y1139670D03*
Y1146048D03*
Y1158804D03*
X415358D03*
X411658Y1152426D03*
X422760D03*
X419059D03*
X430831Y895569D03*
X427130D03*
X430831Y901947D03*
Y908325D03*
X427130Y901947D03*
Y908325D03*
X430831Y914702D03*
Y921080D03*
X427130Y914702D03*
Y921080D03*
X430831Y927458D03*
X427130D03*
X432012Y1130103D03*
X428311D03*
X432012Y1142859D03*
Y1136481D03*
X428311Y1142859D03*
Y1136481D03*
X449310Y895569D03*
X453011D03*
X449310Y908325D03*
Y901947D03*
X453011Y908325D03*
Y901947D03*
X450491Y1130103D03*
X454192D03*
X450491Y1136481D03*
Y1142859D03*
X454192Y1136481D03*
Y1142859D03*
X452328Y1516970D03*
X453903Y1519698D03*
X458562Y892380D03*
X469664D03*
X462263D03*
X458562Y905135D03*
Y898758D03*
X469664Y905135D03*
Y898758D03*
X462263Y905135D03*
Y898758D03*
X459743Y1133293D03*
X463444D03*
X459743Y1146048D03*
Y1139670D03*
X463444Y1146048D03*
Y1139670D03*
X457052Y1516970D03*
X461777D03*
X466501D03*
X458627Y1519698D03*
X463351D03*
X468076D03*
X480767Y892380D03*
X484467D03*
X473365D03*
X480767Y898758D03*
Y905135D03*
X484467Y898758D03*
X473365Y905135D03*
Y898758D03*
X484467Y905135D03*
X470845Y1133293D03*
X481948D03*
X474546D03*
X481948Y1146048D03*
Y1139670D03*
X470845Y1146048D03*
Y1139670D03*
X474546Y1146048D03*
Y1139670D03*
X471225Y1516970D03*
X475950D03*
X480674D03*
X472800Y1519698D03*
X477525D03*
X482249D03*
X491869Y892380D03*
X495570D03*
X491869Y905135D03*
Y898758D03*
Y911513D03*
X495570Y905135D03*
Y898758D03*
Y911513D03*
X493050Y1133293D03*
Y1126915D03*
X496751Y1133293D03*
Y1126915D03*
X485649Y1133293D03*
X493050Y1146048D03*
Y1139670D03*
X485649Y1146048D03*
Y1139670D03*
X496751Y1146048D03*
Y1139670D03*
X499572Y1516970D03*
X485399D03*
X490123D03*
X494847D03*
X486973Y1519698D03*
X491698D03*
X496422D03*
X510373Y886002D03*
X504822Y889191D03*
X508523D03*
X502971Y892380D03*
X508523Y895569D03*
X504822D03*
X510373Y892380D03*
X508523Y908325D03*
X502971Y911513D03*
X510373Y898758D03*
X504822Y901947D03*
X508523D03*
X502971Y905135D03*
X510373D03*
X504822Y908325D03*
X510373Y911513D03*
X502971Y898758D03*
X510373Y917891D03*
X504822Y921080D03*
X508523D03*
X502971Y924269D03*
X510373D03*
X508523Y914702D03*
X504822D03*
X502971Y917891D03*
X504822Y927458D03*
X508523D03*
X502971Y930647D03*
X510373Y937025D03*
X504822Y940214D03*
X508523D03*
Y933836D03*
X504822D03*
X510373Y930647D03*
X502971Y937025D03*
Y943403D03*
X510373D03*
X504822Y946592D03*
X508523D03*
X502971Y949781D03*
X510373Y956159D03*
X508523Y952970D03*
X504822D03*
X510373Y949781D03*
X502971Y956159D03*
X510373Y962537D03*
X504822Y965726D03*
X508523D03*
X502971Y968915D03*
X504822Y959348D03*
X508523D03*
X502971Y962537D03*
X510373Y968915D03*
X504822Y984860D03*
X510373Y975293D03*
X504822Y978482D03*
X508523D03*
X502971Y981671D03*
X508523Y972104D03*
X504822D03*
X502971Y975293D03*
Y988049D03*
X510373Y994427D03*
X508523Y997616D03*
X504822D03*
X502971Y1000805D03*
X510373D03*
Y988049D03*
X504822Y991238D03*
X508523Y1010372D03*
X510373Y1007183D03*
X508523Y1003994D03*
X504822D03*
X502971Y1007183D03*
X504153Y1031245D03*
X506003Y1034434D03*
X509704D03*
X511554Y1037623D03*
X504153D03*
X506003Y1040812D03*
X509704D03*
X504153Y1044001D03*
Y1050379D03*
X509704Y1059946D03*
X506003Y1047190D03*
X511554Y1050379D03*
X509704Y1053568D03*
Y1072702D03*
X504153Y1063135D03*
X511554D03*
X506003Y1066324D03*
X504153Y1069513D03*
X511554D03*
X506003Y1072702D03*
X509704Y1066324D03*
X504153Y1075891D03*
X511554D03*
X506003Y1079080D03*
X509704D03*
X504153Y1082269D03*
X511554D03*
X506003Y1085458D03*
X511554Y1088647D03*
X504153D03*
X509704Y1085458D03*
X511554Y1101403D03*
X506003Y1104592D03*
X509704Y1091836D03*
X504153Y1095025D03*
X511554D03*
X506003Y1098214D03*
X509704D03*
X504153Y1101403D03*
X509704Y1104592D03*
X506003Y1091836D03*
X509704Y1110970D03*
X504153Y1114159D03*
X511554D03*
X506003Y1117348D03*
X509704D03*
X511554Y1107781D03*
X504153D03*
X506003Y1110970D03*
X504153Y1120537D03*
X511554D03*
X506003Y1123726D03*
X509704Y1130103D03*
X504153Y1133293D03*
X511554D03*
Y1126915D03*
X504153D03*
X509704Y1123726D03*
X506003Y1130103D03*
Y1136481D03*
X509704D03*
X504153Y1139670D03*
X511554D03*
X506003Y1142859D03*
X509704Y1149237D03*
X511554Y1146048D03*
X504153D03*
X509704Y1142859D03*
X506003Y1149237D03*
X504153Y1152426D03*
X511554D03*
X506003Y1155615D03*
X504296Y1516970D03*
X509021D03*
X513745D03*
X501147Y1519698D03*
X505871D03*
X510595D03*
X521475Y886002D03*
X515924Y889191D03*
X523326D03*
X517775Y892380D03*
X523326Y895569D03*
X515924D03*
X521475Y892380D03*
X523326Y908325D03*
X517775Y911513D03*
X521475Y898758D03*
X515924Y901947D03*
X523326D03*
X517775Y905135D03*
X521475D03*
X515924Y908325D03*
X521475Y911513D03*
X517775Y898758D03*
X521475Y917891D03*
X515924Y921080D03*
X523326D03*
X517775Y924269D03*
X521475D03*
X523326Y914702D03*
X515924D03*
X517775Y917891D03*
X515924Y927458D03*
X523326D03*
X517775Y930647D03*
X521475Y937025D03*
X515924Y940214D03*
X523326D03*
Y933836D03*
X515924D03*
X521475Y930647D03*
X517775Y937025D03*
Y943403D03*
X521475D03*
X515924Y946592D03*
X523326D03*
X517775Y949781D03*
X521475Y956159D03*
X523326Y952970D03*
X515924D03*
X521475Y949781D03*
X517775Y956159D03*
X521475Y962537D03*
X515924Y965726D03*
X523326D03*
X517775Y968915D03*
X515924Y959348D03*
X523326D03*
X517775Y962537D03*
X521475Y968915D03*
X515924Y984860D03*
X521475Y975293D03*
X515924Y978482D03*
X523326D03*
X517775Y981671D03*
X523326Y972104D03*
X515924D03*
X517775Y975293D03*
Y988049D03*
X521475Y994427D03*
X523326Y997616D03*
X515924D03*
X517775Y1000805D03*
X521475D03*
Y988049D03*
X515924Y991238D03*
X523326Y1010372D03*
X521475Y1007183D03*
X523326Y1003994D03*
X515924D03*
X517775Y1007183D03*
X518956Y1031245D03*
X517105Y1034434D03*
X524507D03*
X522657Y1037623D03*
X518956D03*
X517105Y1040812D03*
X524507D03*
X518956Y1044001D03*
Y1050379D03*
X524507Y1059946D03*
X517105Y1047190D03*
X522657Y1050379D03*
X524507Y1053568D03*
Y1072702D03*
X518956Y1063135D03*
X522657D03*
X517105Y1066324D03*
X518956Y1069513D03*
X522657D03*
X517105Y1072702D03*
X524507Y1066324D03*
X518956Y1075891D03*
X522657D03*
X517105Y1079080D03*
X524507D03*
X518956Y1082269D03*
X522657D03*
X517105Y1085458D03*
X522657Y1088647D03*
X518956D03*
X524507Y1085458D03*
X522657Y1101403D03*
X517105Y1104592D03*
X524507Y1091836D03*
X518956Y1095025D03*
X522657D03*
X517105Y1098214D03*
X524507D03*
X518956Y1101403D03*
X524507Y1104592D03*
X517105Y1091836D03*
X524507Y1110970D03*
X518956Y1114159D03*
X522657D03*
X517105Y1117348D03*
X524507D03*
X522657Y1107781D03*
X518956D03*
X517105Y1110970D03*
X518956Y1120537D03*
X522657D03*
X517105Y1123726D03*
X524507Y1130103D03*
X518956Y1133293D03*
X522657D03*
Y1126915D03*
X518956D03*
X524507Y1123726D03*
X517105Y1130103D03*
Y1136481D03*
X524507D03*
X518956Y1139670D03*
X522657D03*
X517105Y1142859D03*
X524507Y1149237D03*
X522657Y1146048D03*
X518956D03*
X524507Y1142859D03*
X517105Y1149237D03*
X518956Y1152426D03*
X522657D03*
X524507Y1155615D03*
X518470Y1516970D03*
X523194D03*
X515320Y1519698D03*
X520044D03*
X524769D03*
X580390Y1530608D03*
X585114D03*
X581965Y1533336D03*
X586689D03*
X589839Y1530608D03*
X594563D03*
X599287D03*
X604012D03*
X591413Y1533336D03*
X596138D03*
X600862D03*
X608736Y1530608D03*
X613461D03*
X618185D03*
X605587Y1533336D03*
X610311D03*
X615035D03*
X627634Y1530608D03*
X632358D03*
X622909D03*
X629209Y1533336D03*
X633933D03*
X619760D03*
X624484D03*
X637083Y1530608D03*
X641807D03*
X646532D03*
X638657Y1533336D03*
X643382D03*
X648106D03*
X651256Y1530608D03*
X652831Y1533336D03*
X1196028Y1563608D03*
X1197603Y1566336D03*
X1200752Y1563608D03*
X1205477D03*
X1210201D03*
X1214925D03*
X1202327Y1566336D03*
X1207051D03*
X1211776D03*
X1219650Y1563608D03*
X1224374D03*
X1229099D03*
X1216500Y1566336D03*
X1221225D03*
X1225949D03*
X1243272Y1563608D03*
X1233823D03*
X1238547D03*
X1244847Y1566336D03*
X1230673D03*
X1235398D03*
X1240122D03*
X1247996Y1563608D03*
X1252721D03*
X1257445D03*
X1249571Y1566336D03*
X1254295D03*
X1259020D03*
X1262170Y1563608D03*
X1266894D03*
X1263744Y1566336D03*
X1268469D03*
X1334807Y886001D03*
X1332957Y889190D03*
Y895568D03*
X1334807Y892379D03*
X1332957Y908324D03*
X1334807Y898757D03*
X1332957Y901946D03*
X1334807Y905134D03*
Y911512D03*
Y917890D03*
X1332957Y921079D03*
X1334807Y924268D03*
X1332957Y914701D03*
Y927457D03*
X1334807Y937024D03*
X1332957Y940213D03*
Y933835D03*
X1334807Y930646D03*
Y943402D03*
X1332957Y946591D03*
X1334807Y956158D03*
X1332957Y952969D03*
X1334807Y949780D03*
Y962536D03*
X1332957Y965725D03*
Y959347D03*
X1334807Y968914D03*
Y975292D03*
X1332957Y978481D03*
Y972103D03*
X1334807Y994426D03*
X1332957Y997615D03*
X1334807Y1000804D03*
X1332957Y991237D03*
Y1010371D03*
X1334807Y1007182D03*
X1332957Y1003993D03*
X1334138Y1034433D03*
Y1040811D03*
Y1059945D03*
Y1053567D03*
Y1072701D03*
Y1066323D03*
Y1079079D03*
Y1085457D03*
Y1091835D03*
Y1098213D03*
Y1104591D03*
Y1110969D03*
Y1117347D03*
Y1130102D03*
Y1123725D03*
Y1136480D03*
Y1149236D03*
Y1142858D03*
Y1155614D03*
X1345910Y886001D03*
X1347760Y889190D03*
Y895568D03*
X1345910Y892379D03*
X1340359Y889190D03*
X1338508Y892379D03*
X1340359Y895568D03*
X1347760Y908324D03*
X1345910Y898757D03*
X1347760Y901946D03*
X1345910Y905134D03*
Y911512D03*
X1338508D03*
X1340359Y901946D03*
X1338508Y905134D03*
X1340359Y908324D03*
X1338508Y898757D03*
X1345910Y917890D03*
X1347760Y921079D03*
X1345910Y924268D03*
X1347760Y914701D03*
X1340359Y921079D03*
X1338508Y924268D03*
X1340359Y914701D03*
X1338508Y917890D03*
X1347760Y927457D03*
X1345910Y937024D03*
X1347760Y940213D03*
Y933835D03*
X1345910Y930646D03*
X1340359Y927457D03*
X1338508Y930646D03*
X1340359Y940213D03*
Y933835D03*
X1338508Y937024D03*
X1345910Y943402D03*
X1347760Y946591D03*
X1345910Y956158D03*
X1347760Y952969D03*
X1345910Y949780D03*
X1338508Y943402D03*
X1340359Y946591D03*
X1338508Y949780D03*
X1340359Y952969D03*
X1338508Y956158D03*
X1345910Y962536D03*
X1347760Y965725D03*
Y959347D03*
X1345910Y968914D03*
X1340359Y965725D03*
X1338508Y968914D03*
X1340359Y959347D03*
X1338508Y962536D03*
X1345910Y975292D03*
X1347760Y978481D03*
Y972103D03*
X1340359Y984859D03*
Y978481D03*
X1338508Y981670D03*
X1340359Y972103D03*
X1338508Y975292D03*
X1345910Y994426D03*
X1347760Y997615D03*
X1345910Y1000804D03*
X1347760Y991237D03*
X1338508Y988048D03*
X1340359Y997615D03*
X1338508Y1000804D03*
Y994426D03*
X1347760Y1010371D03*
X1345910Y1007182D03*
X1347760Y1003993D03*
X1340359D03*
X1338508Y1007182D03*
X1348941Y1034433D03*
X1347091Y1037622D03*
X1348941Y1040811D03*
X1347091Y1044000D03*
X1339689Y1031244D03*
X1341540Y1034433D03*
X1335989Y1037622D03*
X1339689D03*
X1341540Y1040811D03*
X1335989Y1044000D03*
X1348941Y1059945D03*
X1347091Y1050378D03*
X1348941Y1053567D03*
X1339689Y1050378D03*
X1341540Y1047189D03*
X1335989Y1050378D03*
X1348941Y1072701D03*
X1347091Y1063134D03*
Y1069512D03*
X1348941Y1066323D03*
X1339689Y1063134D03*
X1335989D03*
X1341540Y1066323D03*
X1339689Y1069512D03*
X1335989D03*
X1341540Y1072701D03*
X1347091Y1075890D03*
X1348941Y1079079D03*
X1347091Y1082268D03*
Y1088646D03*
X1348941Y1085457D03*
X1339689Y1075890D03*
X1335989D03*
X1341540Y1079079D03*
X1339689Y1082268D03*
X1335989D03*
X1341540Y1085457D03*
X1335989Y1088646D03*
X1339689D03*
X1347091Y1101402D03*
X1348941Y1091835D03*
X1347091Y1095024D03*
X1348941Y1098213D03*
Y1104591D03*
X1335989Y1101402D03*
X1341540Y1104591D03*
X1339689Y1095024D03*
X1335989D03*
X1341540Y1098213D03*
X1339689Y1101402D03*
X1341540Y1091835D03*
X1348941Y1110969D03*
X1347091Y1114158D03*
X1348941Y1117347D03*
X1347091Y1107780D03*
X1339689Y1114158D03*
X1335989D03*
X1341540Y1117347D03*
X1335989Y1107780D03*
X1339689D03*
X1341540Y1110969D03*
X1347091Y1120536D03*
X1348941Y1130102D03*
X1347091Y1133292D03*
Y1126914D03*
X1348941Y1123725D03*
X1339689Y1120536D03*
X1335989D03*
X1341540Y1123725D03*
X1339689Y1133292D03*
X1335989D03*
Y1126914D03*
X1339689D03*
X1341540Y1130102D03*
X1348941Y1136480D03*
X1347091Y1139669D03*
X1348941Y1149236D03*
X1347091Y1146047D03*
X1348941Y1142858D03*
X1341540Y1136480D03*
X1339689Y1139669D03*
X1335989D03*
X1341540Y1142858D03*
X1335989Y1146047D03*
X1339689D03*
X1341540Y1149236D03*
X1347091Y1152425D03*
X1339689D03*
X1335989D03*
X1364414Y892379D03*
X1360713D03*
X1351461Y889190D03*
X1353311Y892379D03*
X1351461Y895568D03*
X1364414Y905134D03*
Y898757D03*
Y911512D03*
X1360713Y905134D03*
Y898757D03*
Y911512D03*
X1353311D03*
X1351461Y901946D03*
X1353311Y905134D03*
X1351461Y908324D03*
X1353311Y898757D03*
X1351461Y921079D03*
X1353311Y924268D03*
X1351461Y914701D03*
X1353311Y917890D03*
X1351461Y927457D03*
X1353311Y930646D03*
X1351461Y940213D03*
Y933835D03*
X1353311Y937024D03*
Y943402D03*
X1351461Y946591D03*
X1353311Y949780D03*
X1351461Y952969D03*
X1353311Y956158D03*
X1351461Y965725D03*
X1353311Y968914D03*
X1351461Y959347D03*
X1353311Y962536D03*
X1351461Y984859D03*
Y978481D03*
X1353311Y981670D03*
X1351461Y972103D03*
X1353311Y975292D03*
Y988048D03*
X1351461Y997615D03*
X1353311Y1000804D03*
Y994426D03*
X1351461Y1003993D03*
X1353311Y1007182D03*
X1354493Y1031244D03*
X1352642Y1034433D03*
X1354493Y1037622D03*
X1352642Y1040811D03*
X1354493Y1050378D03*
X1352642Y1047189D03*
X1354493Y1063134D03*
X1352642Y1066323D03*
X1354493Y1069512D03*
X1352642Y1072701D03*
X1354493Y1075890D03*
X1352642Y1079079D03*
X1354493Y1082268D03*
X1352642Y1085457D03*
X1354493Y1088646D03*
X1352642Y1104591D03*
X1354493Y1095024D03*
X1352642Y1098213D03*
X1354493Y1101402D03*
X1352642Y1091835D03*
X1354493Y1114158D03*
X1352642Y1117347D03*
X1354493Y1107780D03*
X1352642Y1110969D03*
X1354493Y1120536D03*
X1352642Y1123725D03*
X1354493Y1133292D03*
Y1126914D03*
X1352642Y1130102D03*
X1361894Y1126914D03*
Y1133292D03*
X1352642Y1136480D03*
X1354493Y1139669D03*
X1352642Y1142858D03*
X1354493Y1146047D03*
X1352642Y1149236D03*
X1361894Y1139669D03*
Y1146047D03*
X1354493Y1152425D03*
X1352642Y1155614D03*
X1361894Y1158803D03*
X1358193D03*
X1361894Y1152425D03*
X1375516Y892379D03*
X1371815D03*
X1375516Y898757D03*
Y905134D03*
X1371815Y898757D03*
Y905134D03*
X1365595Y1126914D03*
Y1133292D03*
X1376697D03*
X1372997D03*
X1365595Y1139669D03*
Y1146047D03*
X1376697Y1139669D03*
Y1146047D03*
X1372997Y1139669D03*
Y1146047D03*
Y1158803D03*
X1369296D03*
X1365595Y1152425D03*
X1376697D03*
X1372997D03*
X1386619Y892379D03*
X1394020D03*
X1382918D03*
X1386619Y905134D03*
Y898757D03*
X1394020Y905134D03*
Y898757D03*
X1382918Y905134D03*
Y898757D03*
X1387800Y1133292D03*
X1384099D03*
X1387800Y1139669D03*
Y1146047D03*
X1384099Y1139669D03*
Y1146047D03*
Y1158803D03*
X1380398D03*
X1391500D03*
X1387800Y1152425D03*
X1384099D03*
X1406973Y895568D03*
X1397721Y892379D03*
X1403272Y895568D03*
X1406973Y908324D03*
Y901946D03*
X1397721Y905134D03*
Y898757D03*
X1403272Y908324D03*
Y901946D03*
X1398902Y1133292D03*
X1408154Y1130102D03*
X1395201Y1133292D03*
X1404453Y1130102D03*
X1398902Y1139669D03*
Y1146047D03*
X1408154Y1142858D03*
Y1136480D03*
X1395201Y1139669D03*
Y1146047D03*
X1404453Y1142858D03*
Y1136480D03*
X1395201Y1158803D03*
X1398902Y1152425D03*
X1395201D03*
X1434704Y892379D03*
X1425452Y895568D03*
X1438405Y892379D03*
X1429153Y895568D03*
X1434704Y898757D03*
Y905134D03*
X1425452Y901946D03*
Y908324D03*
X1438405Y898757D03*
Y905134D03*
X1429153Y901946D03*
Y908324D03*
X1434704Y911512D03*
X1438405D03*
X1434704Y917890D03*
Y924268D03*
X1425452Y914701D03*
Y921079D03*
X1438405Y917890D03*
Y924268D03*
X1429153Y914701D03*
Y921079D03*
X1425452Y927457D03*
X1429153D03*
X1430334Y1130102D03*
X1426633D03*
X1435885Y1133292D03*
Y1146047D03*
Y1139669D03*
X1426633Y1136480D03*
Y1142858D03*
X1430334Y1136480D03*
Y1142858D03*
X1445806Y892379D03*
X1449507D03*
X1445806Y898757D03*
Y905134D03*
X1449507Y898757D03*
Y905134D03*
X1445806Y911512D03*
X1449507D03*
X1445806Y917890D03*
Y924268D03*
X1449507Y917890D03*
Y924268D03*
X1446987Y1133292D03*
X1450688D03*
X1439586D03*
X1446987Y1139669D03*
X1450688D03*
X1446987Y1146047D03*
X1439586D03*
Y1139669D03*
X1450688Y1146047D03*
X1468011Y892379D03*
X1456909D03*
X1460609D03*
X1468011Y911512D03*
Y898757D03*
Y905134D03*
X1456909Y898757D03*
Y905134D03*
X1460609Y898757D03*
Y905134D03*
X1456909Y911512D03*
X1460609D03*
X1468011Y924268D03*
Y917890D03*
X1456909Y924268D03*
Y917890D03*
X1460609Y924268D03*
Y917890D03*
X1468011Y930646D03*
X1456909D03*
X1460609D03*
X1458090Y1133292D03*
X1461791D03*
X1458090Y1146047D03*
Y1139669D03*
X1461791Y1146047D03*
Y1139669D03*
X1461777Y1552698D03*
X1460202Y1549970D03*
X1464926D03*
X1466501Y1552698D03*
X1471712Y892379D03*
X1480964Y889190D03*
X1479113Y892379D03*
X1480964Y895568D03*
X1471712Y911512D03*
Y898757D03*
Y905134D03*
X1479113Y911512D03*
X1480964Y901946D03*
X1479113Y905134D03*
X1480964Y908324D03*
X1479113Y898757D03*
X1480964Y921079D03*
X1479113Y924268D03*
X1480964Y914701D03*
X1479113Y917890D03*
X1471712Y924268D03*
Y917890D03*
X1480964Y927457D03*
X1479113Y930646D03*
X1480964Y940213D03*
Y933835D03*
X1479113Y937024D03*
X1471712Y930646D03*
X1479113Y943402D03*
X1480964Y946591D03*
X1479113Y949780D03*
X1480964Y952969D03*
X1479113Y956158D03*
X1480964Y965725D03*
X1479113Y968914D03*
X1480964Y959347D03*
X1479113Y962536D03*
X1480964Y984859D03*
Y978481D03*
X1479113Y981670D03*
X1480964Y972103D03*
X1479113Y975292D03*
Y988048D03*
X1480964Y997615D03*
X1479113Y1000804D03*
X1480964Y991237D03*
Y1003993D03*
X1479113Y1007182D03*
X1480295Y1031244D03*
X1482145Y1034433D03*
X1480295Y1037622D03*
X1482145Y1040811D03*
X1480295Y1044000D03*
Y1050378D03*
X1482145Y1047189D03*
X1480295Y1063134D03*
X1482145Y1066323D03*
X1480295Y1069512D03*
X1482145Y1072701D03*
X1480295Y1075890D03*
X1482145Y1079079D03*
X1480295Y1082268D03*
X1482145Y1085457D03*
X1480295Y1088646D03*
X1482145Y1104591D03*
X1480295Y1095024D03*
X1482145Y1098213D03*
X1480295Y1101402D03*
X1482145Y1091835D03*
X1480295Y1114158D03*
X1482145Y1117347D03*
X1480295Y1107780D03*
X1482145Y1110969D03*
X1480295Y1120536D03*
X1482145Y1123725D03*
X1480295Y1133292D03*
Y1126914D03*
X1482145Y1130102D03*
X1469192Y1133292D03*
Y1126914D03*
X1472893Y1133292D03*
Y1126914D03*
X1482145Y1136480D03*
X1480295Y1139669D03*
X1482145Y1142858D03*
X1480295Y1146047D03*
X1482145Y1149236D03*
X1469192Y1146047D03*
Y1139669D03*
X1472893Y1146047D03*
Y1139669D03*
X1480295Y1152425D03*
X1482145Y1155614D03*
X1479099Y1549970D03*
X1483824D03*
X1480674Y1552698D03*
X1469651Y1549970D03*
X1474375D03*
X1471225Y1552698D03*
X1475950D03*
X1486515Y886001D03*
X1484665Y889190D03*
Y895568D03*
X1486515Y892379D03*
X1497617Y886001D03*
X1492066Y889190D03*
X1493917Y892379D03*
X1492066Y895568D03*
X1497617Y892379D03*
X1484665Y908324D03*
X1486515Y898757D03*
X1484665Y901946D03*
X1486515Y905134D03*
Y911512D03*
X1493917D03*
X1497617Y898757D03*
X1492066Y901946D03*
X1493917Y905134D03*
X1497617D03*
X1492066Y908324D03*
X1497617Y911512D03*
X1493917Y898757D03*
X1486515Y917890D03*
X1484665Y921079D03*
X1486515Y924268D03*
X1484665Y914701D03*
X1497617Y917890D03*
X1492066Y921079D03*
X1493917Y924268D03*
X1497617D03*
X1492066Y914701D03*
X1493917Y917890D03*
X1484665Y927457D03*
X1486515Y937024D03*
X1484665Y940213D03*
Y933835D03*
X1486515Y930646D03*
X1492066Y927457D03*
X1493917Y930646D03*
X1497617Y937024D03*
X1492066Y940213D03*
Y933835D03*
X1497617Y930646D03*
X1493917Y937024D03*
X1486515Y943402D03*
X1484665Y946591D03*
X1486515Y956158D03*
X1484665Y952969D03*
X1486515Y949780D03*
X1493917Y943402D03*
X1497617D03*
X1492066Y946591D03*
X1493917Y949780D03*
X1497617Y956158D03*
X1492066Y952969D03*
X1497617Y949780D03*
X1493917Y956158D03*
X1486515Y962536D03*
X1484665Y965725D03*
Y959347D03*
X1486515Y968914D03*
X1497617Y962536D03*
X1492066Y965725D03*
X1493917Y968914D03*
X1492066Y959347D03*
X1493917Y962536D03*
X1497617Y968914D03*
X1486515Y975292D03*
X1484665Y978481D03*
Y972103D03*
X1492066Y984859D03*
X1497617Y975292D03*
X1492066Y978481D03*
X1493917Y981670D03*
X1492066Y972103D03*
X1493917Y975292D03*
X1486515Y994426D03*
X1484665Y997615D03*
X1486515Y1000804D03*
Y988048D03*
X1493917D03*
X1497617Y994426D03*
X1492066Y997615D03*
X1493917Y1000804D03*
X1497617D03*
Y988048D03*
X1492066Y991237D03*
X1484665Y1010371D03*
X1486515Y1007182D03*
X1484665Y1003993D03*
X1497617Y1007182D03*
X1492066Y1003993D03*
X1493917Y1007182D03*
X1485846Y1034433D03*
X1487696Y1037622D03*
X1485846Y1040811D03*
X1495098Y1031244D03*
X1493247Y1034433D03*
X1498799Y1037622D03*
X1495098D03*
X1493247Y1040811D03*
X1495098Y1044000D03*
X1485846Y1059945D03*
X1487696Y1050378D03*
X1485846Y1053567D03*
X1495098Y1050378D03*
X1493247Y1047189D03*
X1498799Y1050378D03*
X1485846Y1072701D03*
X1487696Y1063134D03*
Y1069512D03*
X1485846Y1066323D03*
X1495098Y1063134D03*
X1498799D03*
X1493247Y1066323D03*
X1495098Y1069512D03*
X1498799D03*
X1493247Y1072701D03*
X1487696Y1075890D03*
X1485846Y1079079D03*
X1487696Y1082268D03*
Y1088646D03*
X1485846Y1085457D03*
X1495098Y1075890D03*
X1498799D03*
X1493247Y1079079D03*
X1495098Y1082268D03*
X1498799D03*
X1493247Y1085457D03*
X1498799Y1088646D03*
X1495098D03*
X1487696Y1101402D03*
X1485846Y1091835D03*
X1487696Y1095024D03*
X1485846Y1098213D03*
Y1104591D03*
X1498799Y1101402D03*
X1493247Y1104591D03*
X1495098Y1095024D03*
X1498799D03*
X1493247Y1098213D03*
X1495098Y1101402D03*
X1493247Y1091835D03*
X1485846Y1110969D03*
X1487696Y1114158D03*
X1485846Y1117347D03*
X1487696Y1107780D03*
X1495098Y1114158D03*
X1498799D03*
X1493247Y1117347D03*
X1498799Y1107780D03*
X1495098D03*
X1493247Y1110969D03*
X1487696Y1120536D03*
X1485846Y1130102D03*
X1487696Y1133292D03*
Y1126914D03*
X1485846Y1123725D03*
X1495098Y1120536D03*
X1498799D03*
X1493247Y1123725D03*
X1495098Y1133292D03*
X1498799D03*
Y1126914D03*
X1495098D03*
X1493247Y1130102D03*
X1485846Y1136480D03*
X1487696Y1139669D03*
X1485846Y1149236D03*
X1487696Y1146047D03*
X1485846Y1142858D03*
X1493247Y1136480D03*
X1495098Y1139669D03*
X1498799D03*
X1493247Y1142858D03*
X1498799Y1146047D03*
X1495098D03*
X1493247Y1149236D03*
X1487696Y1152425D03*
X1495098D03*
X1498799D03*
X1497997Y1549970D03*
X1488548D03*
X1493273D03*
X1485399Y1552698D03*
X1490123D03*
X1494847D03*
X1499468Y889190D03*
Y895568D03*
Y908324D03*
Y901946D03*
Y921079D03*
Y914701D03*
Y927457D03*
Y940213D03*
Y933835D03*
Y946591D03*
Y952969D03*
Y965725D03*
Y959347D03*
Y978481D03*
Y972103D03*
Y997615D03*
Y1010371D03*
Y1003993D03*
X1500649Y1034433D03*
Y1040811D03*
Y1059945D03*
Y1053567D03*
Y1072701D03*
Y1066323D03*
Y1079079D03*
Y1085457D03*
Y1091835D03*
Y1098213D03*
Y1104591D03*
Y1110969D03*
Y1117347D03*
Y1130102D03*
Y1123725D03*
Y1136480D03*
Y1149236D03*
Y1142858D03*
Y1155614D03*
X1507446Y1549970D03*
X1512170D03*
X1502721D03*
X1509021Y1552698D03*
X1513745D03*
X1499572D03*
X1504296D03*
X1516895Y1549970D03*
X1521619D03*
X1526344D03*
X1518469Y1552698D03*
X1523194D03*
X1527918D03*
X1531068Y1549970D03*
X1532643Y1552698D03*
X1588264Y1563608D03*
X1592988D03*
X1597713D03*
X1602437D03*
X1589839Y1566336D03*
X1594563D03*
X1599287D03*
X1607161Y1563608D03*
X1611886D03*
X1616610D03*
X1604012Y1566336D03*
X1608736D03*
X1613461D03*
X1621335Y1563608D03*
X1626059D03*
X1630783D03*
X1618185Y1566336D03*
X1622909D03*
X1627634D03*
X1632358D03*
X1635508Y1563608D03*
X1640232D03*
X1644957D03*
X1637083Y1566336D03*
X1641807D03*
X1646531D03*
X1649681Y1563608D03*
X1654406D03*
X1659130D03*
X1651256Y1566336D03*
X1655980D03*
X1660705D03*
G54D49*
X676509Y145866D03*
G54D33*
X230905Y1649173D03*
Y1653897D03*
Y1663346D03*
Y1668070D03*
Y1677519D03*
Y1682244D03*
Y1691692D03*
Y1696417D03*
Y1705866D03*
Y1710590D03*
Y1720039D03*
Y1724763D03*
Y1734212D03*
X238779Y1643661D03*
X246653Y1649173D03*
Y1653897D03*
X238779Y1653110D03*
Y1657834D03*
X246653Y1663346D03*
Y1668070D03*
X238779Y1667283D03*
Y1672007D03*
X246653Y1677519D03*
Y1682244D03*
X238779Y1681456D03*
Y1686180D03*
X246653Y1691692D03*
Y1696417D03*
X238779Y1695629D03*
Y1700354D03*
X246653Y1705866D03*
Y1710590D03*
X238779Y1709803D03*
Y1714527D03*
X246653Y1720039D03*
Y1724763D03*
X238779Y1723976D03*
Y1728700D03*
X246653Y1734212D03*
X254527Y1643661D03*
Y1653110D03*
Y1657834D03*
Y1667283D03*
Y1672007D03*
Y1681456D03*
Y1686180D03*
Y1695629D03*
Y1700354D03*
Y1709803D03*
Y1714527D03*
Y1723976D03*
Y1728700D03*
X270275Y1643661D03*
X262401Y1649173D03*
X270275Y1653110D03*
X262401Y1653897D03*
X270275Y1657834D03*
X262401Y1663346D03*
X270275Y1667283D03*
X262401Y1668070D03*
X270275Y1672007D03*
X262401Y1677519D03*
X270275Y1681456D03*
X262401Y1682244D03*
X270275Y1686180D03*
X262401Y1691692D03*
X270275Y1695629D03*
X262401Y1696417D03*
X270275Y1700354D03*
X262401Y1705866D03*
X270275Y1709803D03*
X262401Y1710590D03*
X270275Y1714527D03*
X262401Y1720039D03*
X270275Y1723976D03*
X262401Y1724763D03*
X270275Y1728700D03*
X262401Y1734212D03*
X286023Y1643661D03*
X278149Y1649173D03*
X286023Y1653110D03*
X278149Y1653897D03*
X286023Y1657834D03*
X278149Y1663346D03*
X286023Y1667283D03*
X278149Y1668070D03*
X286023Y1672007D03*
X278149Y1677519D03*
X286023Y1681456D03*
X278149Y1682244D03*
X286023Y1686180D03*
X278149Y1691692D03*
X286023Y1695629D03*
X278149Y1696417D03*
X286023Y1700354D03*
X278149Y1705866D03*
X286023Y1709803D03*
X278149Y1710590D03*
X286023Y1714527D03*
X278149Y1720039D03*
X286023Y1723976D03*
X278149Y1724763D03*
X286023Y1728700D03*
X278149Y1734212D03*
X305709Y1672007D03*
X297835Y1677519D03*
X305709Y1681456D03*
X297835Y1682244D03*
X305709Y1686180D03*
X297835Y1691692D03*
X305709Y1695629D03*
X297835Y1696417D03*
X305709Y1700354D03*
X297835Y1705866D03*
X305709Y1709803D03*
X297835Y1710590D03*
X305709Y1714527D03*
X297835Y1720039D03*
X305709Y1723976D03*
X297835Y1724763D03*
X305709Y1728700D03*
X297835Y1734212D03*
X321457Y1672007D03*
X313583Y1677519D03*
X321457Y1681456D03*
X313583Y1682244D03*
X321457Y1686180D03*
X313583Y1691692D03*
X321457Y1695629D03*
X313583Y1696417D03*
X321457Y1700354D03*
X313583Y1705866D03*
X321457Y1709803D03*
X313583Y1710590D03*
X321457Y1714527D03*
X313583Y1720039D03*
X321457Y1723976D03*
X313583Y1724763D03*
X321457Y1728700D03*
X313583Y1734212D03*
X329331Y1677519D03*
Y1682244D03*
Y1691692D03*
Y1696417D03*
Y1705866D03*
Y1710590D03*
Y1720039D03*
Y1724763D03*
Y1734212D03*
X337205Y1672007D03*
X345079Y1677519D03*
Y1682244D03*
X337205Y1681456D03*
Y1686180D03*
X345079Y1691692D03*
Y1696417D03*
X337205Y1695629D03*
Y1700354D03*
X345079Y1705866D03*
Y1710590D03*
X337205Y1709803D03*
Y1714527D03*
X345079Y1720039D03*
Y1724763D03*
X337205Y1723976D03*
Y1728700D03*
X345079Y1734212D03*
X352953Y1672007D03*
Y1681456D03*
Y1686180D03*
Y1695629D03*
Y1700354D03*
Y1709803D03*
Y1714527D03*
Y1723976D03*
Y1728700D03*
X495078Y1677519D03*
Y1682244D03*
Y1691692D03*
Y1696417D03*
Y1705866D03*
Y1710590D03*
Y1720039D03*
Y1724763D03*
Y1734212D03*
X502952Y1672007D03*
X510826Y1677519D03*
Y1682244D03*
X502952Y1681456D03*
Y1686180D03*
X510826Y1691692D03*
Y1696417D03*
X502952Y1695629D03*
Y1700354D03*
X510826Y1705866D03*
Y1710590D03*
X502952Y1709803D03*
Y1714527D03*
X510826Y1720039D03*
Y1724763D03*
X502952Y1723976D03*
Y1728700D03*
X510826Y1734212D03*
X518700Y1672007D03*
Y1681456D03*
Y1686180D03*
X526574Y1677519D03*
Y1682244D03*
X518700Y1695629D03*
Y1700354D03*
X526574Y1691692D03*
Y1696417D03*
X518700Y1709803D03*
Y1714527D03*
X526574Y1705866D03*
Y1710590D03*
X518700Y1723976D03*
Y1728700D03*
X526574Y1720039D03*
Y1724763D03*
Y1734212D03*
X534448Y1672007D03*
X542322Y1677519D03*
Y1682244D03*
X534448Y1681456D03*
Y1686180D03*
X542322Y1691692D03*
Y1696417D03*
X534448Y1695629D03*
Y1700354D03*
X542322Y1705866D03*
Y1710590D03*
X534448Y1709803D03*
Y1714527D03*
X542322Y1720039D03*
Y1724763D03*
X534448Y1723976D03*
Y1728700D03*
X542322Y1734212D03*
X550196Y1672007D03*
Y1681456D03*
Y1686180D03*
Y1695629D03*
Y1700354D03*
Y1709803D03*
Y1714527D03*
Y1723976D03*
Y1728700D03*
X569882Y1672007D03*
X562008Y1677519D03*
X569882Y1681456D03*
X562008Y1682244D03*
X569882Y1686180D03*
X562008Y1691692D03*
X569882Y1695629D03*
X562008Y1696417D03*
X569882Y1700354D03*
X562008Y1705866D03*
X569882Y1709803D03*
X562008Y1710590D03*
X569882Y1714527D03*
X562008Y1720039D03*
X569882Y1723976D03*
X562008Y1724763D03*
X569882Y1728700D03*
X562008Y1734212D03*
X585630Y1672007D03*
X577756Y1677519D03*
X585630Y1681456D03*
X577756Y1682244D03*
X585630Y1686180D03*
X577756Y1691692D03*
X585630Y1695629D03*
X577756Y1696417D03*
X585630Y1700354D03*
X577756Y1705866D03*
X585630Y1709803D03*
X577756Y1710590D03*
X585630Y1714527D03*
X577756Y1720039D03*
X585630Y1723976D03*
X577756Y1724763D03*
X585630Y1728700D03*
X577756Y1734212D03*
X601378Y1672007D03*
X593504Y1677519D03*
X601378Y1681456D03*
X593504Y1682244D03*
X601378Y1686180D03*
X593504Y1691692D03*
X601378Y1695629D03*
X593504Y1696417D03*
X601378Y1700354D03*
X593504Y1705866D03*
X601378Y1709803D03*
X593504Y1710590D03*
X601378Y1714527D03*
X593504Y1720039D03*
X601378Y1723976D03*
X593504Y1724763D03*
X601378Y1728700D03*
X593504Y1734212D03*
X617126Y1672007D03*
X609252Y1677519D03*
X617126Y1681456D03*
X609252Y1682244D03*
X617126Y1686180D03*
X609252Y1691692D03*
X617126Y1695629D03*
X609252Y1696417D03*
X617126Y1700354D03*
X609252Y1705866D03*
X617126Y1709803D03*
X609252Y1710590D03*
X617126Y1714527D03*
X609252Y1720039D03*
X617126Y1723976D03*
X609252Y1724763D03*
X617126Y1728700D03*
X609252Y1734212D03*
X1238778Y1677519D03*
Y1682244D03*
Y1691692D03*
Y1696417D03*
Y1705866D03*
Y1710590D03*
Y1720039D03*
Y1724763D03*
Y1734212D03*
X1246652Y1672007D03*
X1254526Y1677519D03*
Y1682244D03*
X1246652Y1681456D03*
Y1686180D03*
X1254526Y1691692D03*
Y1696417D03*
X1246652Y1695629D03*
Y1700354D03*
X1254526Y1705866D03*
Y1710590D03*
X1246652Y1709803D03*
Y1714527D03*
X1254526Y1720039D03*
Y1724763D03*
X1246652Y1723976D03*
Y1728700D03*
X1254526Y1734212D03*
X1262400Y1672007D03*
Y1681456D03*
Y1686180D03*
X1270274Y1677519D03*
Y1682244D03*
X1262400Y1695629D03*
Y1700354D03*
X1270274Y1691692D03*
Y1696417D03*
X1262400Y1709803D03*
Y1714527D03*
X1270274Y1705866D03*
Y1710590D03*
X1262400Y1723976D03*
Y1728700D03*
X1270274Y1720039D03*
Y1724763D03*
Y1734212D03*
X1278148Y1672007D03*
X1286022Y1677519D03*
Y1682244D03*
X1278148Y1681456D03*
Y1686180D03*
X1286022Y1691692D03*
Y1696417D03*
X1278148Y1695629D03*
Y1700354D03*
X1286022Y1705866D03*
Y1710590D03*
X1278148Y1709803D03*
Y1714527D03*
X1286022Y1720039D03*
Y1724763D03*
X1278148Y1723976D03*
Y1728700D03*
X1286022Y1734212D03*
X1293896Y1672007D03*
Y1681456D03*
Y1686180D03*
Y1695629D03*
Y1700354D03*
Y1709803D03*
Y1714527D03*
Y1723976D03*
Y1728700D03*
X1313582Y1672007D03*
X1305708Y1677519D03*
X1313582Y1681456D03*
X1305708Y1682244D03*
X1313582Y1686180D03*
X1305708Y1691692D03*
X1313582Y1695629D03*
X1305708Y1696417D03*
X1313582Y1700354D03*
X1305708Y1705866D03*
X1313582Y1709803D03*
X1305708Y1710590D03*
X1313582Y1714527D03*
X1305708Y1720039D03*
X1313582Y1723976D03*
X1305708Y1724763D03*
X1313582Y1728700D03*
X1305708Y1734212D03*
X1329330Y1672007D03*
X1321456Y1677519D03*
X1329330Y1681456D03*
X1321456Y1682244D03*
X1329330Y1686180D03*
X1321456Y1691692D03*
X1329330Y1695629D03*
X1321456Y1696417D03*
X1329330Y1700354D03*
X1321456Y1705866D03*
X1329330Y1709803D03*
X1321456Y1710590D03*
X1329330Y1714527D03*
X1321456Y1720039D03*
X1329330Y1723976D03*
X1321456Y1724763D03*
X1329330Y1728700D03*
X1321456Y1734212D03*
X1345078Y1672007D03*
X1337204Y1677519D03*
X1345078Y1681456D03*
X1337204Y1682244D03*
X1345078Y1686180D03*
X1337204Y1691692D03*
X1345078Y1695629D03*
X1337204Y1696417D03*
X1345078Y1700354D03*
X1337204Y1705866D03*
X1345078Y1709803D03*
X1337204Y1710590D03*
X1345078Y1714527D03*
X1337204Y1720039D03*
X1345078Y1723976D03*
X1337204Y1724763D03*
X1345078Y1728700D03*
X1337204Y1734212D03*
X1360826Y1672007D03*
X1352952Y1677519D03*
X1360826Y1681456D03*
X1352952Y1682244D03*
X1360826Y1686180D03*
X1352952Y1691692D03*
X1360826Y1695629D03*
X1352952Y1696417D03*
X1360826Y1700354D03*
X1352952Y1705866D03*
X1360826Y1709803D03*
X1352952Y1710590D03*
X1360826Y1714527D03*
X1352952Y1720039D03*
X1360826Y1723976D03*
X1352952Y1724763D03*
X1360826Y1728700D03*
X1352952Y1734212D03*
X1510826Y1672007D03*
X1502952Y1677519D03*
X1510826Y1681456D03*
X1502952Y1682244D03*
X1510826Y1686180D03*
X1502952Y1691692D03*
X1510826Y1695629D03*
X1502952Y1696417D03*
X1510826Y1700354D03*
X1502952Y1705866D03*
X1510826Y1709803D03*
X1502952Y1710590D03*
X1510826Y1714527D03*
X1502952Y1720039D03*
X1510826Y1723976D03*
X1502952Y1724763D03*
X1510826Y1728700D03*
X1502952Y1734212D03*
X1526574Y1672007D03*
X1518700Y1677519D03*
X1526574Y1681456D03*
X1518700Y1682244D03*
X1526574Y1686180D03*
X1518700Y1691692D03*
X1526574Y1695629D03*
X1518700Y1696417D03*
X1526574Y1700354D03*
X1518700Y1705866D03*
X1526574Y1709803D03*
X1518700Y1710590D03*
X1526574Y1714527D03*
X1518700Y1720039D03*
X1526574Y1723976D03*
X1518700Y1724763D03*
X1526574Y1728700D03*
X1518700Y1734212D03*
X1542322Y1672007D03*
X1534448Y1677519D03*
X1542322Y1681456D03*
X1534448Y1682244D03*
X1542322Y1686180D03*
X1534448Y1691692D03*
X1542322Y1695629D03*
X1534448Y1696417D03*
X1542322Y1700354D03*
X1534448Y1705866D03*
X1542322Y1709803D03*
X1534448Y1710590D03*
X1542322Y1714527D03*
X1534448Y1720039D03*
X1542322Y1723976D03*
X1534448Y1724763D03*
X1542322Y1728700D03*
X1534448Y1734212D03*
X1558070Y1672007D03*
X1550196Y1677519D03*
X1558070Y1681456D03*
X1550196Y1682244D03*
X1558070Y1686180D03*
X1550196Y1691692D03*
X1558070Y1695629D03*
X1550196Y1696417D03*
X1558070Y1700354D03*
X1550196Y1705866D03*
X1558070Y1709803D03*
X1550196Y1710590D03*
X1558070Y1714527D03*
X1550196Y1720039D03*
X1558070Y1723976D03*
X1550196Y1724763D03*
X1558070Y1728700D03*
X1550196Y1734212D03*
X1569882Y1677519D03*
Y1682244D03*
Y1691692D03*
Y1696417D03*
Y1705866D03*
Y1710590D03*
Y1720039D03*
Y1724763D03*
Y1734212D03*
X1577756Y1672007D03*
X1585630Y1677519D03*
Y1682244D03*
X1577756Y1681456D03*
Y1686180D03*
X1585630Y1691692D03*
Y1696417D03*
X1577756Y1695629D03*
Y1700354D03*
X1585630Y1705866D03*
Y1710590D03*
X1577756Y1709803D03*
Y1714527D03*
X1585630Y1720039D03*
Y1724763D03*
X1577756Y1723976D03*
Y1728700D03*
X1585630Y1734212D03*
X1593504Y1672007D03*
Y1681456D03*
Y1686180D03*
X1601378Y1677519D03*
Y1682244D03*
X1593504Y1695629D03*
Y1700354D03*
X1601378Y1691692D03*
Y1696417D03*
X1593504Y1709803D03*
Y1714527D03*
X1601378Y1705866D03*
Y1710590D03*
X1593504Y1723976D03*
Y1728700D03*
X1601378Y1720039D03*
Y1724763D03*
Y1734212D03*
X1609252Y1672007D03*
X1617126Y1677519D03*
Y1682244D03*
X1609252Y1681456D03*
Y1686180D03*
X1617126Y1691692D03*
Y1696417D03*
X1609252Y1695629D03*
Y1700354D03*
X1617126Y1705866D03*
Y1710590D03*
X1609252Y1709803D03*
Y1714527D03*
X1617126Y1720039D03*
Y1724763D03*
X1609252Y1723976D03*
Y1728700D03*
X1617126Y1734212D03*
X1625000Y1672007D03*
Y1681456D03*
Y1686180D03*
Y1695629D03*
Y1700354D03*
Y1709803D03*
Y1714527D03*
Y1723976D03*
Y1728700D03*
G54D73*
X1859986Y1403418D03*
X1859706Y1709011D03*
X1871790Y476573D03*
X1861790D03*
X1870648Y783729D03*
X1860648D03*
X1862295Y850767D03*
X1872295D03*
X1871790Y1158071D03*
X1861790D03*
X1869986Y1403418D03*
X1869706Y1709011D03*
X1881862Y107291D03*
X1882340Y410829D03*
X1882711Y476864D03*
X1882240Y783474D03*
X1883273Y850816D03*
X1882579Y1158348D03*
X1881223Y1404467D03*
X1881177Y1709323D03*
X1891862Y107291D03*
X1892340Y410829D03*
X1892711Y476864D03*
X1892240Y783474D03*
X1893273Y850816D03*
X1892579Y1158348D03*
X1891223Y1404467D03*
X1891177Y1709323D03*
X2082012Y108312D03*
X2072012D03*
X2071128Y410829D03*
X2081128D03*
G54D13*
X27559Y87795D03*
X40708Y631889D03*
Y1368908D03*
X51180Y1714961D03*
X373622Y87795D03*
X395671Y1714960D03*
X661024Y631890D03*
X707677Y1714960D03*
X800787Y87795D03*
X931693Y757874D03*
X931692Y1072835D03*
X931693Y1387795D03*
X1045866Y87795D03*
X1155709Y1714961D03*
X1271260Y631890D03*
X1461806Y1714961D03*
X1499606Y87795D03*
X1806298Y1714961D03*
X1829921Y87795D03*
X1816772Y631889D03*
Y1368897D03*
G54D35*
X277098Y185236D03*
X395208D03*
G54D64*
X1183858Y217205D03*
X1173858D03*
X1193858D03*
G54D46*
X443467Y594259D03*
X1425533Y601230D03*
G54D16*
X27048Y1533228D03*
X79590Y1369350D03*
X137284Y1533228D03*
X215418Y658055D03*
X276440Y1357539D03*
X420125Y656008D03*
X443764Y1339823D03*
X523173Y578174D03*
X681440Y1385138D03*
X791678D03*
X873622Y1145275D03*
X983858D03*
X1052960Y1369350D03*
X1249812Y1357539D03*
X1370284Y582303D03*
X1417134Y1339823D03*
X1533552Y682342D03*
X1629732Y1383523D03*
X1664890Y642972D03*
X1714330Y1570984D03*
X1739968Y1383527D03*
X1761575Y159134D03*
X1824566Y1570988D03*
X1838150Y201929D03*
G54D51*
X757184Y1702772D03*
X1072863Y1409176D03*
X1080970Y1640958D03*
G54D65*
X1225530Y60384D03*
G54D72*
X1835198Y1601502D03*
G54D76*
X1864986Y1390234D03*
X1886862Y94107D03*
X1887711Y463680D03*
X1888273Y837632D03*
G54D74*
X1866790Y463389D03*
X1867295Y837583D03*
X1886223Y1391283D03*
X2077012Y95128D03*
G54D37*
X303154Y879624D03*
Y886002D03*
X305004Y882813D03*
X303154Y892380D03*
Y898758D03*
X310555Y873246D03*
X317957Y879624D03*
X310555D03*
X319807Y876435D03*
X314256Y873246D03*
X310555Y886002D03*
X314256D03*
X316107Y882813D03*
Y889191D03*
X308705D03*
X319807Y882813D03*
X314256Y892380D03*
X308705Y895569D03*
Y882813D03*
X314256Y898758D03*
X316107Y901947D03*
X308705D03*
Y908325D03*
X314256Y911513D03*
X316107Y908325D03*
X314256Y917891D03*
X308705Y914702D03*
Y921080D03*
X316107D03*
Y940214D03*
X308705Y927458D03*
X316107D03*
X308705Y933836D03*
X314256Y930647D03*
Y937025D03*
X308705Y940214D03*
X314256Y949781D03*
X316107Y946592D03*
X308705D03*
Y952970D03*
X314256Y956159D03*
X316107Y959348D03*
X308705D03*
Y965726D03*
X316107D03*
X314256Y968915D03*
X317957Y981671D03*
X308705Y978482D03*
X316107D03*
X314256Y975293D03*
X308705Y972104D03*
X316107Y984860D03*
X308705D03*
X312406D03*
X319807D03*
X308705Y991238D03*
X310555Y988049D03*
X314256D03*
X316107Y997616D03*
X308705D03*
X314256Y994427D03*
X316107Y1003994D03*
X314256Y1007183D03*
X316107Y1010372D03*
X308705D03*
Y1003994D03*
X327209Y876435D03*
X332760Y879624D03*
X325358D03*
X334598Y872066D03*
X334610Y882813D03*
X321658Y886002D03*
X325358D03*
X330910Y882813D03*
X329059Y886002D03*
X334610Y889191D03*
X327209D03*
X334610Y895569D03*
X321658Y892380D03*
X327209Y895569D03*
X329059Y892380D03*
X334610Y901947D03*
X321658Y898758D03*
X327209Y901947D03*
X329059Y898758D03*
X321658Y905135D03*
Y911513D03*
X329059Y905135D03*
Y911513D03*
X327209Y908325D03*
X334610Y908324D03*
Y914702D03*
X321658Y917891D03*
X327209Y914702D03*
X329059Y917891D03*
X334610Y921080D03*
X321658Y924269D03*
X329059D03*
X327209Y921080D03*
X334610Y927458D03*
Y933836D03*
X321658Y930647D03*
X327209Y927458D03*
Y933836D03*
X329059Y930647D03*
X334610Y940214D03*
X321658Y937025D03*
X327209Y940214D03*
X329059Y937025D03*
Y956159D03*
X334610Y946592D03*
X321658Y943403D03*
Y949781D03*
X329059Y943403D03*
Y949781D03*
X327209Y946592D03*
X334610Y952970D03*
X321658Y956159D03*
X327209Y952970D03*
X334610Y959348D03*
Y965726D03*
X329059Y962537D03*
X327209Y965726D03*
X321658Y962537D03*
X327209Y959348D03*
X321658Y968915D03*
X329059D03*
X334610Y972104D03*
Y978482D03*
X321658Y975293D03*
Y981671D03*
X329059Y975293D03*
X327209Y972104D03*
X332760Y981671D03*
X329059D03*
X327209Y978482D03*
X334610Y984860D03*
X327209D03*
X330910D03*
X334610Y991238D03*
Y997616D03*
X321658Y988049D03*
Y994427D03*
X327209Y991238D03*
X329059Y988049D03*
Y994427D03*
X327209Y997616D03*
X321658Y1000805D03*
X329059D03*
X334610Y1003994D03*
Y1010372D03*
X321658Y1007183D03*
X327209Y1010372D03*
X329059Y1007183D03*
X327209Y1003994D03*
X343862Y879624D03*
X340162Y879568D03*
X345713Y882813D03*
X336461Y886002D03*
X340162D03*
X347563D03*
X342012Y882813D03*
X347563Y892380D03*
X342012Y889191D03*
X340162Y892380D03*
X347563Y898758D03*
Y905135D03*
Y911513D03*
X342012Y901947D03*
X340162Y898758D03*
Y911513D03*
X342012Y908325D03*
X347563Y917891D03*
Y924269D03*
X340162Y917891D03*
X342012Y921080D03*
X347563Y930647D03*
Y937025D03*
X342012Y927458D03*
X340162Y930647D03*
X342012Y940214D03*
X340162Y937025D03*
X347563Y943403D03*
Y949781D03*
Y956159D03*
X340162Y949781D03*
X342012Y946592D03*
X340162Y956159D03*
X347563Y962537D03*
Y968915D03*
X342012Y959348D03*
Y965726D03*
X340162Y968915D03*
X347563Y975293D03*
Y981671D03*
X345713Y984860D03*
X340162Y975293D03*
X343862Y981671D03*
X342012Y978482D03*
Y984860D03*
X347563Y988049D03*
Y994427D03*
Y1000805D03*
X340162Y988049D03*
X342012Y997616D03*
X340162Y994427D03*
X347563Y1007183D03*
X342012Y1010372D03*
X340162Y1007183D03*
X342012Y1003994D03*
X351265Y879568D03*
X360516Y876435D03*
X354965Y879624D03*
X356803Y872066D03*
X351264Y886002D03*
X362366D03*
X356815Y882813D03*
X360516D03*
X353114D03*
X354965Y886002D03*
Y892380D03*
X360516Y889191D03*
Y895569D03*
X353114Y889191D03*
Y895569D03*
X354965Y898758D03*
X360516Y901947D03*
X353114D03*
X354965Y911513D03*
Y905135D03*
X360516Y908325D03*
X353114Y908324D03*
X354965Y917891D03*
X360516Y914702D03*
X353114D03*
X354965Y924269D03*
X360516Y921080D03*
X353114D03*
X354965Y930647D03*
X360516Y927458D03*
Y933836D03*
X353114D03*
Y927458D03*
X354965Y937025D03*
X360516Y940214D03*
X353114D03*
X360516Y946592D03*
X353114D03*
X360516Y952970D03*
X353114D03*
X354965Y956159D03*
Y943403D03*
Y949781D03*
X360516Y959348D03*
Y965726D03*
X353114Y959348D03*
Y965726D03*
X354965Y962537D03*
Y968915D03*
Y975293D03*
Y981671D03*
X360516Y972104D03*
Y978482D03*
X358665Y981671D03*
X353114Y972104D03*
Y978482D03*
X360516Y984860D03*
X356815D03*
X353114D03*
X360516Y997616D03*
Y991238D03*
X353114D03*
Y997616D03*
X354965Y988049D03*
Y994427D03*
Y1000805D03*
Y1007183D03*
X360516Y1003994D03*
X353114D03*
X360516Y1010372D03*
X353114D03*
X369768Y879624D03*
X373469D03*
X375319Y876435D03*
X377169Y879624D03*
X366067Y886002D03*
Y892380D03*
X367917Y889191D03*
X373469Y892380D03*
X367917Y882813D03*
X373469Y886002D03*
X379020Y882813D03*
X377169Y886002D03*
X379020Y895569D03*
X366067Y898758D03*
Y911513D03*
X367917Y901947D03*
X373469Y898758D03*
X379020Y908325D03*
X373469Y911513D03*
Y905135D03*
X367917Y908324D03*
X366067Y917891D03*
X373469D03*
X367917Y921080D03*
X373469Y924269D03*
X379020Y921080D03*
X366067Y930647D03*
Y937025D03*
X367917Y927458D03*
X379020Y933836D03*
X373469Y930647D03*
X367917Y940214D03*
X373469Y937025D03*
X379020Y940214D03*
X366067Y949781D03*
Y956159D03*
X367917Y946592D03*
X373469Y943403D03*
Y949781D03*
Y956159D03*
X379020Y952970D03*
X366067Y968915D03*
X367917Y959348D03*
Y965726D03*
X373469Y962537D03*
Y968915D03*
X379020Y965726D03*
X366067Y975293D03*
X369768Y981671D03*
X367917Y978482D03*
X373469Y975293D03*
Y981671D03*
X367917Y984860D03*
X379020D03*
X371618D03*
X379020Y978482D03*
X366067Y994427D03*
Y988049D03*
X367917Y997616D03*
X379020Y991238D03*
X373469Y988049D03*
X379020Y997616D03*
X373469Y994427D03*
Y1000805D03*
X366067Y1007183D03*
X373469D03*
X367917Y1003994D03*
X379020D03*
X367917Y1010372D03*
X386421Y876435D03*
X388272Y879624D03*
X384571Y873246D03*
X382721Y882813D03*
Y889191D03*
X380870Y892380D03*
X384571Y886002D03*
X386421Y882813D03*
X393823D03*
X388272Y886002D03*
X390122Y882813D03*
X391973Y892380D03*
X390122Y895569D03*
X386421Y889191D03*
X393823D03*
X382721Y901947D03*
X380870Y898758D03*
Y911513D03*
Y905135D03*
X393823Y901947D03*
X391973Y898758D03*
X390122Y901947D03*
X386421D03*
X391973Y905135D03*
Y911513D03*
X390122Y908325D03*
X382721Y914702D03*
X380870Y917891D03*
Y924269D03*
X386421Y914702D03*
X391973Y917891D03*
X393823Y914702D03*
X390122D03*
Y921080D03*
X391973Y924269D03*
X382721Y927458D03*
Y933836D03*
X380870Y930647D03*
X386421Y927458D03*
Y933836D03*
X393823Y927458D03*
X390122D03*
X393823Y933836D03*
X391973Y930647D03*
X390122Y933836D03*
Y940214D03*
X382721Y946592D03*
X380870Y943403D03*
Y949781D03*
Y956159D03*
X386421Y946592D03*
X391973Y943403D03*
Y949781D03*
X393823Y946592D03*
X390122D03*
X391973Y956159D03*
X390122Y952970D03*
X382721Y959348D03*
X380870Y962537D03*
Y968915D03*
X393823Y959348D03*
X390122D03*
Y965726D03*
X386421Y959348D03*
X391973Y962537D03*
Y968915D03*
X386421Y984860D03*
X382721Y972104D03*
X380870Y975293D03*
X393823Y972104D03*
X390122D03*
Y978482D03*
X384571Y981671D03*
X391973D03*
Y975293D03*
X386421Y972104D03*
X393823Y984860D03*
X391973Y988049D03*
X384571Y994427D03*
Y988049D03*
X391973Y994427D03*
X393823Y991238D03*
X386421D03*
Y997616D03*
X391973Y1000805D03*
X384571D03*
X393823Y997616D03*
X386421Y1003994D03*
X382721Y1010372D03*
X390122D03*
X391973Y1007183D03*
X393823Y1003994D03*
X395673Y1007183D03*
X384571D03*
X410477Y873246D03*
X397524Y876435D03*
X399374Y873246D03*
Y879624D03*
X397524Y882813D03*
Y889191D03*
X401225Y882813D03*
X408626D03*
X404925D03*
X401225Y895569D03*
X408626Y889191D03*
X404925D03*
X403075Y892380D03*
X397524Y901947D03*
X401225D03*
X408626D03*
X404925D03*
X403075Y898758D03*
Y905135D03*
Y911513D03*
X401225Y908324D03*
X397524Y914702D03*
X401225D03*
X408626D03*
X403075Y917891D03*
X404925Y914702D03*
X401225Y921080D03*
X403075Y924269D03*
X401225Y933836D03*
X408626Y927458D03*
X404925D03*
X403075Y930647D03*
X401225Y940214D03*
X397524Y927458D03*
Y933836D03*
X401225Y927458D03*
X397524Y946592D03*
X401225D03*
X403075Y943403D03*
X408626Y946592D03*
X403075Y949781D03*
X404925Y946592D03*
X401225Y952970D03*
X403075Y956159D03*
X397524Y959348D03*
X401225Y965726D03*
Y959348D03*
X408626D03*
X404925D03*
X403075Y962537D03*
Y968915D03*
X397524Y972104D03*
X401225D03*
X408626D03*
X404925D03*
X399374Y981671D03*
X406776D03*
X401225Y978482D03*
X403075Y975293D03*
X401225Y984860D03*
X408626D03*
Y991238D03*
X399374Y988049D03*
Y994427D03*
X406776Y988049D03*
X401225Y991238D03*
Y997616D03*
X399374Y1000805D03*
X397524Y1010372D03*
X399374Y1007183D03*
X401225Y1003994D03*
X421579Y873246D03*
X412327Y882813D03*
Y895569D03*
X414177Y892380D03*
X419729Y882813D03*
X416028D03*
X423429Y895569D03*
X425280Y892380D03*
X416028Y889191D03*
X419729D03*
X412327Y901947D03*
X414177Y898758D03*
Y905135D03*
Y911513D03*
X412327Y908325D03*
X423429Y901947D03*
X425280Y898758D03*
X419729Y901947D03*
X416028D03*
X425280Y905135D03*
Y911513D03*
X423429Y908324D03*
X414177Y917891D03*
X412327Y914702D03*
X414177Y924269D03*
X412327Y921080D03*
X423429Y914702D03*
X419729D03*
X416028D03*
X425280Y917891D03*
Y924269D03*
X423429Y921080D03*
X412327Y927458D03*
Y933836D03*
X414177Y930647D03*
X412327Y940214D03*
X414177Y937025D03*
X423429Y927458D03*
X419729D03*
X423429Y933836D03*
X425280Y930647D03*
X419729Y933836D03*
X416028Y927458D03*
Y933836D03*
X425280Y937025D03*
X423429Y940214D03*
X414177Y949781D03*
X412327Y946592D03*
X414177Y943403D03*
X412327Y952970D03*
X414177Y956159D03*
X416028Y946592D03*
X425280Y943403D03*
Y949781D03*
X423429Y946592D03*
X419729D03*
X423429Y952970D03*
X425280Y956159D03*
X412327Y965726D03*
Y959348D03*
X414177Y962537D03*
Y968915D03*
X423429Y965726D03*
X416028Y959348D03*
X423429D03*
X419729D03*
X425280Y962537D03*
Y968915D03*
X416028Y972104D03*
X423429D03*
X419729D03*
X416028Y984860D03*
X423429D03*
X412327Y978482D03*
X414177Y981671D03*
Y975293D03*
X412327Y972104D03*
X423429Y978482D03*
X421579Y981671D03*
X425280Y975293D03*
X414177Y988049D03*
X421579D03*
X423429Y991238D03*
X416028D03*
X434532Y876435D03*
X432681Y879624D03*
X430831Y882813D03*
X427130D03*
X430831Y889191D03*
X427130D03*
X434532Y895569D03*
Y889191D03*
X428981Y905135D03*
X434532Y901947D03*
X432681Y905135D03*
X434532Y908325D03*
X428981Y917891D03*
X432681D03*
X434532Y914702D03*
Y921080D03*
X428981Y930647D03*
Y937025D03*
X432681Y930647D03*
X434532Y927458D03*
Y933836D03*
X432681Y937025D03*
X434532Y940214D03*
X428981Y949781D03*
X432681D03*
X434532Y946592D03*
Y952970D03*
X428981Y962537D03*
X432681D03*
X434532Y959348D03*
Y965726D03*
X428981Y981671D03*
Y975293D03*
X430831Y984860D03*
X434532Y972104D03*
X432681Y975293D03*
X434532Y978482D03*
X430831Y991238D03*
X428981Y988049D03*
X445609Y876435D03*
X447460Y879624D03*
X445609Y882813D03*
Y889191D03*
Y895569D03*
X453011Y882813D03*
X449310Y889191D03*
X453011D03*
X454861Y892380D03*
X445609Y901947D03*
Y908325D03*
X454861Y898758D03*
X451160Y905135D03*
X454861D03*
Y911513D03*
X447460Y905135D03*
X445609Y914702D03*
Y921080D03*
X447460Y917891D03*
X451160D03*
X454861D03*
Y924269D03*
Y930647D03*
X447460Y937025D03*
X451160D03*
X454861D03*
X445609Y927458D03*
Y933836D03*
Y940214D03*
X447460Y930647D03*
X451160D03*
X445609Y946592D03*
Y952970D03*
X447460Y949781D03*
X454861Y943403D03*
X451160Y949781D03*
X454861D03*
Y956159D03*
X445609Y959348D03*
Y965726D03*
X454861Y962537D03*
X451160D03*
X447460D03*
X454861Y968915D03*
X445609Y972104D03*
Y978482D03*
Y984860D03*
X447460Y981671D03*
X454861D03*
X451160Y975293D03*
X447460D03*
X454861D03*
X453011Y984860D03*
X445609Y991238D03*
X453011D03*
X454861Y988049D03*
X447460D03*
X460412Y876435D03*
X469664Y879624D03*
X460412Y889191D03*
X456712Y895569D03*
X467814Y882813D03*
X465964Y892380D03*
X467814Y895569D03*
X464113Y889191D03*
X456712Y908324D03*
X465964Y911513D03*
X456712Y901947D03*
X460412D03*
X465964Y898758D03*
X467814Y901947D03*
X464113D03*
X467814Y908325D03*
X465964Y905135D03*
X460412Y914702D03*
X456712D03*
Y921080D03*
X467814Y914702D03*
X464113D03*
X465964Y917891D03*
X467814Y921080D03*
X465964Y924269D03*
X460412Y927458D03*
X456712D03*
Y933836D03*
X460412D03*
X456712Y940214D03*
X467814Y927458D03*
Y933836D03*
X464113Y927458D03*
Y933836D03*
X467814Y940214D03*
X465964Y937025D03*
X460412Y946592D03*
X456712D03*
Y952970D03*
X467814Y946592D03*
X464113D03*
X465964Y943403D03*
Y949781D03*
X467814Y952970D03*
X465964Y956159D03*
X456712Y965726D03*
X460412Y959348D03*
X456712D03*
X467814Y965726D03*
Y959348D03*
X465964Y962537D03*
X464113Y959348D03*
X465964Y968915D03*
X456712Y972104D03*
Y978482D03*
X462263Y981671D03*
X460412Y972104D03*
Y984860D03*
X469664Y981671D03*
X467814Y978482D03*
Y972104D03*
X465964Y975293D03*
X464113Y972104D03*
X467814Y984860D03*
X460412Y991238D03*
X462263Y988049D03*
X469664D03*
X467814Y991238D03*
X471515Y876435D03*
X480767Y873246D03*
Y879624D03*
X482617Y876435D03*
X478916Y882813D03*
X475215D03*
X471515D03*
X478916Y895569D03*
X477066Y892380D03*
X475215Y889191D03*
X471515D03*
X482617Y882813D03*
Y889191D03*
X478916Y901947D03*
X471515D03*
X475215D03*
X477066Y898758D03*
X478916Y908325D03*
X477066Y905135D03*
Y911513D03*
X482617Y901947D03*
X478916Y914702D03*
X477066Y917891D03*
X475215Y914702D03*
X471515D03*
X478916Y921080D03*
X477066Y924269D03*
X482617Y914702D03*
X478916Y927458D03*
Y933836D03*
X475215Y927458D03*
X471515D03*
X477066Y930647D03*
X478916Y940214D03*
X482617Y927458D03*
Y933836D03*
X478916Y946592D03*
X477066Y943403D03*
X475215Y946592D03*
X471515D03*
X477066Y949781D03*
X478916Y952970D03*
X477066Y956159D03*
X482617Y946592D03*
X478916Y965726D03*
Y959348D03*
X475215D03*
X471515D03*
X477066Y962537D03*
Y968915D03*
X482617Y959348D03*
X478916Y978482D03*
Y972104D03*
X477066Y981671D03*
Y975293D03*
X475215Y972104D03*
X471515D03*
X475215Y984860D03*
X484467Y981671D03*
X482617Y972104D03*
Y984860D03*
X477066Y994427D03*
X475215Y991238D03*
X477066Y988049D03*
Y1000805D03*
X484467Y994427D03*
Y988049D03*
X482617Y991238D03*
Y997616D03*
X484467Y1000805D03*
X477066Y1007183D03*
X484467D03*
X482617Y1010372D03*
Y1003994D03*
X493719Y876435D03*
X491869Y879624D03*
X493719Y882813D03*
X490019D03*
X486318D03*
X493719Y889191D03*
X486318D03*
X490019Y895569D03*
X488168Y892380D03*
X497420Y889191D03*
X499271Y892380D03*
X493719Y901947D03*
X486318D03*
X490019D03*
X488168Y898758D03*
Y905135D03*
Y911513D03*
X497420Y901947D03*
X499271Y898758D03*
Y905135D03*
Y911513D03*
X490019Y908324D03*
X493719Y914702D03*
X488168Y917891D03*
X490019Y914702D03*
X486318D03*
X490019Y921080D03*
X488168Y924269D03*
X499271Y917891D03*
X497420Y914702D03*
X499271Y924269D03*
X493719Y927458D03*
X486318D03*
X490019D03*
X493719Y933836D03*
X490019D03*
X486318D03*
X488168Y930647D03*
X490019Y940214D03*
X497420Y927458D03*
Y933836D03*
X499271Y930647D03*
X488168Y943403D03*
X493719Y946592D03*
X490019D03*
X486318D03*
X488168Y949781D03*
X490019Y952970D03*
X488168Y956159D03*
X497420Y946592D03*
X499271Y943403D03*
Y949781D03*
Y956159D03*
X490019Y965726D03*
X493719Y959348D03*
X490019D03*
X486318D03*
X488168Y962537D03*
Y968915D03*
X499271Y962537D03*
X497420Y959348D03*
X499271Y968915D03*
X491869Y981671D03*
X490019Y978482D03*
X493719Y972104D03*
X488168Y975293D03*
X490019Y972104D03*
X486318D03*
X490019Y984860D03*
X497420Y972104D03*
X499271Y975293D03*
Y981671D03*
X497420Y984860D03*
X491869Y994427D03*
Y988049D03*
X490019Y997616D03*
Y991238D03*
X491869Y1000805D03*
X497420Y991238D03*
Y997616D03*
X499271Y988049D03*
Y994427D03*
Y1000805D03*
X491869Y1007183D03*
X490019Y1010372D03*
Y1003994D03*
X497420Y1010372D03*
Y1003994D03*
X499271Y1007183D03*
X502971Y879624D03*
X501133Y872118D03*
X508523Y882813D03*
X506672Y886002D03*
X502971D03*
X504822Y882813D03*
X506672Y892380D03*
X501121Y895569D03*
X512223Y882813D03*
X514074Y886002D03*
X512223Y889191D03*
X514074Y892380D03*
X506672Y898758D03*
Y905135D03*
Y911513D03*
X501121Y908325D03*
X512223Y901947D03*
X514074Y898758D03*
Y911513D03*
X512223Y908325D03*
X506672Y917891D03*
X501121Y921080D03*
X506672Y924269D03*
X514074Y917891D03*
X512223Y921080D03*
X506672Y930647D03*
X501121Y933836D03*
X506672Y937025D03*
X501121Y940214D03*
X512223Y927458D03*
X514074Y930647D03*
X512223Y940214D03*
X514074Y937025D03*
X506672Y943403D03*
Y949781D03*
X501121Y952970D03*
X506672Y956159D03*
X514074Y949781D03*
X512223Y946592D03*
X514074Y956159D03*
X506672Y962537D03*
X501121Y965726D03*
X506672Y968915D03*
X512223Y959348D03*
Y965726D03*
X514074Y968915D03*
X510373Y981671D03*
X506672Y975293D03*
Y981671D03*
X501121Y978482D03*
X508523Y984860D03*
X514074Y975293D03*
X512223Y978482D03*
Y984860D03*
X506672Y988049D03*
Y994427D03*
Y1000805D03*
X514074Y988049D03*
Y994427D03*
X512223Y997616D03*
X506672Y1007183D03*
X514074D03*
X512223Y1003994D03*
X525176Y879624D03*
X515924Y876435D03*
X525176Y873246D03*
Y886002D03*
X523326Y882813D03*
X517775Y886002D03*
X519625Y882813D03*
X527027Y895569D03*
Y889191D03*
X525176Y892380D03*
X519625Y889191D03*
Y895569D03*
X528877Y886002D03*
X527027Y901947D03*
X525176Y898758D03*
X519625Y901947D03*
X525176Y905135D03*
Y911513D03*
X519625Y908325D03*
X527027Y908324D03*
X525176Y917891D03*
X519625Y914702D03*
X527027D03*
Y921080D03*
X525176Y924269D03*
X519625Y921080D03*
X525176Y937025D03*
X527027Y927458D03*
Y933836D03*
X525176Y930647D03*
X519625Y927458D03*
Y933836D03*
X527027Y940214D03*
X519625D03*
X527027Y946592D03*
X519625D03*
X525176Y943403D03*
Y949781D03*
X527027Y952970D03*
X525176Y956159D03*
X519625Y952970D03*
X527027Y959348D03*
Y965726D03*
X525176Y962537D03*
X519625Y959348D03*
Y965726D03*
X525176Y968915D03*
X521475Y981671D03*
X519625Y978482D03*
X527027Y984860D03*
X523326D03*
X519625D03*
X527027Y972104D03*
Y978482D03*
X525176Y975293D03*
Y981671D03*
X519625Y972104D03*
X527027Y991238D03*
Y997616D03*
X525176Y988049D03*
Y994427D03*
X519625Y991238D03*
Y997616D03*
X525176Y1000805D03*
X527027Y1010372D03*
Y1003994D03*
X525176Y1007183D03*
X519625Y1010372D03*
Y1003994D03*
X534428Y876435D03*
X539979Y879624D03*
X532578D03*
X541830Y876435D03*
X543680Y879624D03*
X538129Y889191D03*
X539979Y892380D03*
X532578D03*
X543680Y886002D03*
X538129Y882813D03*
X532578Y886002D03*
X534428Y882813D03*
X538129Y901947D03*
X539979Y898758D03*
X532578D03*
X539979Y911513D03*
X538129Y908325D03*
X532578Y905135D03*
Y911513D03*
X539979Y917891D03*
X532578D03*
X538129Y921080D03*
X532578Y924269D03*
X538129Y927458D03*
X539979Y930647D03*
X532578D03*
X539979Y937025D03*
X538129Y940214D03*
X532578Y937025D03*
X539979Y949781D03*
X538129Y946592D03*
X532578Y943403D03*
Y949781D03*
X539979Y956159D03*
X532578D03*
X538129Y959348D03*
Y965726D03*
X532578Y962537D03*
X539979Y968915D03*
X532578D03*
X539979Y975293D03*
X532578D03*
X538129Y978482D03*
X536279Y981671D03*
X532578D03*
X538129Y984860D03*
X534428D03*
X532578Y994427D03*
X539979Y988049D03*
X532578D03*
X539979Y994427D03*
X538129Y997616D03*
X532578Y1000805D03*
X539978Y1007184D03*
X538129Y1003994D03*
X532578Y1007183D03*
X545531Y876435D03*
X552932D03*
X556633D03*
X551082Y879624D03*
X545543Y872085D03*
X554783Y886002D03*
X549231Y882813D03*
X558483Y892380D03*
X545531Y889191D03*
Y895569D03*
X552932Y889191D03*
X551082Y892380D03*
X552932Y895569D03*
X558483Y886002D03*
X545531Y882813D03*
X551082Y886002D03*
X558483Y898758D03*
X545531Y901947D03*
X552932D03*
X551082Y898758D03*
X558483Y905135D03*
Y911513D03*
X551082Y905135D03*
Y911513D03*
X552932Y908325D03*
X545531Y908324D03*
X558483Y917891D03*
X551082D03*
X552932Y914702D03*
X545531D03*
X558483Y924269D03*
X551082D03*
X552932Y921080D03*
X545531D03*
X558483Y930647D03*
X545531Y927458D03*
Y933836D03*
X552932Y927458D03*
Y933836D03*
X551082Y930647D03*
X558483Y937025D03*
X545531Y940214D03*
X551082Y937025D03*
X552932Y940214D03*
X558483Y943403D03*
Y949781D03*
X545531Y946592D03*
X551082Y943403D03*
Y949781D03*
X552932Y946592D03*
X558483Y956159D03*
X545531Y952970D03*
X552932D03*
X551082Y956159D03*
X558483Y962537D03*
X545531Y959348D03*
Y965726D03*
X552932Y959348D03*
X551082Y962537D03*
X552932Y965726D03*
X558483Y968915D03*
X551082D03*
X558483Y975293D03*
Y981671D03*
X545531Y972104D03*
Y978482D03*
X547381Y981671D03*
X551082Y975293D03*
X552932Y972104D03*
X551082Y981671D03*
X552932Y978482D03*
Y984860D03*
X549231D03*
X545531D03*
X558483Y988049D03*
Y994427D03*
X552932Y991238D03*
X551082Y994427D03*
X552932Y997616D03*
X545531Y991238D03*
Y997616D03*
X551082Y988049D03*
X558483Y1000805D03*
X551082D03*
X558483Y1007183D03*
X545531Y1010372D03*
Y1003994D03*
X552932Y1010372D03*
X551082Y1007183D03*
X552932Y1003994D03*
X562184Y879624D03*
X569586Y873246D03*
X560334Y882813D03*
X564034D03*
X569586Y886002D03*
X571436Y882813D03*
Y889191D03*
X564034D03*
X565885Y892380D03*
X571436Y895569D03*
X564034Y901947D03*
X571436D03*
X565885Y898758D03*
X564034Y908325D03*
X571436D03*
X565885Y911513D03*
Y917891D03*
X571436Y914702D03*
X564034Y921080D03*
X571436D03*
X564034Y927458D03*
X571436D03*
X565885Y930647D03*
X571436Y933836D03*
X565885Y937025D03*
X564034Y940214D03*
X571436D03*
X565885Y949781D03*
X564034Y946592D03*
X571436D03*
Y952970D03*
X565885Y956159D03*
X564034Y959348D03*
X571436D03*
X564034Y965726D03*
X571436D03*
X565885Y968915D03*
X562184Y981671D03*
X565885Y975293D03*
X571436Y972104D03*
X564034Y978482D03*
X571436D03*
X567735Y984860D03*
X560334D03*
X564034D03*
X571436D03*
X569586Y988049D03*
X571436Y991238D03*
X565885Y994427D03*
X564034Y997616D03*
X571436D03*
X565885Y988049D03*
X571436Y1010372D03*
X565885Y1007183D03*
X564034Y1003994D03*
X571436D03*
X576987Y879624D03*
X575137Y882813D03*
X576987Y886002D03*
Y892380D03*
Y898758D03*
X1286697Y873245D03*
Y879623D03*
X1279296D03*
X1284847Y895568D03*
Y882812D03*
X1286697Y886001D03*
X1281146Y882812D03*
X1279296Y886001D03*
X1284847Y889190D03*
X1279296Y892379D03*
X1284847Y901946D03*
X1279296Y898757D03*
X1284847Y908324D03*
Y914701D03*
Y921079D03*
Y927457D03*
Y933835D03*
Y940213D03*
Y946591D03*
Y952969D03*
Y959347D03*
Y965725D03*
Y972103D03*
Y978481D03*
Y984859D03*
X1288548D03*
X1284847Y991237D03*
X1286697Y988048D03*
X1284847Y997615D03*
Y1010371D03*
Y1003993D03*
X1290398Y873245D03*
X1301500Y879623D03*
X1303351Y876434D03*
X1294099Y879623D03*
X1295949Y876434D03*
X1303351Y895568D03*
X1290398Y886001D03*
Y892379D03*
X1292249Y882812D03*
X1297800Y886001D03*
X1301500D03*
X1295949Y882812D03*
X1292249Y889190D03*
X1303351D03*
X1297800Y892379D03*
X1290398Y898757D03*
Y911512D03*
X1292249Y901946D03*
X1297800Y898757D03*
X1303351Y901946D03*
X1292249Y908324D03*
X1297800Y905134D03*
Y911512D03*
X1303351Y908324D03*
X1290398Y917890D03*
X1297800D03*
X1303351Y914701D03*
Y921079D03*
X1297800Y924268D03*
X1292249Y921079D03*
X1297800Y930646D03*
X1303351Y927457D03*
Y933835D03*
X1292249Y927457D03*
X1303351Y940213D03*
X1297800Y937024D03*
X1292249Y940213D03*
X1290398Y930646D03*
Y937024D03*
Y949780D03*
Y956158D03*
X1297800Y949780D03*
X1303351Y946591D03*
X1292249D03*
X1297800Y943402D03*
X1303351Y952969D03*
X1297800Y956158D03*
X1290398Y968914D03*
X1297800Y962536D03*
X1303351Y959347D03*
Y965725D03*
X1292249Y959347D03*
Y965725D03*
X1297800Y968914D03*
X1290398Y975292D03*
X1297800Y981670D03*
Y975292D03*
X1303351Y972103D03*
Y978481D03*
X1294099Y981670D03*
X1292249Y978481D03*
X1303351Y984859D03*
X1295949D03*
X1292249D03*
X1290398Y988048D03*
Y994426D03*
X1297800D03*
Y988048D03*
X1303351Y991237D03*
Y997615D03*
X1292249D03*
X1297800Y1000804D03*
X1290398Y1007182D03*
X1292249Y1010371D03*
X1297800Y1007182D03*
X1303351Y1010371D03*
Y1003993D03*
X1292249D03*
X1314453Y876434D03*
X1308902Y873245D03*
Y879623D03*
X1310752Y895568D03*
X1307052Y882812D03*
X1305201Y886001D03*
Y892379D03*
X1310752Y882812D03*
X1312603Y886001D03*
X1316304D03*
X1318154Y882812D03*
X1310752Y889190D03*
X1318154D03*
X1316304Y892379D03*
X1305201Y898757D03*
Y905134D03*
Y911512D03*
X1310752Y901946D03*
X1318154D03*
X1316304Y898757D03*
Y911512D03*
X1318154Y908324D03*
X1310752Y908323D03*
X1305201Y917890D03*
Y924268D03*
X1310752Y914701D03*
X1316304Y917890D03*
X1318154Y921079D03*
X1310752D03*
X1305201Y930646D03*
Y937024D03*
X1310752Y927457D03*
Y933835D03*
X1318154Y927457D03*
X1316304Y930646D03*
Y937024D03*
X1310752Y940213D03*
X1318154D03*
X1305201Y943402D03*
Y949780D03*
Y956158D03*
X1310752Y946591D03*
X1316304Y949780D03*
X1318154Y946591D03*
X1310752Y952969D03*
X1316304Y956158D03*
X1318154Y959347D03*
Y965725D03*
X1316304Y968914D03*
X1305201Y962536D03*
Y968914D03*
X1310752Y959347D03*
Y965725D03*
X1305201Y975292D03*
Y981670D03*
X1307052Y984859D03*
X1310752Y972103D03*
Y978481D03*
X1316304Y975292D03*
X1318154Y978481D03*
X1308902Y981670D03*
X1310752Y984859D03*
X1318154D03*
X1305201Y988048D03*
Y994426D03*
Y1000804D03*
X1310752Y991237D03*
Y997615D03*
X1316304Y988048D03*
X1318154Y997615D03*
X1316304Y994426D03*
X1305201Y1007182D03*
X1310752Y1003993D03*
Y1010371D03*
X1318154D03*
X1316304Y1007182D03*
X1318154Y1003993D03*
X1320004Y879623D03*
X1331107Y873245D03*
X1325556Y876434D03*
X1331107Y879623D03*
X1321855Y882812D03*
X1323705Y886001D03*
X1329256Y882812D03*
X1332957D03*
X1331107Y886001D03*
X1327406D03*
X1323705Y892379D03*
X1329256Y889190D03*
X1331107Y892379D03*
X1329256Y895568D03*
X1323705Y898757D03*
X1331107D03*
X1329256Y901946D03*
X1331107Y911512D03*
X1323705D03*
Y905134D03*
X1331107D03*
X1329256Y908323D03*
Y914701D03*
X1323705Y917890D03*
X1331107D03*
X1323705Y924268D03*
X1329256Y921079D03*
X1331107Y924268D03*
Y930646D03*
X1329256Y933835D03*
X1323705Y930646D03*
X1329256Y927457D03*
X1331107Y937024D03*
X1329256Y940213D03*
X1323705Y937024D03*
X1331107Y943402D03*
X1329256Y946591D03*
X1331107Y949780D03*
X1323705Y943402D03*
Y949780D03*
X1329256Y952969D03*
X1331107Y956158D03*
X1323705D03*
X1329256Y959347D03*
X1331107Y962536D03*
X1329256Y965725D03*
X1323705Y962536D03*
X1331107Y968914D03*
X1323705D03*
X1320004Y981670D03*
X1321855Y984859D03*
X1323705Y975292D03*
Y981670D03*
X1329256Y972103D03*
X1331107Y975292D03*
X1329256Y978481D03*
X1331107Y981670D03*
X1334807D03*
X1329256Y984859D03*
X1332957D03*
X1323705Y1000804D03*
Y988048D03*
Y994426D03*
X1329256Y997615D03*
X1331107Y988048D03*
X1329256Y991237D03*
X1331107Y994426D03*
Y1000804D03*
X1323705Y1007182D03*
X1329256Y1003993D03*
X1331107Y1007182D03*
X1329256Y1010371D03*
X1336658Y876434D03*
X1345910Y879623D03*
X1349611D03*
X1338508Y886001D03*
X1336658Y882812D03*
Y889190D03*
Y895568D03*
X1342209Y886001D03*
X1349611D03*
X1344059Y882812D03*
Y889190D03*
X1342209Y892379D03*
X1349611D03*
X1336658Y901946D03*
Y908324D03*
X1342209Y898757D03*
X1349611D03*
X1344059Y901946D03*
X1349611Y905134D03*
X1342209Y911512D03*
X1349611D03*
X1344059Y908323D03*
X1336658Y914701D03*
Y921079D03*
X1342209Y917890D03*
X1349611D03*
X1344059Y921079D03*
X1349611Y924268D03*
X1336658Y933835D03*
Y927457D03*
Y940213D03*
X1344059Y927457D03*
X1342209Y930646D03*
X1349611D03*
X1344059Y940213D03*
X1342209Y937024D03*
X1349611D03*
Y943402D03*
X1344059Y946591D03*
X1349611Y949780D03*
X1342209D03*
X1349611Y956158D03*
X1342209D03*
X1336658Y946591D03*
Y952969D03*
Y965725D03*
Y959347D03*
X1344059D03*
X1349611Y962536D03*
X1344059Y965725D03*
X1349611Y968914D03*
X1342209D03*
X1336658Y972103D03*
Y978481D03*
Y984859D03*
X1349611Y975292D03*
X1342209D03*
X1344059Y978481D03*
X1349611Y981670D03*
X1345910D03*
X1344059Y984859D03*
X1347760D03*
X1336658Y997615D03*
Y991237D03*
X1349611Y988048D03*
Y994426D03*
X1342209D03*
X1344059Y997615D03*
X1342209Y988048D03*
X1349611Y1000804D03*
X1336658Y1010371D03*
X1344059D03*
X1336658Y1003993D03*
X1344059D03*
X1342209Y1007182D03*
X1349611D03*
X1351461Y876434D03*
X1353311Y879623D03*
X1364414D03*
X1360713Y873245D03*
X1362563Y876434D03*
X1353311Y886001D03*
X1362563Y882812D03*
X1358863D03*
X1364414Y886001D03*
X1360713D03*
X1355162Y882812D03*
X1357012Y892379D03*
X1355162Y895568D03*
X1362563Y889190D03*
X1358863D03*
X1357012Y898757D03*
X1362563Y901946D03*
X1358863D03*
X1357012Y905134D03*
Y911512D03*
X1355162Y908324D03*
X1358863Y914701D03*
X1362563D03*
X1357012Y917890D03*
X1355162Y921079D03*
X1357012Y924268D03*
X1362563Y933835D03*
X1358863D03*
X1355162D03*
X1362563Y927457D03*
X1358863D03*
X1357012Y930646D03*
X1355162Y940213D03*
X1357012Y943402D03*
X1358863Y946591D03*
X1362563D03*
X1357012Y949780D03*
Y956158D03*
X1355162Y952969D03*
X1358863Y959347D03*
X1362563D03*
X1357012Y962536D03*
X1355162Y965725D03*
X1357012Y968914D03*
X1358863Y972103D03*
X1362563D03*
X1357012Y975292D03*
X1360713Y981670D03*
X1355162Y978481D03*
X1362563Y984859D03*
X1355162D03*
Y991237D03*
Y997615D03*
X1362563Y991237D03*
Y997615D03*
X1360713Y994426D03*
Y988048D03*
Y1000804D03*
X1358863Y1010371D03*
X1360713Y1007182D03*
X1362563Y1003993D03*
X1355162D03*
X1373666Y876434D03*
X1375516Y873245D03*
Y879623D03*
X1369965Y882812D03*
X1366264D03*
X1369965Y889190D03*
X1368115Y892379D03*
X1366264Y895568D03*
X1373666Y882812D03*
X1377367D03*
X1379217Y892379D03*
X1377367Y895568D03*
X1373666Y889190D03*
X1368115Y898757D03*
X1369965Y901946D03*
X1366264D03*
X1368115Y905134D03*
Y911512D03*
X1366264Y908324D03*
X1379217Y898757D03*
X1377367Y901946D03*
X1373666D03*
X1379217Y905134D03*
X1377367Y908324D03*
X1379217Y911512D03*
X1369965Y914701D03*
X1368115Y917890D03*
X1366264Y914701D03*
X1368115Y924268D03*
X1366264Y921079D03*
X1377367Y914701D03*
X1373666D03*
X1379217Y917890D03*
X1377367Y921079D03*
X1379217Y924268D03*
X1366264Y933835D03*
X1369965Y927457D03*
X1368115Y930646D03*
X1369965Y933835D03*
X1366264Y927457D03*
Y940213D03*
X1377367Y927457D03*
X1373666D03*
X1379217Y930646D03*
X1377367Y933835D03*
X1373666D03*
X1377367Y940213D03*
X1368115Y943402D03*
X1369965Y946591D03*
X1368115Y949780D03*
X1366264Y946591D03*
X1368115Y956158D03*
X1366264Y952969D03*
X1379217Y943402D03*
X1373666Y946591D03*
X1377367D03*
X1379217Y949780D03*
X1377367Y952969D03*
X1379217Y956158D03*
X1366264Y959347D03*
X1369965D03*
X1368115Y962536D03*
X1366264Y965725D03*
X1368115Y968914D03*
X1373666Y959347D03*
X1377367Y965725D03*
Y959347D03*
X1379217Y962536D03*
Y968914D03*
X1369965Y972103D03*
X1368115Y975292D03*
Y981670D03*
X1366264Y972103D03*
Y978481D03*
X1369965Y984859D03*
X1373666Y972103D03*
X1377367D03*
X1379217Y975292D03*
X1375516Y981670D03*
X1377367Y978481D03*
Y984859D03*
X1369965Y991237D03*
Y997615D03*
X1368115Y994426D03*
Y988048D03*
Y1000804D03*
X1375516Y994426D03*
X1377367Y991237D03*
Y997615D03*
X1375516Y988048D03*
Y1000804D03*
X1369965Y1003993D03*
X1368115Y1007182D03*
X1366264Y1010371D03*
X1373666D03*
X1375516Y1007182D03*
X1371815D03*
X1377367Y1003993D03*
X1386619Y879623D03*
X1382918Y873245D03*
X1384768Y876434D03*
X1394020Y873245D03*
X1384768Y882812D03*
X1381067D03*
Y889190D03*
X1384768D03*
X1392170Y882812D03*
X1388469D03*
Y895568D03*
X1392170Y889190D03*
X1390319Y892379D03*
X1381067Y901946D03*
X1384768D03*
X1388469D03*
X1390319Y898757D03*
X1392170Y901946D03*
X1388469Y908324D03*
X1390319Y911512D03*
Y905134D03*
X1381067Y914701D03*
X1384768D03*
X1390319Y917890D03*
X1388469Y914701D03*
X1392170D03*
X1388469Y921079D03*
X1390319Y924268D03*
X1381067Y927457D03*
X1384768D03*
X1388469D03*
Y933835D03*
X1392170Y927457D03*
X1390319Y930646D03*
X1392170Y933835D03*
X1388469Y940213D03*
X1390319Y937024D03*
X1381067Y946591D03*
X1384768D03*
X1388469D03*
X1390319Y943402D03*
X1392170Y946591D03*
X1390319Y949780D03*
X1388469Y952969D03*
X1390319Y956158D03*
X1381067Y959347D03*
X1384768D03*
X1388469Y965725D03*
Y959347D03*
X1392170D03*
X1390319Y962536D03*
Y968914D03*
X1388469Y978481D03*
X1381067Y972103D03*
X1384768D03*
X1382918Y981670D03*
X1384768Y984859D03*
X1388469Y972103D03*
X1392170D03*
X1390319Y981670D03*
Y975292D03*
X1392170Y984859D03*
X1384768Y991237D03*
X1382918Y988048D03*
X1392170Y991237D03*
X1390319Y988048D03*
X1397721Y873245D03*
Y879623D03*
X1395871Y876434D03*
X1408823Y879623D03*
X1399571Y882812D03*
X1395871D03*
X1401422Y892379D03*
X1399571Y895568D03*
X1395871Y889190D03*
X1403272Y882812D03*
X1406973D03*
X1403272Y889190D03*
X1406973D03*
X1399571Y901946D03*
X1395871D03*
X1401422Y905134D03*
Y911512D03*
X1405123Y905134D03*
X1408823D03*
X1401422Y898757D03*
X1399571Y908323D03*
Y914701D03*
X1401422Y917890D03*
X1395871Y914701D03*
X1399571Y921079D03*
X1401422Y924268D03*
X1405123Y917890D03*
X1408823D03*
X1395871Y927457D03*
Y933835D03*
X1399571Y927457D03*
X1401422Y930646D03*
X1399571Y933835D03*
Y940213D03*
X1401422Y937024D03*
X1405123Y930646D03*
X1408823D03*
X1405123Y937024D03*
X1408823D03*
X1401422Y943402D03*
X1399571Y946591D03*
X1401422Y949780D03*
X1399571Y952969D03*
X1401422Y956158D03*
X1408823Y949780D03*
X1405123D03*
X1395871Y946591D03*
X1399571Y965725D03*
X1395871Y959347D03*
X1399571D03*
X1401422Y962536D03*
Y968914D03*
X1408823Y962536D03*
X1405123D03*
X1397721Y981670D03*
X1399571Y978481D03*
X1395871Y972103D03*
X1399571D03*
X1401422Y975292D03*
X1399571Y984859D03*
X1405123Y981670D03*
X1408823Y975292D03*
X1405123D03*
X1406973Y984859D03*
X1399571Y991237D03*
X1397721Y988048D03*
X1406973Y991237D03*
X1405123Y988048D03*
X1410674Y876434D03*
X1423602Y879623D03*
X1421751Y876434D03*
X1410674Y882812D03*
Y889190D03*
Y895568D03*
X1421751Y882812D03*
Y895568D03*
Y889190D03*
X1410674Y901946D03*
Y908324D03*
X1421751Y901946D03*
X1423602Y905134D03*
X1421751Y908324D03*
X1410674Y914701D03*
Y921079D03*
X1423602Y917890D03*
X1421751Y914701D03*
Y921079D03*
Y940213D03*
X1410674Y927457D03*
Y933835D03*
Y940213D03*
X1423602Y930646D03*
X1421751Y927457D03*
Y933835D03*
X1423602Y937024D03*
X1410674Y946591D03*
Y952969D03*
X1423602Y949780D03*
X1421751Y946591D03*
Y952969D03*
X1410674Y959347D03*
Y965725D03*
X1423602Y962536D03*
X1421751Y959347D03*
Y965725D03*
X1410674Y972103D03*
Y978481D03*
X1423602Y981670D03*
Y975292D03*
X1421751Y972103D03*
Y978481D03*
Y984859D03*
X1423602Y988048D03*
X1421751Y991237D03*
X1436554Y876434D03*
X1429153Y882812D03*
X1425452Y889190D03*
X1429153D03*
X1431003Y892379D03*
X1432854Y895568D03*
X1436554Y889190D03*
X1432854Y901946D03*
X1431003Y898757D03*
Y911512D03*
Y905134D03*
X1427302D03*
X1436554Y901946D03*
X1432854Y908323D03*
Y914701D03*
X1431003Y917890D03*
X1427302D03*
X1432854Y921079D03*
X1431003Y924268D03*
X1436554Y914701D03*
X1432854Y927457D03*
X1431003Y930646D03*
X1427302D03*
X1432854Y933835D03*
Y940213D03*
X1431003Y937024D03*
X1427302D03*
X1436554Y927457D03*
Y933835D03*
X1431003Y943402D03*
Y949780D03*
X1427302D03*
X1432854Y946591D03*
Y952969D03*
X1431003Y956158D03*
X1436554Y946591D03*
X1432854Y959347D03*
X1427302Y962536D03*
X1431003D03*
X1432854Y965725D03*
X1431003Y968914D03*
X1436554Y959347D03*
X1432854Y978481D03*
X1431003Y981670D03*
X1432854Y972103D03*
X1431003Y975292D03*
X1427302D03*
X1429153Y984859D03*
X1438405Y981670D03*
X1436554Y972103D03*
Y984859D03*
X1431003Y988048D03*
X1429153Y991237D03*
X1436554D03*
X1438405Y988048D03*
X1447657Y876434D03*
X1445806Y879623D03*
X1443956Y882812D03*
X1447657D03*
X1440255Y889190D03*
X1447657D03*
X1442106Y892379D03*
X1443956Y895568D03*
X1451357Y882812D03*
X1451358Y889190D03*
X1453208Y892379D03*
X1442106Y898757D03*
X1440255Y901946D03*
X1447657D03*
X1443956D03*
X1442106Y905134D03*
X1443956Y908324D03*
X1442106Y911512D03*
X1451358Y901946D03*
X1453208Y898757D03*
Y905134D03*
Y911512D03*
X1440255Y914701D03*
X1443956D03*
X1447657D03*
X1442106Y917890D03*
X1443956Y921079D03*
X1442106Y924268D03*
X1451357Y914701D03*
X1453208Y917890D03*
Y924268D03*
X1440255Y927457D03*
X1443956D03*
X1447657D03*
X1440255Y933835D03*
X1443956D03*
X1442106Y937024D03*
X1443956Y940213D03*
X1453208Y930646D03*
X1451357Y927457D03*
X1447657Y946591D03*
X1442106Y943402D03*
X1440255Y946591D03*
X1442106Y949780D03*
X1443956Y946591D03*
Y952969D03*
X1442106Y956158D03*
X1451357Y946591D03*
X1453208Y943402D03*
Y949780D03*
Y956158D03*
X1440255Y959347D03*
X1443956D03*
X1447657D03*
X1443956Y965725D03*
X1442106Y962536D03*
Y968914D03*
X1451357Y959347D03*
X1453208Y962536D03*
Y968914D03*
X1445806Y981670D03*
X1443956Y978481D03*
Y972103D03*
X1447657D03*
X1442106Y975292D03*
X1440255Y972103D03*
X1443956Y984859D03*
X1453208Y981670D03*
X1451357Y972103D03*
X1453208Y975292D03*
X1451357Y984859D03*
X1445806Y988048D03*
X1443956Y991237D03*
X1453208Y988048D03*
Y994426D03*
X1451357Y991237D03*
X1453208Y1000804D03*
Y1007182D03*
X1456909Y873245D03*
Y879623D03*
X1458759Y876434D03*
X1468011Y879623D03*
X1455058Y882812D03*
X1462460D03*
X1466161D03*
X1458759D03*
Y889190D03*
X1455058Y895568D03*
X1464310Y892379D03*
X1466161Y895568D03*
X1462460Y889190D03*
X1464310Y898757D03*
X1455058Y901946D03*
X1458759D03*
X1466161D03*
X1462460D03*
X1464310Y905134D03*
X1455058Y908324D03*
X1464310Y911512D03*
X1466161Y908323D03*
X1458759Y914701D03*
X1464310Y917890D03*
Y924268D03*
X1455058Y921079D03*
X1466161D03*
X1455058Y914701D03*
X1462460D03*
X1466161D03*
X1455058Y927457D03*
X1458759D03*
X1466161D03*
X1462460D03*
X1455058Y933835D03*
X1464310Y930646D03*
X1462460Y933835D03*
X1466161D03*
X1458759D03*
X1455058Y940213D03*
X1466161D03*
X1462460Y946591D03*
X1466161D03*
X1458759D03*
X1466161Y952969D03*
X1464310Y956158D03*
X1455058Y952969D03*
X1464310Y943402D03*
X1455058Y946591D03*
X1464310Y949780D03*
X1455058Y965725D03*
X1466161D03*
X1455058Y959347D03*
X1462460D03*
X1466161D03*
X1458759D03*
X1464310Y962536D03*
Y968914D03*
X1460609Y981670D03*
X1455058Y978481D03*
X1466161D03*
X1455058Y972103D03*
X1462460D03*
X1466161D03*
X1458759D03*
X1464310Y975292D03*
X1458759Y984859D03*
X1466161D03*
X1468011Y981670D03*
X1458759Y997615D03*
X1466161D03*
X1460609Y988048D03*
Y994426D03*
X1458759Y991237D03*
X1466161D03*
X1460609Y1000804D03*
X1468011Y988048D03*
Y994426D03*
Y1000804D03*
X1458759Y1003993D03*
X1466161D03*
Y1010371D03*
X1458759D03*
X1460609Y1007182D03*
X1468011D03*
X1479113Y873245D03*
X1469861Y876434D03*
X1479113Y879623D03*
X1482814Y886001D03*
X1480964Y882812D03*
X1469861D03*
X1479113Y886001D03*
X1482814Y892379D03*
X1469861Y889190D03*
X1473562D03*
X1475413Y892379D03*
X1477263Y895568D03*
X1482814Y898757D03*
X1469861Y901946D03*
X1475413Y898757D03*
X1473562Y901946D03*
X1482814Y905134D03*
Y911512D03*
X1477263Y908324D03*
X1475413Y911512D03*
Y905134D03*
X1482814Y917890D03*
X1469861Y914701D03*
X1473562D03*
X1475413Y917890D03*
Y924268D03*
X1482814D03*
X1477263Y921079D03*
X1469861Y933835D03*
X1473562D03*
X1482814Y930646D03*
X1475413D03*
X1477263Y933835D03*
X1473562Y927457D03*
X1469861D03*
X1482814Y937024D03*
X1477263Y940213D03*
X1482814Y943402D03*
Y949780D03*
X1475413Y943402D03*
X1469861Y946591D03*
X1473562D03*
X1475413Y949780D03*
X1482814Y956158D03*
X1477263Y952969D03*
X1475413Y956158D03*
X1482814Y962536D03*
X1469861Y959347D03*
X1473562D03*
X1475413Y962536D03*
X1477263Y965725D03*
X1482814Y968914D03*
X1475413D03*
X1482814Y975292D03*
Y981670D03*
X1469861Y972103D03*
X1473562D03*
X1475413Y975292D03*
X1477263Y978481D03*
X1475413Y981670D03*
X1473562Y984859D03*
X1475413Y1000804D03*
X1482814Y988048D03*
Y994426D03*
X1473562Y991237D03*
Y997615D03*
X1475413Y988048D03*
Y994426D03*
X1482814Y1000804D03*
Y1007182D03*
X1473562Y1003993D03*
Y1010371D03*
X1475413Y1007182D03*
X1492066Y876434D03*
X1490216Y886001D03*
X1484665Y882812D03*
X1488365D03*
X1495767D03*
X1493917Y886001D03*
X1488365Y889190D03*
X1495767D03*
X1490216Y892379D03*
X1495767Y895568D03*
X1490216Y898757D03*
X1488365Y901946D03*
X1495767D03*
X1488365Y908324D03*
X1490216Y911512D03*
X1495767Y908324D03*
Y914701D03*
X1490216Y917890D03*
X1488365Y921079D03*
X1495767D03*
X1490216Y930646D03*
X1495767Y933835D03*
X1488365Y927457D03*
X1495767D03*
X1488365Y940213D03*
X1495767D03*
X1490216Y937024D03*
X1488365Y946591D03*
X1490216Y949780D03*
X1495767Y946591D03*
Y952969D03*
X1490216Y956158D03*
X1488365Y965725D03*
X1495767Y959347D03*
Y965725D03*
X1488365Y959347D03*
X1490216Y968914D03*
X1495767Y972103D03*
X1490216Y975292D03*
X1486515Y981670D03*
X1488365Y978481D03*
X1495767D03*
X1497617Y981670D03*
X1484665Y984859D03*
X1488365D03*
X1495767D03*
X1490216Y988048D03*
X1488365Y997615D03*
X1490216Y994426D03*
X1495767Y991237D03*
Y997615D03*
X1488365Y1003993D03*
X1490216Y1007182D03*
X1495767Y1003993D03*
Y1010371D03*
X1501318Y873245D03*
Y879623D03*
X1510570Y876434D03*
X1508720Y879623D03*
X1501318Y886001D03*
X1510570Y882812D03*
X1508720Y886001D03*
X1503169Y889190D03*
Y895568D03*
X1501318Y892379D03*
X1508720D03*
X1499468Y882812D03*
X1505019Y886001D03*
X1501318Y898757D03*
X1508720D03*
X1503169Y901946D03*
X1501318Y905134D03*
X1508720D03*
X1501318Y911512D03*
X1508720D03*
X1503169Y908323D03*
Y914701D03*
X1501318Y917890D03*
X1508720D03*
X1503169Y921079D03*
X1501318Y924268D03*
X1508720D03*
X1503169Y927457D03*
X1501318Y930646D03*
X1503169Y933835D03*
X1508720Y930646D03*
Y937024D03*
X1503169Y940213D03*
X1501318Y937024D03*
Y943402D03*
X1508720D03*
X1503169Y946591D03*
X1501318Y949780D03*
X1508720D03*
X1503169Y952969D03*
X1501318Y956158D03*
X1508720D03*
X1503169Y959347D03*
Y965725D03*
X1501318Y962536D03*
X1508720D03*
X1501318Y968914D03*
X1508720D03*
X1510570Y984859D03*
X1512421Y981670D03*
X1503169Y972103D03*
X1501318Y975292D03*
X1503169Y978481D03*
X1501318Y981670D03*
X1508720Y975292D03*
Y981670D03*
X1499468Y984859D03*
X1503169D03*
Y991237D03*
X1501318Y988048D03*
X1503169Y997615D03*
X1501318Y994426D03*
X1508720Y988048D03*
Y994426D03*
X1501318Y1000804D03*
X1508720D03*
X1501318Y1007182D03*
X1503169Y1010371D03*
X1508720Y1007182D03*
X1503169Y1003993D03*
X1521673Y876434D03*
X1517972D03*
X1519822Y879623D03*
X1527224D03*
X1516121D03*
X1523523Y873245D03*
X1514271Y882812D03*
Y889190D03*
X1521673Y882812D03*
X1519822Y886001D03*
X1525373Y882812D03*
X1527224Y886001D03*
X1521673Y889190D03*
Y895568D03*
X1527224Y892379D03*
X1516121D03*
X1514271Y901946D03*
Y908324D03*
X1521673Y901946D03*
X1527224Y898757D03*
X1516121D03*
X1527224Y911512D03*
Y905134D03*
X1516121Y911512D03*
X1521673Y908323D03*
X1514271Y921079D03*
X1521673Y914701D03*
X1527224Y917890D03*
X1516121D03*
X1521673Y921079D03*
X1527224Y924268D03*
X1514271Y927457D03*
Y940213D03*
X1516121Y930646D03*
X1521673Y927457D03*
Y933835D03*
X1527224Y930646D03*
X1516121Y937024D03*
X1527224D03*
X1521673Y940213D03*
X1514271Y946591D03*
X1516121Y949780D03*
X1521673Y946591D03*
X1527224Y943402D03*
Y949780D03*
X1521673Y952969D03*
X1527224Y956158D03*
X1516121D03*
X1514271Y959347D03*
Y965725D03*
X1521673Y959347D03*
Y965725D03*
X1527224Y962536D03*
Y968914D03*
X1516121D03*
X1514271Y978481D03*
Y984859D03*
X1521673Y972103D03*
X1523523Y981670D03*
X1521673Y978481D03*
X1527224Y975292D03*
Y981670D03*
X1516121Y975292D03*
X1521673Y984859D03*
X1525373D03*
X1514271Y997615D03*
X1521673Y991237D03*
Y997615D03*
X1527224Y988048D03*
Y994426D03*
X1516121Y988048D03*
Y994426D03*
X1527224Y1000804D03*
X1514271Y1003993D03*
X1516121Y1007182D03*
X1521673Y1003993D03*
Y1010371D03*
X1527224Y1007182D03*
X1529074Y876434D03*
X1538326Y879623D03*
X1530925Y886001D03*
X1529074Y889190D03*
Y895568D03*
X1540176Y882812D03*
X1536476D03*
X1534625Y886001D03*
X1540176Y889190D03*
X1542027Y892379D03*
X1534625D03*
X1529074Y901946D03*
Y908324D03*
X1542027Y898757D03*
X1540176Y901946D03*
X1534625Y898757D03*
X1540176Y908324D03*
X1542027Y911512D03*
X1534625Y905134D03*
Y911512D03*
X1529074Y914701D03*
Y921079D03*
X1542027Y917890D03*
X1534625D03*
X1540176Y921079D03*
X1534625Y924268D03*
X1529074Y927457D03*
Y933835D03*
Y940213D03*
X1540176Y927457D03*
X1542027Y930646D03*
X1534625D03*
X1542027Y937024D03*
X1540176Y940213D03*
X1534625Y937024D03*
X1529074Y946591D03*
Y952969D03*
X1540176Y946591D03*
X1542027Y949780D03*
X1534625Y943402D03*
Y949780D03*
Y956158D03*
X1542027D03*
X1529074Y959347D03*
Y965725D03*
X1540176Y959347D03*
Y965725D03*
X1534625Y962536D03*
X1542027Y968914D03*
X1534625D03*
X1538326Y981670D03*
X1542027Y975292D03*
X1540176Y978481D03*
X1534625Y975292D03*
Y981670D03*
X1536476Y984859D03*
X1540176D03*
X1529074Y972103D03*
Y978481D03*
Y984859D03*
Y991237D03*
Y997615D03*
X1542027Y988048D03*
X1540176Y997615D03*
X1542027Y994426D03*
X1534625Y988048D03*
Y994426D03*
Y1000804D03*
X1542027Y1007182D03*
X1534625D03*
X1529074Y1003993D03*
Y1010371D03*
X1540176Y1003993D03*
X1545728Y873245D03*
X1553129Y879623D03*
X1545728Y886001D03*
X1547578Y882812D03*
X1553129Y886001D03*
X1551279Y882812D03*
X1547578Y889190D03*
Y895568D03*
X1553129Y892379D03*
X1547578Y901946D03*
X1553129Y898757D03*
X1547578Y908324D03*
Y914701D03*
Y921079D03*
Y927457D03*
Y933835D03*
Y940213D03*
Y946591D03*
Y952969D03*
Y959347D03*
Y965725D03*
X1543877Y984859D03*
X1547578Y972103D03*
Y978481D03*
Y984859D03*
X1545728Y988048D03*
X1547578Y991237D03*
Y997615D03*
Y1003993D03*
Y1010371D03*
G54D59*
X928740Y321654D03*
G54D34*
X250326Y185236D03*
X368437D03*
G54D60*
X916546Y309460D03*
X911495Y321654D03*
X916546Y333848D03*
X928740Y304409D03*
Y338899D03*
X940934Y309460D03*
X945985Y321654D03*
X940934Y333848D03*
G54D71*
X1766929Y1714960D03*
G54D11*
X19685Y-29134D03*
Y1803261D03*
X2081889Y-29134D03*
Y1803261D03*
G54D27*
X117933Y605376D03*
X763602Y605413D03*
X1094076Y605378D03*
X1739745Y605411D03*
G54D18*
X44000Y154200D03*
X31818Y1424257D03*
X441043Y1672205D03*
Y1718465D03*
X1416437Y1672205D03*
Y1718465D03*
X1800449Y126194D03*
X1804650Y1667292D03*
G54D52*
X791280Y1704890D03*
X1066280D03*
G54D32*
X230905Y1644448D03*
Y1658621D03*
Y1672795D03*
Y1686968D03*
Y1701141D03*
Y1715314D03*
Y1729488D03*
X246653Y1644448D03*
X238779Y1648385D03*
X246653Y1658621D03*
X238779Y1662558D03*
X246653Y1672795D03*
X238779Y1676732D03*
X246653Y1686968D03*
X238779Y1690905D03*
X246653Y1701141D03*
X238779Y1705078D03*
X246653Y1715314D03*
X238779Y1719251D03*
X246653Y1729488D03*
X238779Y1733425D03*
X254527Y1648385D03*
Y1662558D03*
Y1676732D03*
Y1690905D03*
Y1705078D03*
Y1719251D03*
Y1733425D03*
X262401Y1644448D03*
X270275Y1648385D03*
X262401Y1658621D03*
X270275Y1662558D03*
X262401Y1672795D03*
X270275Y1676732D03*
X262401Y1686968D03*
X270275Y1690905D03*
X262401Y1701141D03*
X270275Y1705078D03*
X262401Y1715314D03*
X270275Y1719251D03*
X262401Y1729488D03*
X270275Y1733425D03*
X278149Y1644448D03*
X286023Y1648385D03*
X278149Y1658621D03*
X286023Y1662558D03*
X278149Y1672795D03*
X286023Y1676732D03*
X278149Y1686968D03*
X286023Y1690905D03*
X278149Y1701141D03*
X286023Y1705078D03*
X278149Y1715314D03*
X286023Y1719251D03*
X278149Y1729488D03*
X286023Y1733425D03*
X297835Y1672795D03*
X305709Y1676732D03*
X297835Y1686968D03*
X305709Y1690905D03*
X297835Y1701141D03*
X305709Y1705078D03*
X297835Y1715314D03*
X305709Y1719251D03*
X297835Y1729488D03*
X305709Y1733425D03*
X313583Y1672795D03*
X321457Y1676732D03*
X313583Y1686968D03*
X321457Y1690905D03*
X313583Y1701141D03*
X321457Y1705078D03*
X313583Y1715314D03*
X321457Y1719251D03*
X313583Y1729488D03*
X321457Y1733425D03*
X329331Y1672795D03*
Y1686968D03*
Y1701141D03*
Y1715314D03*
Y1729488D03*
X345079Y1672795D03*
X337205Y1676732D03*
X345079Y1686968D03*
X337205Y1690905D03*
X345079Y1701141D03*
X337205Y1705078D03*
X345079Y1715314D03*
X337205Y1719251D03*
X345079Y1729488D03*
X337205Y1733425D03*
X352953Y1676732D03*
Y1690905D03*
Y1705078D03*
Y1719251D03*
Y1733425D03*
X495078Y1672795D03*
Y1686968D03*
Y1701141D03*
Y1715314D03*
Y1729488D03*
X510826Y1672795D03*
X502952Y1676732D03*
X510826Y1686968D03*
X502952Y1690905D03*
X510826Y1701141D03*
X502952Y1705078D03*
X510826Y1715314D03*
X502952Y1719251D03*
X510826Y1729488D03*
X502952Y1733425D03*
X526574Y1672795D03*
X518700Y1676732D03*
X526574Y1686968D03*
X518700Y1690905D03*
X526574Y1701141D03*
X518700Y1705078D03*
X526574Y1715314D03*
X518700Y1719251D03*
X526574Y1729488D03*
X518700Y1733425D03*
X542322Y1672795D03*
X534448Y1676732D03*
X542322Y1686968D03*
X534448Y1690905D03*
X542322Y1701141D03*
X534448Y1705078D03*
X542322Y1715314D03*
X534448Y1719251D03*
X542322Y1729488D03*
X534448Y1733425D03*
X550196Y1676732D03*
Y1690905D03*
Y1705078D03*
Y1719251D03*
Y1733425D03*
X562008Y1672795D03*
X569882Y1676732D03*
X562008Y1686968D03*
X569882Y1690905D03*
X562008Y1701141D03*
X569882Y1705078D03*
X562008Y1715314D03*
X569882Y1719251D03*
X562008Y1729488D03*
X569882Y1733425D03*
X577756Y1672795D03*
X585630Y1676732D03*
X577756Y1686968D03*
X585630Y1690905D03*
X577756Y1701141D03*
X585630Y1705078D03*
X577756Y1715314D03*
X585630Y1719251D03*
X577756Y1729488D03*
X585630Y1733425D03*
X593504Y1672795D03*
X601378Y1676732D03*
X593504Y1686968D03*
X601378Y1690905D03*
X593504Y1701141D03*
X601378Y1705078D03*
X593504Y1715314D03*
X601378Y1719251D03*
X593504Y1729488D03*
X601378Y1733425D03*
X609252Y1672795D03*
X617126Y1676732D03*
X609252Y1686968D03*
X617126Y1690905D03*
X609252Y1701141D03*
X617126Y1705078D03*
X609252Y1715314D03*
X617126Y1719251D03*
X609252Y1729488D03*
X617126Y1733425D03*
X1238778Y1672795D03*
Y1686968D03*
Y1701141D03*
Y1715314D03*
Y1729488D03*
X1254526Y1672795D03*
X1246652Y1676732D03*
X1254526Y1686968D03*
X1246652Y1690905D03*
X1254526Y1701141D03*
X1246652Y1705078D03*
X1254526Y1715314D03*
X1246652Y1719251D03*
X1254526Y1729488D03*
X1246652Y1733425D03*
X1270274Y1672795D03*
X1262400Y1676732D03*
X1270274Y1686968D03*
X1262400Y1690905D03*
X1270274Y1701141D03*
X1262400Y1705078D03*
X1270274Y1715314D03*
X1262400Y1719251D03*
X1270274Y1729488D03*
X1262400Y1733425D03*
X1286022Y1672795D03*
X1278148Y1676732D03*
X1286022Y1686968D03*
X1278148Y1690905D03*
X1286022Y1701141D03*
X1278148Y1705078D03*
X1286022Y1715314D03*
X1278148Y1719251D03*
X1286022Y1729488D03*
X1278148Y1733425D03*
X1305708Y1672795D03*
Y1686968D03*
X1293896Y1676732D03*
X1305708Y1701141D03*
X1293896Y1690905D03*
X1305708Y1715314D03*
X1293896Y1705078D03*
X1305708Y1729488D03*
X1293896Y1719251D03*
Y1733425D03*
X1313582Y1676732D03*
Y1690905D03*
Y1705078D03*
Y1719251D03*
Y1733425D03*
X1321456Y1672795D03*
X1329330Y1676732D03*
X1321456Y1686968D03*
X1329330Y1690905D03*
X1321456Y1701141D03*
X1329330Y1705078D03*
X1321456Y1715314D03*
X1329330Y1719251D03*
X1321456Y1729488D03*
X1329330Y1733425D03*
X1337204Y1672795D03*
X1345078Y1676732D03*
X1337204Y1686968D03*
X1345078Y1690905D03*
X1337204Y1701141D03*
X1345078Y1705078D03*
X1337204Y1715314D03*
X1345078Y1719251D03*
X1337204Y1729488D03*
X1345078Y1733425D03*
X1352952Y1672795D03*
X1360826Y1676732D03*
X1352952Y1686968D03*
X1360826Y1690905D03*
X1352952Y1701141D03*
X1360826Y1705078D03*
X1352952Y1715314D03*
X1360826Y1719251D03*
X1352952Y1729488D03*
X1360826Y1733425D03*
X1502952Y1672795D03*
X1510826Y1676732D03*
X1502952Y1686968D03*
X1510826Y1690905D03*
X1502952Y1701141D03*
X1510826Y1705078D03*
X1502952Y1715314D03*
X1510826Y1719251D03*
X1502952Y1729488D03*
X1510826Y1733425D03*
X1518700Y1672795D03*
X1526574Y1676732D03*
X1518700Y1686968D03*
X1526574Y1690905D03*
X1518700Y1701141D03*
X1526574Y1705078D03*
X1518700Y1715314D03*
X1526574Y1719251D03*
X1518700Y1729488D03*
X1526574Y1733425D03*
X1534448Y1672795D03*
X1542322Y1676732D03*
X1534448Y1686968D03*
X1542322Y1690905D03*
X1534448Y1701141D03*
X1542322Y1705078D03*
X1534448Y1715314D03*
X1542322Y1719251D03*
X1534448Y1729488D03*
X1542322Y1733425D03*
X1550196Y1672795D03*
X1558070Y1676732D03*
X1550196Y1686968D03*
X1558070Y1690905D03*
X1550196Y1701141D03*
X1558070Y1705078D03*
X1550196Y1715314D03*
X1558070Y1719251D03*
X1550196Y1729488D03*
X1558070Y1733425D03*
X1569882Y1672795D03*
Y1686968D03*
Y1701141D03*
Y1715314D03*
Y1729488D03*
X1585630Y1672795D03*
X1577756Y1676732D03*
X1585630Y1686968D03*
X1577756Y1690905D03*
X1585630Y1701141D03*
X1577756Y1705078D03*
X1585630Y1715314D03*
X1577756Y1719251D03*
X1585630Y1729488D03*
X1577756Y1733425D03*
X1601378Y1672795D03*
X1593504Y1676732D03*
X1601378Y1686968D03*
X1593504Y1690905D03*
X1601378Y1701141D03*
X1593504Y1705078D03*
X1601378Y1715314D03*
X1593504Y1719251D03*
X1601378Y1729488D03*
X1593504Y1733425D03*
X1617126Y1672795D03*
X1609252Y1676732D03*
X1617126Y1686968D03*
X1609252Y1690905D03*
X1617126Y1701141D03*
X1609252Y1705078D03*
X1617126Y1715314D03*
X1609252Y1719251D03*
X1617126Y1729488D03*
X1609252Y1733425D03*
X1625000Y1676732D03*
Y1690905D03*
Y1705078D03*
Y1719251D03*
Y1733425D03*
G54D45*
X441043Y1698268D03*
X1416437D03*
G54D54*
X805690Y204724D03*
X1057659D03*
G54D15*
X17292Y290137D03*
X35689Y301357D03*
X33822Y1462075D03*
Y1459075D03*
Y1456075D03*
X36822D03*
Y1459075D03*
Y1462075D03*
X33822Y1465075D03*
X36822D03*
X37671Y1515214D03*
X34704Y1515235D03*
X47892Y290137D03*
X49400Y384392D03*
X49250Y396332D03*
X47618Y412613D03*
X47619Y421655D03*
X42822Y1462075D03*
Y1459075D03*
Y1456075D03*
Y1465075D03*
X47138Y1513072D03*
X47089Y1510268D03*
X50642Y1557451D03*
X45633Y1592481D03*
X50133D03*
X38426Y1654079D03*
X41427Y1668587D03*
X38426Y1659059D03*
X44583Y1672433D03*
Y1677613D03*
X66289Y301357D03*
X61340Y384362D03*
X61250Y396142D03*
X56542Y589521D03*
X66822Y1462075D03*
Y1459075D03*
Y1456075D03*
X57822Y1462075D03*
Y1459075D03*
Y1456075D03*
X66822Y1465075D03*
X57822D03*
X63990Y1562177D03*
Y1567627D03*
Y1564727D03*
X63915Y1558805D03*
Y1556254D03*
X63990Y1570427D03*
X61225Y1570283D03*
X58564Y1570209D03*
X65767Y1609405D03*
X59767D03*
X53767D03*
X65767Y1615405D03*
X65943Y1621405D03*
X59767D03*
X53767Y1615405D03*
Y1621405D03*
X59427Y1644410D03*
X53648Y1653088D03*
X77790Y520108D03*
X77733Y526764D03*
X77790Y537808D03*
X77733Y544464D03*
X81822Y1462075D03*
Y1456075D03*
Y1465075D03*
X68427Y1644410D03*
X73427D03*
X80000Y1702450D03*
X79500Y1720450D03*
X88722Y1462075D03*
X85722D03*
X88722Y1456075D03*
X85722D03*
X88722Y1465075D03*
X85722D03*
X85621Y1551969D03*
X82974Y1552051D03*
X83340Y1654353D03*
X89466Y1663138D03*
Y1667127D03*
X83340Y1659333D03*
X85395Y1670331D03*
Y1675311D03*
X102096Y1555442D03*
X100439Y1667361D03*
X106573Y1660235D03*
X100915Y1679564D03*
X105069Y1685763D03*
X102243Y1682263D03*
Y1689263D03*
X120016Y300654D03*
Y320631D03*
X114973Y1660235D03*
X113469Y1685763D03*
X133120Y1454751D03*
X137120D03*
X141028Y1454705D03*
X140775Y1638035D03*
X146982Y526997D03*
X145028Y1454705D03*
X152449Y1623572D03*
Y1628528D03*
X151611Y1663933D03*
X159427Y1687843D03*
X151510Y1676811D03*
X163113Y1477590D03*
Y1499490D03*
X164730Y1521561D03*
X161239Y1636147D03*
Y1631191D03*
X162995Y1661377D03*
X160011Y1663933D03*
X163003Y1666462D03*
X159910Y1676811D03*
X162848Y1679357D03*
X162840Y1674272D03*
X187250Y129674D03*
X189410Y388180D03*
X200754Y595174D03*
Y603274D03*
X192951Y1560498D03*
X196081Y1639349D03*
X195504Y1645359D03*
X203754Y595174D03*
Y603274D03*
X207968Y1653130D03*
X203800Y1646832D03*
X272242Y523076D03*
X276085Y1509654D03*
X270720Y1531073D03*
X273220D03*
X275720D03*
X281147Y521803D03*
X280621Y1478082D03*
X291175Y1477590D03*
X283221Y1484772D03*
Y1479992D03*
X278021Y1484772D03*
Y1479992D03*
X283221Y1493392D03*
X280621Y1491482D03*
X278021Y1493392D03*
X291175Y1499490D03*
X283221Y1498172D03*
X278021D03*
X291619Y1536606D03*
X291593Y1529402D03*
Y1531902D03*
X284800Y1526750D03*
X277572Y1536763D03*
X280072D03*
X291619Y1539106D03*
X292792Y1521561D03*
X297323Y1651172D03*
X318660Y24989D03*
X307255Y1641150D03*
X339914Y165170D03*
X384668Y471926D03*
X410701Y99148D03*
X396977Y216685D03*
X399625Y479119D03*
X408683Y1478082D03*
Y1491482D03*
X406083Y1479992D03*
Y1484772D03*
Y1493392D03*
Y1498172D03*
X404147Y1509654D03*
X398782Y1531073D03*
X401282D03*
X403782D03*
X411800Y220200D03*
X413425Y479042D03*
X411283Y1479992D03*
Y1484772D03*
Y1493392D03*
Y1498172D03*
X412862Y1526750D03*
X436090Y120007D03*
X429997Y166400D03*
X441997D03*
X439299Y220046D03*
X427225Y478965D03*
X440159Y966741D03*
Y981741D03*
Y974241D03*
X427286Y1477590D03*
Y1499490D03*
X428746Y1521727D03*
X427730Y1536606D03*
X427704Y1531902D03*
Y1529402D03*
X427730Y1539106D03*
X428500Y1650000D03*
X465997Y166400D03*
X457997D03*
X466041Y1664913D03*
X483467Y209755D03*
X514418Y145171D03*
Y149171D03*
Y153171D03*
X513360Y169190D03*
X511771Y199576D03*
X506261Y865338D03*
X522418Y153171D03*
X516572Y865327D03*
X530418Y145171D03*
Y149171D03*
Y153171D03*
X531280Y210922D03*
X544794Y1478082D03*
Y1491482D03*
X542194Y1479992D03*
Y1484772D03*
Y1493392D03*
X537694Y1504872D03*
X542194Y1498172D03*
X543759Y1536882D03*
X540193Y1531073D03*
X537693D03*
X535193D03*
X541259Y1536882D03*
X555348Y1477590D03*
X547394Y1479992D03*
Y1484772D03*
Y1493392D03*
X555348Y1499490D03*
X547394Y1498172D03*
X556965Y1521561D03*
X556642Y1529389D03*
X554715Y1531564D03*
X550540Y1526910D03*
X556197Y1536687D03*
Y1539187D03*
X561248Y106985D03*
Y100399D03*
X562208Y387227D03*
Y376427D03*
Y401158D03*
X568433Y415846D03*
X581985Y379577D03*
Y390377D03*
Y404308D03*
X588723Y423949D03*
X593975Y164440D03*
X598208Y387227D03*
Y376427D03*
X599164Y432209D03*
X604718Y257562D03*
X617985Y379577D03*
Y398578D03*
Y390377D03*
X610935Y409996D03*
X615075Y443000D03*
X633882Y587488D03*
X646285Y297171D03*
X640317Y391085D03*
X634566Y407848D03*
X639482Y587488D03*
X645446Y587300D03*
X653821Y90326D03*
X653013Y443200D03*
X664170Y445711D03*
X651046Y587300D03*
X672856Y1478082D03*
Y1491482D03*
X675112Y1479602D03*
X675456Y1484772D03*
Y1493392D03*
X670256Y1479992D03*
Y1484772D03*
Y1493392D03*
X665756Y1504872D03*
X675456Y1498172D03*
X670256D03*
X680710Y1520284D03*
X683674Y1522287D03*
X695796Y418358D03*
X708395Y430957D03*
X702095Y421508D03*
X698946Y437256D03*
X702095Y449854D03*
X708395Y474971D03*
X698946Y468672D03*
X695796Y487570D03*
X706172Y1552082D03*
X698003Y1684692D03*
X711544Y421508D03*
X720993Y443555D03*
Y446705D03*
X717843D03*
Y440405D03*
X720993Y449854D03*
Y462373D03*
Y459223D03*
Y456074D03*
X717843Y459223D03*
Y465523D03*
X711544Y484420D03*
X722141Y1405912D03*
X721916Y1414339D03*
Y1416939D03*
X722141Y1408412D03*
X721916Y1428989D03*
Y1431589D03*
X733512Y427807D03*
X727292Y421508D03*
X736661Y443555D03*
X733512Y446705D03*
Y443555D03*
X727292Y446705D03*
Y443555D03*
X724143D03*
Y462373D03*
X727292D03*
X733512Y459223D03*
X727292D03*
X733512Y462373D03*
X736661D03*
X727292Y474971D03*
X736661Y484420D03*
X724143D03*
X752409Y421508D03*
X739811Y443555D03*
Y446705D03*
X742961Y440405D03*
X739811Y449854D03*
Y456074D03*
Y459223D03*
Y462373D03*
X742961Y465523D03*
X752409Y484420D03*
X746082Y1506931D03*
X751030Y1668583D03*
X765008Y418358D03*
X758709Y437256D03*
X755559Y456074D03*
X758709Y468672D03*
X765008Y487570D03*
X758179Y1482049D03*
X758163Y1526223D03*
X758179Y1534963D03*
X779014Y1343262D03*
Y1340062D03*
X782014D03*
Y1337062D03*
Y1343262D03*
X780000Y1353500D03*
X779014Y1346462D03*
Y1349862D03*
X782014Y1346462D03*
Y1349862D03*
X780000Y1357500D03*
Y1363500D03*
Y1360500D03*
X780111Y1405366D03*
X782758Y1405249D03*
X795421Y1331257D03*
X785014Y1350862D03*
X804099Y1333835D03*
X801171Y1343278D03*
X810986Y1361684D03*
X819115Y115223D03*
X824499Y145198D03*
X820405Y311830D03*
X831115Y115223D03*
X829115Y150273D03*
X838670Y1518558D03*
X841310Y1518608D03*
X838630Y1521538D03*
X841270Y1521588D03*
X854578Y99651D03*
X856397Y339751D03*
X847007Y1521458D03*
X844367Y1521408D03*
Y1518784D03*
X847007Y1518834D03*
X855853Y1521308D03*
X853213Y1521258D03*
X850146Y1521261D03*
Y1518637D03*
X853213Y1518634D03*
X855853Y1518684D03*
X860152Y328399D03*
X865132D03*
X861377Y339751D03*
X872986Y753451D03*
X858581Y1518568D03*
X858567Y1521416D03*
X876133Y73580D03*
Y95580D03*
Y117580D03*
X919272Y989932D03*
X921289Y1663187D03*
X942779Y277731D03*
X936693Y1462328D03*
X939507Y1462497D03*
X945195Y1459453D03*
X942056Y1459650D03*
X939416Y1459600D03*
Y1456976D03*
X942056Y1457026D03*
X945195Y1456829D03*
X951099Y632206D03*
X956693Y1459805D03*
X953630Y1456760D03*
X958383Y1462447D03*
X950902Y1459500D03*
X948262Y1459450D03*
X953616Y1459608D03*
X948262Y1456826D03*
X950902Y1456876D03*
X953520Y1567570D03*
X950520D03*
X959520D03*
X956520D03*
X953520Y1582570D03*
X950520D03*
Y1579570D03*
X953520D03*
Y1576570D03*
X950520D03*
X953520Y1573570D03*
X950520D03*
Y1570570D03*
X953520D03*
X959520Y1582570D03*
X956520D03*
Y1579570D03*
X959520D03*
Y1576570D03*
X956520D03*
X959520Y1573570D03*
X956520D03*
Y1570570D03*
X959520D03*
X953520Y1588570D03*
X950520D03*
Y1585570D03*
X953520D03*
X959520Y1588570D03*
X956520D03*
Y1585570D03*
X959520D03*
X977150Y1052684D03*
X966000Y1300000D03*
X968500D03*
X971000D03*
X988160Y1567710D03*
X991160D03*
X985160D03*
X988160Y1582710D03*
X991160D03*
X985160D03*
Y1579710D03*
X991160D03*
X988160D03*
X991160Y1570710D03*
X988160D03*
Y1573710D03*
X991160D03*
X988160Y1576710D03*
X991160D03*
X985160Y1570710D03*
Y1573710D03*
Y1576710D03*
X988160Y1588710D03*
X991160D03*
X985160D03*
Y1585710D03*
X991160D03*
X988160D03*
X1014206Y510304D03*
X1013306Y526146D03*
X1016750Y1567710D03*
X1019750D03*
X1016750Y1576710D03*
Y1573710D03*
Y1570710D03*
X1019750Y1576710D03*
Y1573710D03*
Y1570710D03*
Y1579710D03*
X1016750D03*
Y1582710D03*
X1019750D03*
Y1585710D03*
X1016750D03*
Y1588710D03*
X1019750D03*
X1022750Y1567710D03*
Y1576710D03*
Y1573710D03*
Y1570710D03*
Y1579710D03*
Y1582710D03*
Y1585710D03*
Y1588710D03*
X1045254Y521074D03*
X1037212Y510940D03*
X1048219Y1567883D03*
X1051219D03*
X1048219Y1576883D03*
Y1573883D03*
Y1570883D03*
X1051219Y1576883D03*
Y1573883D03*
Y1570883D03*
Y1579883D03*
X1048219D03*
Y1582883D03*
X1051219D03*
Y1585883D03*
X1048219D03*
Y1588883D03*
X1051219D03*
X1055934Y385488D03*
X1054219Y1567883D03*
Y1576883D03*
Y1573883D03*
Y1570883D03*
Y1579883D03*
Y1582883D03*
Y1585883D03*
Y1588883D03*
X1068143Y383688D03*
X1073204Y383417D03*
X1083819Y353094D03*
X1119067Y1551457D03*
X1133765Y1572102D03*
X1170986Y1510590D03*
Y1532490D03*
X1183354Y77685D03*
X1176972Y86788D03*
X1200824Y1593498D03*
X1192612Y1680410D03*
X1207954Y1680419D03*
X1209879Y1700359D03*
X1230094Y314216D03*
X1226094Y305216D03*
X1216875Y1705826D03*
X1216738Y1720861D03*
X1277732Y236594D03*
Y246594D03*
Y241594D03*
Y251594D03*
X1288494Y1511082D03*
X1285894Y1512992D03*
Y1517772D03*
X1288494Y1524482D03*
X1285894Y1531172D03*
Y1526392D03*
X1283958Y1542654D03*
X1278593Y1564073D03*
X1281093D03*
X1283593D03*
X1287945Y1569763D03*
X1285445D03*
X1302365Y1418702D03*
X1292522Y1421596D03*
X1303943Y1430729D03*
X1299048Y1510590D03*
X1291094Y1512992D03*
Y1517772D03*
X1299048Y1532490D03*
X1291094Y1531172D03*
Y1526392D03*
X1299466Y1562402D03*
Y1564902D03*
X1292673Y1559750D03*
X1299492Y1572106D03*
Y1569606D03*
X1307766Y563013D03*
X1308700Y590300D03*
X1317266Y592522D03*
X1308700Y587800D03*
X1313109Y1195398D03*
Y1200898D03*
X1325366Y592522D03*
X1339488Y1202295D03*
X1340483Y1209006D03*
X1336861Y1222119D03*
X1350809Y1202323D03*
X1368137Y1222298D03*
Y1227798D03*
X1383800Y1685398D03*
X1406655Y1564073D03*
X1409155D03*
X1399940Y1637127D03*
X1414619Y244450D03*
X1416301Y966740D03*
Y981740D03*
Y974240D03*
X1416556Y1511082D03*
X1419156Y1512992D03*
Y1517772D03*
X1413956Y1512992D03*
Y1517772D03*
X1416556Y1524482D03*
X1419156Y1531172D03*
Y1526392D03*
X1413956Y1531172D03*
Y1526392D03*
X1412020Y1542654D03*
X1420735Y1559750D03*
X1411655Y1564073D03*
X1435160Y1510590D03*
Y1532490D03*
X1435578Y1564902D03*
Y1562402D03*
X1436940Y1554277D03*
X1435604Y1572106D03*
Y1569606D03*
X1445985Y116953D03*
X1441390Y163944D03*
X1442993Y176204D03*
X1462405Y61563D03*
X1461242Y128242D03*
X1463017Y136368D03*
X1465832Y535330D03*
X1542767Y1564073D03*
X1552668Y1511082D03*
X1555268Y1512992D03*
Y1517772D03*
X1550068Y1512992D03*
Y1517772D03*
X1552668Y1524482D03*
X1555268Y1531172D03*
Y1526392D03*
X1550068Y1531172D03*
Y1526392D03*
X1548132Y1542654D03*
X1556847Y1559750D03*
X1545267Y1564073D03*
X1547767D03*
X1552118Y1569763D03*
X1549618D03*
X1563222Y1510590D03*
Y1532490D03*
X1564581Y1562316D03*
X1562613Y1564816D03*
X1564128Y1572225D03*
X1562621Y1569761D03*
X1602270Y229530D03*
X1629597Y221842D03*
X1619909Y306746D03*
X1643283Y1425541D03*
X1648337Y1451313D03*
X1654419Y233062D03*
X1655383Y1425541D03*
X1656997Y1708609D03*
Y1723759D03*
X1665100Y156762D03*
Y166762D03*
X1673223Y220857D03*
X1673630Y1533092D03*
Y1537872D03*
X1684925Y118762D03*
Y149762D03*
Y161762D03*
Y153762D03*
X1684942Y234000D03*
X1683587Y1433425D03*
X1680430Y1511198D03*
X1682760Y1512169D03*
X1683330Y1517772D03*
X1678130Y1512992D03*
Y1517772D03*
X1680730Y1524482D03*
X1683330Y1531172D03*
Y1526392D03*
X1678130Y1531172D03*
Y1526392D03*
X1688584Y1553284D03*
X1691548Y1555287D03*
X1686857Y1683918D03*
X1684733Y1698952D03*
X1695102Y1698947D03*
X1691357Y1688418D03*
X1691997Y1708609D03*
X1733083Y654034D03*
X1737606Y1539807D03*
X1736579Y1587480D03*
X1723929Y1654456D03*
X1723963Y1658965D03*
Y1663465D03*
Y1667965D03*
X1731117Y1705115D03*
Y1720265D03*
X1741329Y1482405D03*
Y1485405D03*
Y1491405D03*
Y1488405D03*
X1740058Y1537419D03*
X1744866Y1539589D03*
X1742165Y1539620D03*
X1740979Y1577905D03*
X1743681Y1626750D03*
X1750681D03*
X1747181D03*
X1743481Y1616550D03*
X1750481D03*
X1746981D03*
X1747963Y1641965D03*
X1764029Y1485405D03*
Y1482405D03*
Y1491405D03*
Y1488405D03*
X1756329Y1485405D03*
Y1482405D03*
Y1491405D03*
Y1488405D03*
X1769054Y1585705D03*
X1753079Y1596650D03*
Y1606550D03*
Y1603050D03*
Y1600150D03*
X1761839Y1634223D03*
X1757763Y1643365D03*
X1761494Y1661947D03*
X1779029Y1482405D03*
Y1485405D03*
Y1491405D03*
Y1488405D03*
X1772904Y1585005D03*
X1773863Y1661465D03*
X1774940Y1669037D03*
X1773738Y1672965D03*
X1773963Y1680965D03*
X1793070Y25001D03*
X1788029Y1485405D03*
Y1482405D03*
Y1491405D03*
Y1488405D03*
X1789379Y1588478D03*
X1805525Y146716D03*
X1812029Y1485405D03*
Y1482405D03*
X1803029D03*
Y1485405D03*
X1812029Y1491405D03*
Y1488405D03*
X1803029Y1491405D03*
Y1488405D03*
X1801789Y1536742D03*
X1807408Y1539223D03*
X1810408D03*
X1812078Y1596725D03*
X1812003Y1607375D03*
Y1603875D03*
X1812078Y1600225D03*
X1809179Y1616550D03*
X1809254Y1613775D03*
X1812570Y159275D03*
X1827029Y1488405D03*
Y1491405D03*
Y1485405D03*
Y1482405D03*
X1815344Y1539373D03*
X1818344D03*
X1823112Y1538659D03*
X1812679Y1616550D03*
X1816179D03*
X1812754Y1613775D03*
X1816254D03*
X1837641Y159275D03*
X1840700Y326201D03*
Y348201D03*
Y370201D03*
Y392201D03*
Y414201D03*
Y436201D03*
Y458201D03*
Y480201D03*
Y502201D03*
Y524201D03*
Y546201D03*
Y568201D03*
Y590201D03*
Y656201D03*
Y678201D03*
Y700201D03*
Y722201D03*
Y744201D03*
Y766201D03*
Y788201D03*
Y810201D03*
Y832201D03*
Y854201D03*
Y876201D03*
Y898201D03*
Y920201D03*
Y942201D03*
Y964201D03*
Y986201D03*
Y1008201D03*
Y1030201D03*
Y1052201D03*
Y1074201D03*
Y1096201D03*
Y1118201D03*
Y1140201D03*
Y1162201D03*
Y1184201D03*
Y1206201D03*
Y1228201D03*
Y1250201D03*
Y1272201D03*
Y1294201D03*
Y1316201D03*
Y1338201D03*
Y1404201D03*
Y1448201D03*
Y1470201D03*
Y1492201D03*
Y1514201D03*
Y1536201D03*
Y1558201D03*
Y1580201D03*
X1828889Y1622578D03*
Y1644578D03*
Y1666578D03*
Y1688578D03*
X1854479Y66461D03*
Y110461D03*
Y132461D03*
Y154461D03*
X1847866Y159124D03*
X1854479Y176461D03*
Y198461D03*
Y220461D03*
Y242461D03*
Y264461D03*
Y286461D03*
G54D58*
X922441Y154311D03*
Y243799D03*
G54D12*
X21569Y49379D03*
X21345Y387760D03*
X21309Y395712D03*
X36500Y323500D03*
X33686Y383944D03*
X27309Y383926D03*
X29962Y401000D03*
X36524Y398013D03*
X26771Y398811D03*
X30680Y438142D03*
X35852Y664480D03*
Y686410D03*
Y683910D03*
X43569Y49379D03*
X45423Y197224D03*
Y212224D03*
Y202224D03*
Y207224D03*
X40000Y323500D03*
X55190Y360862D03*
X42809D03*
X46834D03*
X39410Y384582D03*
X39226Y395346D03*
X53825Y421746D03*
X49848Y524210D03*
X49889Y531149D03*
X50880Y1421963D03*
X52405Y1514835D03*
X49405D03*
X52405Y1511986D03*
X49405D03*
X52330Y1509137D03*
X49330D03*
X52796Y1526469D03*
X52905Y1523335D03*
X47760Y1529506D03*
X65347Y66847D03*
X60367D03*
X65347Y71839D03*
X60367D03*
X58457Y69340D03*
X67575Y287500D03*
X56620Y303500D03*
X64150Y434972D03*
X53800Y435451D03*
X54762Y444993D03*
X56800Y524220D03*
X56719Y531120D03*
X64923Y795316D03*
Y832127D03*
Y868938D03*
Y905750D03*
Y942561D03*
Y1089805D03*
Y1126616D03*
Y1163427D03*
Y1200238D03*
Y1237049D03*
X58349Y1412731D03*
X55755Y1511885D03*
X55905Y1514835D03*
X57281Y1523287D03*
X66081D03*
X59881D03*
X63481D03*
X55789Y1509224D03*
X57281Y1526394D03*
X66081D03*
X65281Y1529501D03*
X59881Y1526394D03*
X63481D03*
X62681Y1529501D03*
X64235Y1533150D03*
X61755D03*
X59275D03*
X67196Y1552869D03*
X64235Y1538750D03*
X61755D03*
X59275D03*
X63802Y1579997D03*
X58602D03*
X61302D03*
X75928Y3001D03*
X81159Y17045D03*
X72087Y25977D03*
X74087Y23981D03*
X79043D03*
X81043Y25977D03*
X79192Y19541D03*
X81159Y22037D03*
X73025Y37106D03*
X80111D03*
X73025Y48720D03*
X80111D03*
X69453Y75343D03*
X82367Y71839D03*
X80457Y69340D03*
X82367Y66847D03*
X76347Y72850D03*
X71367D03*
X76347Y77842D03*
X71367D03*
X71779Y157194D03*
Y161194D03*
X71772Y421746D03*
X68365Y443677D03*
X80915Y756766D03*
X73873D03*
Y760266D03*
X69323Y776911D03*
X80915Y763766D03*
X80015Y786950D03*
X69323Y783604D03*
X81065Y791970D03*
X80015Y796989D03*
X69323Y807029D03*
Y813722D03*
Y820415D03*
X80015Y823761D03*
Y833800D03*
X81065Y828781D03*
X69323Y843840D03*
Y850533D03*
X80015Y860572D03*
X81065Y865592D03*
X69323Y857226D03*
X80015Y870611D03*
X69323Y880651D03*
Y887344D03*
Y894037D03*
X80015Y907423D03*
Y897383D03*
X81065Y902403D03*
X69323Y924155D03*
Y917462D03*
X81065Y939214D03*
X80015Y934194D03*
X69323Y930848D03*
X80015Y944234D03*
X69323Y954273D03*
Y960966D03*
Y967659D03*
Y974352D03*
Y981045D03*
Y987737D03*
Y994430D03*
Y1004470D03*
Y1034588D03*
Y1041281D03*
Y1047974D03*
Y1054667D03*
Y1071399D03*
Y1061360D03*
X80015Y1081438D03*
X81065Y1086458D03*
X69323Y1078092D03*
X80015Y1091478D03*
X69323Y1101517D03*
X80015Y1118249D03*
X69323Y1114903D03*
Y1108210D03*
X80015Y1128289D03*
X81065Y1123269D03*
X69323Y1145021D03*
Y1138328D03*
X80015Y1165100D03*
X81065Y1160080D03*
X80015Y1155060D03*
X69323Y1151714D03*
Y1175139D03*
Y1181832D03*
X80015Y1191871D03*
X69323Y1188525D03*
X81065Y1196891D03*
X80015Y1201911D03*
X69323Y1211950D03*
Y1218643D03*
X80015Y1238722D03*
Y1228682D03*
X81065Y1233702D03*
X69323Y1225336D03*
Y1248761D03*
Y1255454D03*
X76378Y1406622D03*
X74325Y1523303D03*
X68870Y1523147D03*
X71359Y1523186D03*
X81868Y1511285D03*
X81405Y1516835D03*
X81905Y1513835D03*
X81405Y1519835D03*
Y1522835D03*
X78808Y1522839D03*
X81905Y1508698D03*
X74440Y1526385D03*
X74462Y1529665D03*
X82696Y1529095D03*
X76806Y1593265D03*
X80400Y1602225D03*
X86139Y17045D03*
X95333D03*
X88148Y19541D03*
X95216Y25977D03*
X86260D03*
X93216Y23981D03*
X88260D03*
X86139Y22037D03*
X95333D03*
X93365Y19541D03*
X94284Y37106D03*
X87198D03*
Y48720D03*
X94284D03*
X87347Y71839D03*
Y66847D03*
X91457Y75340D03*
X93367Y72847D03*
Y77839D03*
X89150Y154494D03*
X93717Y159053D03*
X87654Y376026D03*
X87520Y386502D03*
X85465Y773564D03*
Y780257D03*
Y803682D03*
X94624Y795316D03*
X85465Y810375D03*
Y817068D03*
X94624Y832127D03*
X85465Y840493D03*
Y847186D03*
Y853879D03*
Y877304D03*
X94624Y868938D03*
X85465Y890690D03*
Y883997D03*
X94624Y905750D03*
X85465Y920808D03*
Y914115D03*
Y927501D03*
Y950926D03*
X94624Y942561D03*
X85465Y957619D03*
Y971005D03*
Y964312D03*
Y984391D03*
Y977698D03*
Y991084D03*
Y997777D03*
Y1004470D03*
Y1044627D03*
Y1031241D03*
Y1037934D03*
Y1051320D03*
Y1058013D03*
Y1068052D03*
Y1074745D03*
X94624Y1089805D03*
X85465Y1098171D03*
Y1104863D03*
Y1111556D03*
X94624Y1126616D03*
X85465Y1134982D03*
Y1148367D03*
Y1141675D03*
X94624Y1163427D03*
X85465Y1178486D03*
Y1171793D03*
Y1185178D03*
Y1208604D03*
X94624Y1200238D03*
X85465Y1215297D03*
Y1221989D03*
X94624Y1237049D03*
X85465Y1252108D03*
Y1245415D03*
X90501Y1338952D03*
X92791Y1341302D03*
X96191Y1337721D03*
X92941Y1346172D03*
X91000Y1350300D03*
X88500D03*
X84000Y1408000D03*
Y1412500D03*
Y1417000D03*
X97530Y1410247D03*
X93000Y1430500D03*
X84000Y1421500D03*
Y1426000D03*
X93000Y1435500D03*
Y1440000D03*
X84500D03*
X95624Y1523287D03*
X85368Y1511285D03*
X85405Y1513835D03*
X88868Y1511285D03*
X88905Y1513835D03*
X93024Y1523287D03*
X85405Y1508698D03*
X88905D03*
X97498Y1533150D03*
X95624Y1526394D03*
X95018Y1533150D03*
X88696Y1526769D03*
X93024Y1526394D03*
X88696Y1523769D03*
X97498Y1538750D03*
X95018D03*
X93029Y1705225D03*
X97683Y1722477D03*
X97928Y3001D03*
X100313Y17045D03*
X109506D03*
X109389Y25977D03*
X100433D03*
X107389Y23981D03*
X102433D03*
X100313Y22037D03*
X102321Y19541D03*
X109506Y22037D03*
X107538Y19541D03*
X108458Y37106D03*
X101371D03*
Y48720D03*
X108458D03*
X98347Y72847D03*
X104367Y71839D03*
X109347D03*
X102457Y69340D03*
X104367Y66847D03*
X109347D03*
X98347Y77839D03*
X104829Y151191D03*
X107931Y158767D03*
X99754Y155807D03*
X110616Y756766D03*
X103574D03*
Y760266D03*
X99024Y776911D03*
X110616Y763766D03*
X103574Y767266D03*
X99024Y783604D03*
X109716Y786950D03*
X110766Y791970D03*
X99024Y807029D03*
X109716Y796989D03*
X99024Y813722D03*
Y820415D03*
X109716Y823761D03*
Y833800D03*
X110766Y828781D03*
X99024Y843840D03*
Y850533D03*
Y857226D03*
X109716Y860572D03*
X110766Y865592D03*
X99024Y880651D03*
X109716Y870611D03*
X99024Y887344D03*
Y894037D03*
X109716Y897383D03*
X110766Y902403D03*
X109716Y907423D03*
X99024Y924155D03*
Y917462D03*
Y930848D03*
X110766Y939214D03*
X109716Y934194D03*
X99024Y954273D03*
X109716Y944234D03*
X99024Y960966D03*
Y967659D03*
Y974352D03*
Y981045D03*
Y987737D03*
Y994430D03*
Y1004470D03*
Y1034588D03*
Y1041281D03*
Y1047974D03*
Y1054667D03*
Y1071399D03*
Y1061360D03*
Y1078092D03*
X109716Y1081438D03*
X110766Y1086458D03*
X99024Y1101517D03*
X109716Y1091478D03*
X99024Y1114903D03*
Y1108210D03*
X109716Y1118249D03*
Y1128289D03*
X110766Y1123269D03*
X99024Y1145021D03*
Y1138328D03*
Y1151714D03*
X109716Y1165100D03*
X110766Y1160080D03*
X109716Y1155060D03*
X99024Y1175139D03*
Y1181832D03*
Y1188525D03*
X109716Y1191871D03*
X110766Y1196891D03*
X109716Y1201911D03*
X99024Y1211950D03*
Y1218643D03*
Y1225336D03*
X109716Y1228682D03*
Y1238722D03*
X110766Y1233702D03*
X99024Y1248761D03*
Y1255454D03*
X99211Y1337771D03*
X112677Y1357409D03*
X110077D03*
X107477D03*
X104877D03*
X111581Y1372872D03*
X106721Y1367272D03*
Y1372872D03*
X109151D03*
X112677Y1363473D03*
X110077D03*
X112677Y1360516D03*
X110077D03*
X107477D03*
X104877D03*
X100347Y1361417D03*
X109151Y1367272D03*
X111581D03*
X111630Y1385287D03*
X101995Y1388247D03*
X98492Y1523287D03*
X100922D03*
X109635Y1523158D03*
X106713Y1523098D03*
X103513D03*
X99978Y1533150D03*
X98492Y1526394D03*
X98424Y1529501D03*
X100922Y1526394D03*
X101024Y1529501D03*
X108861Y1528840D03*
Y1526410D03*
X101396Y1552769D03*
X99978Y1538750D03*
X106448Y1696436D03*
X119928Y3001D03*
X114486Y17045D03*
X123683D03*
X123563Y25977D03*
X114607D03*
X116607Y23981D03*
X121563D03*
X114486Y22037D03*
X116494Y19541D03*
X121712D03*
X123683Y22037D03*
X122631Y37106D03*
X115544D03*
Y48720D03*
X122631D03*
X113457Y75340D03*
X115367Y72847D03*
X120347D03*
X126367Y71842D03*
X124457Y69343D03*
X126367Y66850D03*
X115367Y77839D03*
X120347D03*
X115166Y773564D03*
Y780257D03*
X124324Y795316D03*
X115166Y803682D03*
Y810375D03*
Y817068D03*
X124324Y832127D03*
X115166Y840493D03*
Y847186D03*
Y853879D03*
Y877304D03*
X124324Y868938D03*
X115166Y890690D03*
Y883997D03*
X124324Y905750D03*
X115166Y920808D03*
Y914115D03*
Y927501D03*
Y950926D03*
X124324Y942561D03*
X115166Y957619D03*
Y971005D03*
Y964312D03*
Y984391D03*
Y977698D03*
Y991084D03*
Y997777D03*
Y1004470D03*
Y1031241D03*
Y1037934D03*
Y1044627D03*
Y1051320D03*
Y1058013D03*
Y1068052D03*
Y1074745D03*
X124324Y1089805D03*
X115166Y1098171D03*
Y1104863D03*
Y1111556D03*
X124324Y1126616D03*
X115166Y1134982D03*
Y1148367D03*
Y1141675D03*
X124324Y1163427D03*
X115166Y1178486D03*
Y1171793D03*
Y1185178D03*
Y1208604D03*
X124324Y1200238D03*
X115166Y1215297D03*
Y1221989D03*
X124324Y1237049D03*
X115166Y1252108D03*
Y1245415D03*
X124071Y1337843D03*
X126671D03*
X115277Y1357409D03*
X126491Y1354871D03*
X125241Y1357371D03*
X126491Y1352271D03*
X123891Y1354871D03*
Y1352271D03*
X120221Y1357425D03*
X126491Y1349671D03*
X123891D03*
X117777Y1357409D03*
X121207Y1360686D03*
X114405Y1509335D03*
Y1516335D03*
Y1512835D03*
Y1519835D03*
Y1522835D03*
X116905D03*
Y1519835D03*
Y1512835D03*
Y1516335D03*
Y1509335D03*
Y1526335D03*
X120052Y1712450D03*
X141928Y3001D03*
X128663Y17045D03*
X130668Y19541D03*
X128663Y22037D03*
X129718Y37106D03*
Y48720D03*
X135457Y75340D03*
X137367Y72847D03*
X142347D03*
X131347Y71842D03*
Y66850D03*
X137367Y77839D03*
X142347D03*
X128367Y202241D03*
Y207241D03*
Y197241D03*
Y212241D03*
X139440Y439000D03*
X138090Y441900D03*
X140800Y441920D03*
X134812Y530955D03*
X131861Y664958D03*
X139869Y686582D03*
X140316Y756766D03*
X133124D03*
Y760266D03*
X128724Y776911D03*
X140316Y763766D03*
X133124Y767266D03*
X139416Y786950D03*
X128724Y783604D03*
X140466Y791970D03*
X128724Y807029D03*
X139416Y796989D03*
X128724Y813722D03*
Y820415D03*
X139416Y823761D03*
Y833800D03*
X140466Y828781D03*
X128724Y843840D03*
Y850533D03*
Y857226D03*
X139416Y860572D03*
X140466Y865592D03*
X128724Y880651D03*
X139416Y870611D03*
X128724Y887344D03*
Y894037D03*
X139416Y897383D03*
X140466Y902403D03*
X139416Y907423D03*
X128724Y924155D03*
Y917462D03*
X140466Y939214D03*
X139416Y934194D03*
X128724Y930848D03*
Y954273D03*
X139416Y944234D03*
X128724Y960966D03*
Y967659D03*
Y974352D03*
Y981045D03*
Y987737D03*
Y994430D03*
Y1004470D03*
Y1034588D03*
Y1041281D03*
Y1047974D03*
Y1054667D03*
Y1071399D03*
Y1061360D03*
X139416Y1081438D03*
X140466Y1086458D03*
X128724Y1078092D03*
Y1101517D03*
X139416Y1091478D03*
X128724Y1114903D03*
X139416Y1118249D03*
X128724Y1108210D03*
X139416Y1128289D03*
X140466Y1123269D03*
X128724Y1145021D03*
Y1138328D03*
X139416Y1165100D03*
X140466Y1160080D03*
X139416Y1155060D03*
X128724Y1151714D03*
Y1175139D03*
Y1181832D03*
X139416Y1191871D03*
X128724Y1188525D03*
X140466Y1196891D03*
X139416Y1201911D03*
X128724Y1211950D03*
Y1218643D03*
Y1225336D03*
X139416Y1228682D03*
X140466Y1233702D03*
X139416Y1238722D03*
X128724Y1248761D03*
Y1255454D03*
X137551Y1337771D03*
X131791Y1337811D03*
X140077Y1357409D03*
X137477D03*
X139321Y1367272D03*
Y1372872D03*
X141751D03*
X140077Y1360516D03*
X137477D03*
X132947Y1361417D03*
X141751Y1367272D03*
X130492Y1384789D03*
X132150Y1386740D03*
X132643Y1711846D03*
X150473Y25977D03*
X157429Y23981D03*
X152473D03*
X151410Y37106D03*
Y48720D03*
X153347Y71842D03*
X148367D03*
X153347Y66850D03*
X148367D03*
X146453Y69343D03*
X150318Y233536D03*
X142660Y438930D03*
X143720Y441960D03*
X145960Y438800D03*
X146930Y441870D03*
X149210Y438640D03*
X149830Y441920D03*
X149672Y665500D03*
X152705Y683218D03*
X144866Y773564D03*
Y780257D03*
X154025Y795316D03*
X144866Y803682D03*
Y810375D03*
Y817068D03*
X154025Y832127D03*
X144866Y840493D03*
Y847186D03*
Y853879D03*
Y877304D03*
X154025Y868938D03*
X144866Y890690D03*
Y883997D03*
X154025Y905750D03*
X144866Y920808D03*
Y914115D03*
Y927501D03*
X154025Y942561D03*
X144866Y950926D03*
Y957619D03*
Y971005D03*
Y964312D03*
Y984391D03*
Y977698D03*
Y991084D03*
Y997777D03*
Y1004470D03*
Y1031241D03*
Y1037934D03*
Y1044627D03*
Y1051320D03*
Y1058013D03*
Y1068052D03*
Y1074745D03*
X154025Y1089805D03*
X144866Y1098171D03*
Y1104863D03*
Y1111556D03*
X154025Y1126616D03*
X144866Y1134982D03*
Y1148367D03*
Y1141675D03*
X154025Y1163427D03*
X144866Y1178486D03*
Y1171793D03*
Y1185178D03*
Y1208604D03*
X154025Y1200238D03*
X144866Y1215297D03*
Y1221989D03*
X154025Y1237049D03*
X144866Y1252108D03*
Y1245415D03*
X156491Y1354871D03*
Y1352271D03*
X152821Y1357425D03*
X156491Y1349671D03*
X145277Y1357409D03*
X147877D03*
X142677D03*
X150377D03*
X144181Y1367272D03*
X153767Y1360456D03*
Y1363413D03*
X144181Y1372872D03*
X142677Y1360516D03*
X145277Y1363473D03*
X142677D03*
X145277Y1360516D03*
X144230Y1385287D03*
X150900Y1433500D03*
Y1429500D03*
X143478Y1440000D03*
X151082Y1436653D03*
X146978Y1440000D03*
X147277Y1712791D03*
X152815Y1705500D03*
X155740Y1729726D03*
X163928Y3001D03*
X164525Y17045D03*
X159545D03*
X159429Y25977D03*
X164646D03*
X171602Y23981D03*
X166646D03*
X157578Y19541D03*
X166534D03*
X171751D03*
X164525Y22037D03*
X159545D03*
X158497Y37106D03*
X165584D03*
X158497Y48720D03*
X165584D03*
X158661Y75340D03*
X160571Y72847D03*
X165551D03*
X171571Y71839D03*
X169661Y69340D03*
X171571Y66847D03*
X160571Y77839D03*
X165551D03*
X172120Y416600D03*
X168950Y412950D03*
X168910Y415930D03*
X170500Y441420D03*
X167580Y441380D03*
X164870Y441360D03*
X169440Y438390D03*
X166220Y438460D03*
X162975Y760266D03*
Y756766D03*
X170017D03*
X158425Y776911D03*
X170017Y763766D03*
X162975Y767266D03*
X158425Y783604D03*
X169117Y786950D03*
X170167Y791970D03*
X158425Y807029D03*
X169117Y796989D03*
X158425Y813722D03*
Y820415D03*
X169117Y823761D03*
Y833800D03*
X170167Y828781D03*
X158425Y843840D03*
Y850533D03*
Y857226D03*
X169117Y860572D03*
X170167Y865592D03*
X158425Y880651D03*
X169117Y870611D03*
X158425Y887344D03*
Y894037D03*
X169117Y897383D03*
X170167Y902403D03*
X169117Y907423D03*
X158425Y924155D03*
Y917462D03*
Y930848D03*
X170167Y939214D03*
X169117Y934194D03*
X158425Y954273D03*
X169117Y944234D03*
X158425Y960966D03*
Y967659D03*
Y974352D03*
Y981045D03*
Y987737D03*
Y994430D03*
Y1004470D03*
Y1034588D03*
Y1041281D03*
Y1047974D03*
Y1054667D03*
Y1071399D03*
Y1061360D03*
Y1078092D03*
X169117Y1081438D03*
X170167Y1086458D03*
X158425Y1101517D03*
X169117Y1091478D03*
X158425Y1114903D03*
Y1108210D03*
X169117Y1118249D03*
Y1128289D03*
X170167Y1123269D03*
X158425Y1145021D03*
Y1138328D03*
X169117Y1165100D03*
X170167Y1160080D03*
X169117Y1155060D03*
X158425Y1151714D03*
Y1175139D03*
Y1181832D03*
Y1188525D03*
X169117Y1191871D03*
X170167Y1196891D03*
X169117Y1201911D03*
X158425Y1211950D03*
Y1218643D03*
Y1225336D03*
X169117Y1238722D03*
Y1228682D03*
X170167Y1233702D03*
X158425Y1248761D03*
Y1255454D03*
X171481Y1337853D03*
X164481Y1337813D03*
X161881D03*
X170177Y1357409D03*
X159091Y1354871D03*
X157841Y1357371D03*
X159091Y1352271D03*
Y1349671D03*
X172021Y1367272D03*
Y1372872D03*
X170177Y1360516D03*
X165647Y1361417D03*
X163192Y1384789D03*
X164850Y1386740D03*
X168661Y1459995D03*
X166751Y1462595D03*
X168661Y1465195D03*
X164650Y1529350D03*
Y1540250D03*
X171925Y1708428D03*
X167500Y1712864D03*
X171925Y1727581D03*
X157860Y1718500D03*
X185928Y3001D03*
X173719Y17045D03*
X178699D03*
X173602Y25977D03*
X173719Y22037D03*
X178699D03*
X180707Y19541D03*
X172670Y37106D03*
X179757D03*
X172670Y48720D03*
X179757D03*
X176551Y71839D03*
Y66847D03*
X180657Y75343D03*
X182571Y72850D03*
Y77842D03*
X182548Y147260D03*
X176610Y441380D03*
X175990Y438100D03*
X173710Y441330D03*
X172740Y438260D03*
X173299Y664958D03*
X172802Y682036D03*
X174567Y773564D03*
Y780257D03*
Y803682D03*
X183726Y795316D03*
X174567Y810375D03*
Y817068D03*
X183726Y832127D03*
X174567Y840493D03*
Y847186D03*
Y853879D03*
Y877304D03*
X183726Y868938D03*
X174567Y890690D03*
Y883997D03*
X183726Y905750D03*
X174567Y920808D03*
Y914115D03*
Y927501D03*
Y950926D03*
X183726Y942561D03*
X174567Y957619D03*
Y971005D03*
Y964312D03*
Y984391D03*
Y977698D03*
Y991084D03*
Y997777D03*
Y1004470D03*
Y1031241D03*
Y1037934D03*
Y1044627D03*
Y1051320D03*
Y1058013D03*
Y1068052D03*
Y1074745D03*
X183726Y1089805D03*
X174567Y1098171D03*
Y1104863D03*
Y1111556D03*
Y1134982D03*
X183726Y1126616D03*
X174567Y1148367D03*
Y1141675D03*
X183726Y1163427D03*
X174567Y1178486D03*
Y1171793D03*
Y1185178D03*
Y1208604D03*
X183726Y1200238D03*
X174567Y1215297D03*
Y1221989D03*
X183726Y1237049D03*
X174567Y1252108D03*
Y1245415D03*
X185701Y1337853D03*
X183101D03*
X174081D03*
X172777Y1357409D03*
X183077D03*
X185521Y1357425D03*
X175377Y1357409D03*
X177977D03*
X180577D03*
X176881Y1367272D03*
X174451D03*
X186467Y1360456D03*
Y1363413D03*
X172777Y1360516D03*
X176881Y1372872D03*
X174451D03*
X177977Y1363473D03*
X175377D03*
Y1360516D03*
X177977D03*
X176930Y1385287D03*
X173441Y1459995D03*
X173451Y1452895D03*
X180141Y1450295D03*
X175361D03*
X180141Y1455495D03*
X175361D03*
X173441Y1465195D03*
X186851Y1472295D03*
X177322Y1498320D03*
X173980Y1528731D03*
X185254Y1686870D03*
X179444Y1708810D03*
X184340Y1718000D03*
X194607Y25977D03*
X196607Y23981D03*
X201563D03*
X201712Y19541D03*
X195544Y37106D03*
Y48720D03*
X193571Y71839D03*
X198551D03*
X191661Y69340D03*
X193571Y66847D03*
X198551D03*
X187656Y72850D03*
Y77842D03*
X195979Y109462D03*
X203061Y131158D03*
X195690Y415390D03*
X195730Y412410D03*
X200405Y622385D03*
Y632385D03*
X192676Y760266D03*
Y756766D03*
X199718D03*
X192676Y767266D03*
X199718Y763766D03*
X188126Y776911D03*
X199868Y791970D03*
X198818Y786950D03*
X188126Y783604D03*
X198818Y796989D03*
X188126Y807029D03*
Y813722D03*
Y820415D03*
X199868Y828781D03*
X198818Y823761D03*
Y833800D03*
X188126Y843840D03*
Y850533D03*
X199868Y865592D03*
X198818Y860572D03*
X188126Y857226D03*
X198818Y870611D03*
X188126Y880651D03*
Y887344D03*
Y894037D03*
X199868Y902403D03*
X198818Y897383D03*
Y907423D03*
X188126Y917462D03*
Y924155D03*
X199868Y939214D03*
X198818Y934194D03*
X188126Y930848D03*
X198818Y944234D03*
X188126Y954273D03*
Y960966D03*
Y967659D03*
Y974352D03*
Y981045D03*
Y987737D03*
Y994430D03*
Y1004470D03*
Y1034588D03*
Y1041281D03*
Y1047974D03*
Y1054667D03*
Y1061360D03*
Y1071399D03*
X199868Y1086458D03*
X198818Y1081438D03*
X188126Y1078092D03*
X198818Y1091478D03*
X188126Y1101517D03*
X198818Y1118249D03*
X188126Y1108210D03*
Y1114903D03*
X199868Y1123269D03*
X198818Y1128289D03*
X188126Y1138328D03*
Y1145021D03*
X199868Y1160080D03*
X198818Y1155060D03*
Y1165100D03*
X188126Y1151714D03*
Y1175139D03*
X198818Y1191871D03*
X188126Y1181832D03*
Y1188525D03*
X199868Y1196891D03*
X198818Y1201911D03*
X188126Y1211950D03*
Y1218643D03*
X199868Y1233702D03*
X198818Y1228682D03*
Y1238722D03*
X188126Y1225336D03*
Y1248761D03*
Y1255454D03*
X195771Y1337903D03*
X193171D03*
X190541Y1357371D03*
X189191Y1354871D03*
Y1352271D03*
X191791Y1354871D03*
Y1352271D03*
X189191Y1349671D03*
X191791D03*
X198547Y1361417D03*
X196092Y1384789D03*
X197750Y1386740D03*
X193551Y1462595D03*
X200241Y1459995D03*
X195461D03*
X202161Y1450295D03*
X200251Y1452895D03*
X202161Y1455495D03*
X193541Y1469695D03*
X188761D03*
X193541Y1474895D03*
X188761D03*
X200241Y1465195D03*
X195461D03*
X197703Y1550897D03*
X192978Y1550797D03*
X188254D03*
X187388Y1594876D03*
X192344D03*
X199448D03*
X187388Y1589884D03*
X199448D03*
X192344D03*
X193418Y1604876D03*
Y1599884D03*
X198374D03*
Y1604876D03*
Y1611796D03*
X193418D03*
X198374Y1616788D03*
X193418D03*
X192344Y1626788D03*
X199448D03*
X192344Y1621796D03*
X199448D03*
X187388D03*
Y1626788D03*
X200848Y1655656D03*
X190242Y1656635D03*
X201120Y1668603D03*
X199040Y1666925D03*
X196366Y1664821D03*
X190271Y1671753D03*
X195153Y1679774D03*
X190391Y1701988D03*
X195300Y1694898D03*
X194000Y1712362D03*
X201531Y1715000D03*
X192745Y1707106D03*
X199547Y1704605D03*
X195150Y1723000D03*
X207928Y3001D03*
X208659Y17045D03*
X203679D03*
X208780Y25977D03*
X203563D03*
X210780Y23981D03*
X215736D03*
X210668Y19541D03*
X215885D03*
X208659Y22037D03*
X203679D03*
X202631Y37106D03*
X216804D03*
X209718D03*
X202631Y48720D03*
X209718D03*
X216804D03*
X202795Y75340D03*
X204705Y72847D03*
X209685D03*
X213791Y69343D03*
X215705Y66850D03*
Y71842D03*
X204705Y77839D03*
X209685D03*
X214107Y113022D03*
X205489Y142790D03*
X206760Y148760D03*
X206805Y622385D03*
X203605D03*
X206805Y632385D03*
X203605D03*
X204268Y773564D03*
Y780257D03*
X213427Y795316D03*
X204268Y803682D03*
Y810375D03*
Y817068D03*
X213427Y832127D03*
X204268Y840493D03*
Y847186D03*
Y853879D03*
X213427Y868938D03*
X204268Y877304D03*
Y883997D03*
Y890690D03*
X213427Y905750D03*
X204268Y914115D03*
Y920808D03*
Y927501D03*
X213427Y942561D03*
X204268Y950926D03*
Y957619D03*
Y964312D03*
Y971005D03*
Y977698D03*
Y984391D03*
Y991084D03*
Y997777D03*
Y1004470D03*
Y1031241D03*
Y1037934D03*
Y1044627D03*
Y1051320D03*
Y1058013D03*
Y1068052D03*
Y1074745D03*
X213427Y1089805D03*
X204268Y1098171D03*
Y1104863D03*
Y1111556D03*
X213427Y1126616D03*
X204268Y1134982D03*
Y1141675D03*
Y1148367D03*
X213427Y1163427D03*
X204268Y1171793D03*
Y1178486D03*
Y1185178D03*
X213427Y1200238D03*
X204268Y1208604D03*
Y1215297D03*
Y1221989D03*
X213427Y1237049D03*
X204268Y1245415D03*
Y1252108D03*
X215977Y1357409D03*
X210877D03*
X208277D03*
X213477D03*
X205677D03*
X203077D03*
X207351Y1367272D03*
X209781Y1372872D03*
X204921Y1367272D03*
Y1372872D03*
X207351D03*
X210877Y1363473D03*
X208277D03*
Y1360516D03*
X210877D03*
X205677D03*
X203077D03*
X209781Y1367272D03*
X209830Y1385287D03*
X213648Y1416262D03*
X206941Y1450295D03*
Y1455495D03*
X213651Y1472295D03*
X215561Y1469695D03*
Y1474895D03*
X216601Y1550697D03*
X202427D03*
X211876Y1550897D03*
X207152D03*
X211508Y1594876D03*
X204404D03*
X216464D03*
X211508Y1589884D03*
X204404D03*
X216464D03*
X210434Y1604876D03*
X205478D03*
X210434Y1599884D03*
X205478D03*
Y1611796D03*
X210434D03*
Y1616788D03*
X205478D03*
X211508Y1626788D03*
X216464D03*
X211508Y1621796D03*
X216464D03*
X204404Y1626788D03*
Y1621796D03*
X203807Y1681173D03*
Y1696366D03*
X211103Y1708988D03*
X229928Y3001D03*
X217853Y17045D03*
X222833D03*
X217736Y25977D03*
X217853Y22037D03*
X222833D03*
X224841Y19541D03*
X223891Y37106D03*
X230977D03*
X223891Y48720D03*
X230977D03*
X224795Y75340D03*
X226705Y72847D03*
X231685D03*
X220685Y66850D03*
Y71842D03*
X231685Y77839D03*
X226705D03*
X233653Y162074D03*
X222000Y160000D03*
X220687Y522453D03*
X226687D03*
X233493Y676906D03*
X227493D03*
X224493D03*
X230493D03*
X221493D03*
X222377Y760266D03*
Y756766D03*
X229419D03*
X222377Y767266D03*
X229419Y763119D03*
X217827Y776911D03*
X229569Y791970D03*
X228519Y786950D03*
X217827Y783604D03*
X228519Y796989D03*
X217827Y807029D03*
Y813722D03*
Y820415D03*
X229569Y828781D03*
X228519Y823761D03*
Y833800D03*
X217827Y843840D03*
Y850533D03*
X229569Y865592D03*
X228519Y860572D03*
X217827Y857226D03*
X228519Y870611D03*
X217827Y880651D03*
Y887344D03*
Y894037D03*
X229569Y902403D03*
X228519Y897383D03*
Y907423D03*
X217827Y917462D03*
Y924155D03*
X229569Y939214D03*
X228519Y934194D03*
X217827Y930848D03*
X228519Y944234D03*
X217827Y954273D03*
Y960966D03*
Y967659D03*
Y974352D03*
Y981045D03*
Y987737D03*
Y994430D03*
Y1004470D03*
Y1034588D03*
Y1041281D03*
Y1047974D03*
Y1054667D03*
Y1061360D03*
Y1071399D03*
X229569Y1086458D03*
X228519Y1081438D03*
X217827Y1078092D03*
Y1101517D03*
X228519Y1091478D03*
Y1118249D03*
X217827Y1108210D03*
Y1114903D03*
X229569Y1123269D03*
X228519Y1128289D03*
X217827Y1138328D03*
Y1145021D03*
X229569Y1160080D03*
X228519Y1155060D03*
Y1165100D03*
X217827Y1151714D03*
Y1175139D03*
X228519Y1191871D03*
X217827Y1181832D03*
Y1188525D03*
X229569Y1196891D03*
X228519Y1201911D03*
X217827Y1211950D03*
Y1218643D03*
X229569Y1233702D03*
X228519Y1228682D03*
Y1238722D03*
X217827Y1225336D03*
Y1248761D03*
Y1255454D03*
X224481Y1326418D03*
X221881D03*
X224481Y1323918D03*
X221881Y1321418D03*
X224481D03*
X221881Y1323918D03*
X230171Y1323904D03*
Y1321404D03*
X227871Y1338124D03*
X223941Y1338068D03*
X221341D03*
X230661Y1338124D03*
X224691Y1354871D03*
Y1352271D03*
X223441Y1357371D03*
X222091Y1354871D03*
Y1352271D03*
X218421Y1357425D03*
X224691Y1349671D03*
X222091D03*
X219367Y1360456D03*
Y1363413D03*
X231347Y1361417D03*
X228892Y1384789D03*
X230550Y1386740D03*
X228693Y1408885D03*
X224881Y1410685D03*
X220803Y1412115D03*
X217097Y1413863D03*
X227051Y1452895D03*
X220351Y1462595D03*
X228961Y1450295D03*
Y1455495D03*
X227041Y1459995D03*
X222261D03*
X220341Y1469695D03*
Y1474895D03*
X227041Y1465195D03*
X222261D03*
X226050Y1550897D03*
X221325Y1550797D03*
X230774Y1550897D03*
X228524Y1594876D03*
X223568D03*
Y1589884D03*
X228524D03*
X222494Y1604876D03*
X217538D03*
X222494Y1599884D03*
X217538D03*
X229598Y1604876D03*
Y1599884D03*
Y1611796D03*
X217538D03*
X222494D03*
X229598Y1616788D03*
X217538D03*
X222494D03*
X223568Y1626788D03*
X228524D03*
X223568Y1621796D03*
X228524D03*
X243486Y23005D03*
X244296Y59765D03*
X242251Y162515D03*
X246250Y204360D03*
X233438Y593556D03*
X236638D03*
X233456Y601598D03*
X236656D03*
X236674Y609640D03*
X233474D03*
X233969Y773564D03*
Y780257D03*
Y803682D03*
Y810375D03*
Y817068D03*
Y840493D03*
Y847186D03*
Y853879D03*
Y877304D03*
Y883997D03*
Y890690D03*
Y914115D03*
Y920808D03*
Y927501D03*
Y950926D03*
Y957619D03*
Y964312D03*
Y971005D03*
Y977698D03*
Y984391D03*
Y991084D03*
Y997777D03*
Y1004470D03*
Y1031241D03*
Y1037934D03*
Y1044627D03*
Y1051320D03*
Y1058013D03*
Y1068052D03*
Y1074745D03*
Y1098171D03*
Y1104863D03*
Y1111556D03*
Y1134982D03*
Y1141675D03*
Y1148367D03*
Y1171793D03*
Y1178486D03*
Y1185178D03*
Y1208604D03*
Y1215297D03*
Y1221989D03*
Y1245415D03*
Y1252108D03*
X232961Y1323904D03*
Y1321404D03*
X239561Y1338124D03*
X243677Y1357409D03*
X241077D03*
X238477D03*
X235877D03*
X246277D03*
X242581Y1367272D03*
X240151D03*
X243677Y1363473D03*
X241077D03*
Y1360516D03*
X243677D03*
X242581Y1372872D03*
X240151D03*
X237721D03*
Y1367272D03*
X238477Y1360516D03*
X235877D03*
X242630Y1385287D03*
X233194Y1407349D03*
X233741Y1450295D03*
Y1455495D03*
X240451Y1472295D03*
X242361Y1469695D03*
Y1474895D03*
X235499Y1550897D03*
X240223D03*
X244947Y1550697D03*
X240584Y1594876D03*
X235628D03*
Y1589884D03*
X240584D03*
X246614Y1604876D03*
Y1599884D03*
X234554Y1604876D03*
Y1599884D03*
X241658Y1604876D03*
Y1599884D03*
X246614Y1611796D03*
X241658D03*
X234554D03*
X246614Y1616788D03*
X241658D03*
X234554D03*
X235628Y1626788D03*
X240584D03*
X235628Y1621796D03*
X240584D03*
X251928Y3001D03*
X247716Y75865D03*
Y71865D03*
X251793Y100846D03*
X261383Y133786D03*
X258253D03*
X249735Y152694D03*
X254095Y209235D03*
X254671Y642138D03*
X258470Y775410D03*
X260671Y1338124D03*
X258071D03*
X247725Y1338141D03*
X257491Y1352271D03*
X256241Y1357371D03*
X257491Y1354871D03*
X254891Y1352271D03*
Y1354871D03*
X251221Y1357425D03*
X248777Y1357409D03*
X257491Y1349671D03*
X254891D03*
X252167Y1363413D03*
Y1360456D03*
X253851Y1452895D03*
X247151Y1462595D03*
X260541Y1450295D03*
X255761D03*
X260541Y1455495D03*
X255761D03*
X253841Y1459995D03*
X249061D03*
X253841Y1465195D03*
X249061D03*
X247141Y1469695D03*
Y1474895D03*
X259120Y1550797D03*
X254396Y1550897D03*
X249671D03*
X259748Y1594876D03*
X247688D03*
X252644D03*
X247688Y1589884D03*
X259748D03*
X252644D03*
X253718Y1604876D03*
X258674D03*
X253718Y1599884D03*
X258674D03*
Y1611796D03*
X253718D03*
X258674Y1616788D03*
X253718D03*
X252644Y1626788D03*
X259748D03*
X252644Y1621796D03*
X259748D03*
X247688Y1626788D03*
Y1621796D03*
X273928Y3001D03*
X272596Y27185D03*
X263276Y34625D03*
X271596Y40165D03*
X270364Y118415D03*
X272361Y120243D03*
X264574Y159206D03*
Y155206D03*
X267500Y220441D03*
X265100Y595078D03*
X270905Y608485D03*
X273905D03*
Y611485D03*
X272603Y692910D03*
Y695510D03*
X271491Y1291740D03*
X274091D03*
X272077Y1314370D03*
X269477D03*
X274677D03*
X272077Y1311263D03*
X269477D03*
X274677D03*
X271321Y1326726D03*
Y1321126D03*
X276181Y1326726D03*
X273751D03*
X274677Y1317327D03*
X264947Y1315271D03*
X276181Y1321126D03*
X273751D03*
X276230Y1339141D03*
X264085Y1339175D03*
X267251Y1452895D03*
X273941Y1450295D03*
X269161D03*
X273941Y1455495D03*
X269161D03*
X276637Y1523953D03*
X270139Y1548563D03*
X271808Y1594876D03*
X264704D03*
X271808Y1589884D03*
X264704D03*
X265778Y1604876D03*
X270734D03*
X265778Y1599790D03*
X270734D03*
Y1611796D03*
X265778D03*
X270734Y1616788D03*
X265778D03*
X271808Y1626788D03*
Y1621796D03*
X264704Y1626788D03*
Y1621796D03*
X291000Y14820D03*
X285896Y23965D03*
X291156Y21395D03*
X286716Y40020D03*
X285499Y53191D03*
X278989Y48720D03*
X286076D03*
X283949Y152506D03*
X288516Y157065D03*
X285260Y234000D03*
X279500Y234075D03*
X290865Y609470D03*
X277105Y608485D03*
X280305D03*
X277105Y611485D03*
X280305D03*
X286665Y609470D03*
X283705Y608485D03*
X284705Y605485D03*
X283705Y611485D03*
X287832Y674150D03*
X283921Y1291740D03*
X281321D03*
X284821Y1311279D03*
X282377Y1311263D03*
X279877D03*
X277277Y1314370D03*
Y1311263D03*
X288491Y1306125D03*
Y1308725D03*
X291091Y1306125D03*
Y1308725D03*
X288491Y1303525D03*
X291091D03*
X289841Y1311225D03*
X285767Y1314310D03*
Y1317267D03*
X277277Y1317327D03*
X283946Y1530595D03*
X286446D03*
X288824Y1594876D03*
X276764D03*
X283868D03*
Y1589884D03*
X276764D03*
X288824D03*
X277838Y1604876D03*
X282794D03*
X277838Y1599884D03*
X282794D03*
X289898Y1604876D03*
Y1599884D03*
Y1611796D03*
X282794D03*
X277838D03*
X289898Y1616788D03*
X282794D03*
X277838D03*
X283868Y1626788D03*
X288824D03*
X283868Y1621796D03*
X288824D03*
X276764Y1626788D03*
Y1621796D03*
X295928Y3001D03*
X296272Y69128D03*
X293443Y78576D03*
X293448Y82486D03*
Y85986D03*
X303043Y79376D03*
X299943Y79276D03*
X299653Y92506D03*
X299628Y149203D03*
X299624Y158706D03*
X294553Y153819D03*
X293000Y216500D03*
X294165Y609570D03*
X297838Y609585D03*
X300965Y609570D03*
X304449D03*
X305121Y726348D03*
X298991D03*
X294541Y1291378D03*
X291941D03*
X302373Y1314342D03*
X304973D03*
X302373Y1311235D03*
X304973D03*
X304217Y1326698D03*
Y1321098D03*
X297843Y1315243D03*
X295388Y1338615D03*
X297046Y1340566D03*
X305199Y1398269D03*
Y1400769D03*
X295116Y1398132D03*
Y1400632D03*
X292516D03*
Y1398132D03*
X301513Y1452895D03*
X294813Y1462595D03*
X303423Y1450295D03*
Y1455495D03*
X301503Y1459995D03*
X296723D03*
X301503Y1465195D03*
X296723D03*
X299950Y1499500D03*
X301550Y1518040D03*
Y1514420D03*
Y1510800D03*
X302042Y1528731D03*
X300884Y1594876D03*
X295928D03*
Y1589884D03*
X300884D03*
X294854Y1604876D03*
Y1599884D03*
X301958Y1604876D03*
Y1599884D03*
Y1611796D03*
X294854D03*
X301958Y1616788D03*
X294854D03*
X295928Y1626788D03*
X300884D03*
X295928Y1621796D03*
X300884D03*
X317928Y3001D03*
X306716Y39985D03*
X320053Y85806D03*
Y88806D03*
X310425Y243925D03*
X317240Y252970D03*
X308925Y260075D03*
X307865Y609570D03*
X311349Y609632D03*
X313961Y607088D03*
Y604588D03*
X319657Y696415D03*
X319621Y1291740D03*
X321387Y1306097D03*
Y1308697D03*
Y1303497D03*
X317717Y1311251D03*
X315273Y1311235D03*
X312773D03*
X307573Y1314342D03*
Y1311235D03*
X310173Y1314342D03*
Y1311235D03*
X318663Y1314282D03*
X309077Y1321098D03*
X306647D03*
X318663Y1317239D03*
X309077Y1326698D03*
X306647D03*
X307573Y1317299D03*
X310173D03*
X309126Y1339113D03*
X307799Y1400769D03*
Y1398269D03*
X318199Y1400549D03*
X314199D03*
X310399D03*
X308203Y1450295D03*
Y1455495D03*
X314913Y1472295D03*
X316823Y1469695D03*
Y1474895D03*
X321040Y1550797D03*
X316316D03*
X320048Y1594876D03*
X307988D03*
X312944D03*
X307988Y1589884D03*
X320048D03*
X312944D03*
X306914Y1604876D03*
Y1599884D03*
X314018Y1604876D03*
X318974D03*
X314018Y1599884D03*
X318974D03*
Y1611796D03*
X314018D03*
X306914D03*
X318974Y1616788D03*
X314018D03*
X306914D03*
X320048Y1626788D03*
X312944D03*
X320048Y1621796D03*
X312944D03*
X307988Y1626788D03*
Y1621796D03*
X329535Y49379D03*
X331000Y270260D03*
X328966Y543012D03*
X334744Y566086D03*
X333500Y582500D03*
Y578500D03*
X333988Y590633D03*
X329471Y1291778D03*
X322221Y1291740D03*
X326761Y1291778D03*
X335277Y1314285D03*
Y1311178D03*
X323987Y1303497D03*
Y1306097D03*
Y1308697D03*
X322737Y1311197D03*
X330747Y1315186D03*
X328292Y1338558D03*
X329950Y1340509D03*
X333830Y1396299D03*
Y1398899D03*
Y1401499D03*
Y1393799D03*
X324309Y1396599D03*
Y1399199D03*
Y1401799D03*
Y1394099D03*
X321999Y1400549D03*
X321613Y1462595D03*
X323523Y1459995D03*
X328303D03*
X328313Y1452895D03*
X335003Y1450295D03*
X330223D03*
X335003Y1455495D03*
X330223D03*
X328313Y1472295D03*
X323523Y1465195D03*
X328303D03*
X321603Y1469695D03*
Y1474895D03*
X325765Y1550897D03*
X330489Y1550697D03*
X335214Y1550897D03*
X332108Y1594876D03*
X325004D03*
X332108Y1589884D03*
X325004D03*
X326078Y1604876D03*
X331034D03*
X326078Y1599884D03*
X331034D03*
Y1611796D03*
X326078D03*
X331034Y1616788D03*
X326078D03*
X332108Y1626788D03*
X325004D03*
X332108Y1621796D03*
X325004D03*
X343036Y122525D03*
X342075Y287925D03*
X351157Y562415D03*
X345500Y574415D03*
X351157D03*
X338664Y699660D03*
X337030Y697750D03*
X340477Y1314285D03*
X337877D03*
Y1311178D03*
X340477D03*
X350621Y1311194D03*
X348177Y1311178D03*
X343077Y1314285D03*
X345677Y1311178D03*
X343077D03*
X341981Y1321041D03*
X339551D03*
X341981Y1326641D03*
X337121Y1321041D03*
X339551Y1326641D03*
X337121D03*
X340477Y1317242D03*
X343077D03*
X342030Y1339056D03*
X347110Y1398312D03*
X351110D03*
X341760Y1401449D03*
X337760D03*
X349760D03*
X345760D03*
X348413Y1462595D03*
X350323Y1459995D03*
X341713Y1472295D03*
X350323Y1465195D03*
X348403Y1469695D03*
X343623D03*
X348403Y1474895D03*
X343623D03*
X339938Y1550897D03*
X349387Y1550797D03*
X344663Y1550697D03*
X349124Y1594876D03*
X337064D03*
X344168D03*
Y1589884D03*
X337064D03*
X349124D03*
X338138Y1604876D03*
X343094D03*
X338138Y1599884D03*
X343094D03*
X350198Y1604876D03*
Y1599884D03*
Y1611796D03*
X343094D03*
X338138D03*
X350198Y1616788D03*
X343094D03*
X338138D03*
X344168Y1626788D03*
X349124D03*
X344168Y1621796D03*
X349124D03*
X337064Y1626788D03*
Y1621796D03*
X351535Y49379D03*
X366874Y135157D03*
X366771Y127665D03*
X359734Y288768D03*
X360433Y294030D03*
X355832Y297855D03*
X353700Y547893D03*
X356850D03*
X365593Y621622D03*
X364788Y1193918D03*
X364457Y1188109D03*
X359541Y1291918D03*
X362311Y1291968D03*
X356551Y1291880D03*
X353951D03*
X356891Y1306040D03*
Y1308640D03*
Y1303440D03*
X354291Y1306040D03*
Y1308640D03*
Y1303440D03*
X355641Y1311140D03*
X351567Y1314225D03*
Y1317182D03*
X363547Y1315386D03*
X361092Y1338758D03*
X362750Y1340709D03*
X355110Y1398312D03*
X359110D03*
X363110D03*
X357760Y1401449D03*
X353760D03*
X355113Y1452895D03*
X361803Y1450295D03*
X357023D03*
X361803Y1455495D03*
X357023D03*
X355103Y1459995D03*
Y1465195D03*
X354112Y1550897D03*
X358836D03*
X363561D03*
X361184Y1594876D03*
X356228D03*
Y1589884D03*
X361184D03*
X355154Y1604876D03*
Y1599884D03*
X362258Y1604876D03*
Y1599790D03*
Y1611796D03*
X355154D03*
X362258Y1616788D03*
X355154D03*
X356228Y1626788D03*
X361184D03*
X356228Y1621796D03*
X361184D03*
X373535Y49379D03*
X375920Y146577D03*
X380012Y243615D03*
X379200Y298772D03*
X367902Y303760D03*
X380771Y524903D03*
X375943D03*
X371724Y699450D03*
X370090Y697482D03*
X372000Y816862D03*
Y826362D03*
Y828862D03*
Y837862D03*
Y840362D03*
Y849362D03*
X378083Y1184949D03*
X367782Y1199648D03*
X380977Y1311378D03*
X375877Y1314485D03*
X378477Y1311378D03*
X375877D03*
X370677Y1314485D03*
X368077D03*
X373277D03*
X368077Y1311378D03*
X370677D03*
X373277D03*
X375877Y1317442D03*
X372351Y1326841D03*
X369921D03*
Y1321241D03*
X374781Y1326841D03*
X373277Y1317442D03*
X374781Y1321241D03*
X372351D03*
X374830Y1339256D03*
X379610Y1391781D03*
X375056Y1393741D03*
X375213Y1462595D03*
X377123Y1459995D03*
X368513Y1472295D03*
X377123Y1465195D03*
X375203Y1469695D03*
X370423D03*
X375203Y1474895D03*
X370423D03*
X368285Y1550897D03*
X373009Y1550697D03*
X377733Y1550897D03*
X368288Y1594876D03*
X373244D03*
X368288Y1589884D03*
X373244D03*
X367214Y1604876D03*
Y1599790D03*
X374318Y1604876D03*
X379274D03*
X374318Y1599884D03*
X379274D03*
Y1611796D03*
X374318D03*
X367214D03*
X379274Y1616788D03*
X374318D03*
X367214D03*
X373244Y1626788D03*
Y1621796D03*
X368288Y1626788D03*
Y1621796D03*
X372313Y1641759D03*
X379895Y1670046D03*
X372350Y1683284D03*
X385024Y-17575D03*
X381771Y-17589D03*
X388049Y-18895D03*
X381756Y-20104D03*
X385009Y-20090D03*
X381725Y-14717D03*
X385008Y-9673D03*
X385023Y-7158D03*
X381755Y-9687D03*
X388048Y-8478D03*
X381770Y-7172D03*
X381740Y-12202D03*
X395535Y49379D03*
X391600Y121178D03*
X387712Y147441D03*
X384600Y221800D03*
X386563Y280370D03*
X387184Y470495D03*
X387440Y525154D03*
X395657Y546894D03*
X391657Y546816D03*
X387657Y546876D03*
X384500Y810862D03*
X384499Y819862D03*
X388361Y1293713D03*
X385701Y1291828D03*
X392176Y1309859D03*
X394951Y1311259D03*
X389691Y1306240D03*
Y1308840D03*
X387091Y1306240D03*
Y1308840D03*
X389691Y1303640D03*
X387091D03*
X383421Y1311394D03*
X388441Y1311340D03*
X384367Y1314425D03*
Y1317382D03*
X392950Y1315280D03*
X392910Y1317880D03*
X395267Y1358621D03*
X393321Y1385630D03*
X388718Y1387386D03*
X384270Y1389875D03*
X395313Y1452895D03*
X381913D03*
X383823Y1450295D03*
X388603D03*
X383823Y1455495D03*
X388603D03*
X381903Y1459995D03*
Y1465195D03*
X382458Y1550897D03*
X387182Y1550797D03*
X393322Y1573347D03*
X394915Y1590018D03*
X387805Y1607802D03*
Y1604802D03*
Y1610802D03*
X387325Y1627212D03*
X385502Y1667154D03*
X394824Y1667120D03*
X389824D03*
X403734Y110326D03*
Y118976D03*
X397426Y112815D03*
Y116215D03*
X402606Y129465D03*
Y126065D03*
X403141Y144300D03*
X396237Y315507D03*
X399657Y546915D03*
X401880Y696220D03*
X404771Y698670D03*
X396129Y1334717D03*
X408459Y1330709D03*
X405859D03*
X400659D03*
X403259D03*
X408459Y1333816D03*
X405859D03*
X403259D03*
X400659D03*
X408459Y1336773D03*
X405859D03*
X402503Y1340572D03*
X407363D03*
X404933D03*
X407412Y1358587D03*
X407363Y1346172D03*
X404933D03*
X402503D03*
X410002Y1375093D03*
X405978Y1377794D03*
X401953Y1380494D03*
X397187Y1383354D03*
X397223Y1450295D03*
X402003D03*
X397223Y1455495D03*
X402003D03*
X401583Y1504872D03*
X404699Y1523953D03*
X398201Y1548563D03*
X410672Y1561170D03*
X400905Y1596091D03*
X403417Y1606224D03*
X403848Y1615354D03*
X400623Y1629772D03*
X406075Y1641000D03*
X399824Y1667120D03*
X409000Y1667025D03*
X405000Y1683500D03*
X401666Y1677925D03*
X417535Y49379D03*
X413949Y69270D03*
X414486Y127579D03*
Y124179D03*
X423521Y1311969D03*
X421091Y1311219D03*
X419673Y1325571D03*
Y1322971D03*
Y1328171D03*
X422273Y1322971D03*
Y1325571D03*
Y1328171D03*
X416949Y1336713D03*
Y1333756D03*
X424333Y1331447D03*
X411059Y1330709D03*
X416003Y1330725D03*
X413559Y1330709D03*
X421023Y1330671D03*
X414132Y1372234D03*
X415862Y1503715D03*
X422557Y1530595D03*
X420057D03*
X421059Y1569168D03*
X416163Y1594450D03*
X422007Y1592330D03*
X413100Y1607600D03*
X418293Y1607495D03*
X423379Y1607675D03*
X413200Y1612700D03*
X423439Y1612407D03*
X411515Y1599649D03*
X413100Y1617900D03*
X418500Y1618000D03*
X423349Y1617857D03*
X416962Y1634123D03*
X415437Y1636382D03*
X417365Y1630495D03*
X420765D03*
X421347Y1636668D03*
X411500Y1653500D03*
X417441Y1643946D03*
X420000Y1668075D03*
X417000Y1683500D03*
X439535Y49379D03*
X430564Y56348D03*
X430500Y72900D03*
X436090Y128007D03*
X440090Y132007D03*
X433124Y222253D03*
Y225205D03*
X439500Y484000D03*
X439284Y1038766D03*
Y1042766D03*
X431830Y1311240D03*
X438561Y1321622D03*
X432561D03*
X435561D03*
X437624Y1452895D03*
X430924Y1462595D03*
X439534Y1450295D03*
Y1455495D03*
X437614Y1459995D03*
X432834D03*
X437614Y1465195D03*
X432834D03*
X436140Y1499320D03*
X437661Y1518040D03*
Y1514420D03*
Y1510800D03*
X438153Y1528731D03*
X430239Y1581726D03*
X426688Y1598003D03*
X439283Y1608704D03*
X432559Y1627500D03*
X439404Y1615146D03*
X428000Y1640500D03*
X450102Y87011D03*
X450414Y92384D03*
X443014D03*
X452090Y116007D03*
Y124007D03*
Y132007D03*
Y128007D03*
X445997Y170701D03*
X453783Y217646D03*
X441320Y304170D03*
Y310170D03*
X449760Y497240D03*
X448688Y1305947D03*
X449440Y1308386D03*
X450220Y1310834D03*
X451083Y1313347D03*
X441561Y1321622D03*
X444561D03*
X452089Y1316074D03*
X452936Y1318775D03*
X453823Y1321436D03*
X454603Y1324033D03*
X454909Y1326721D03*
X444314Y1450295D03*
Y1455495D03*
X451024Y1472295D03*
X452934Y1469695D03*
Y1474895D03*
X452427Y1550797D03*
X440846Y1576526D03*
X451561Y1589884D03*
Y1594876D03*
X444128Y1604200D03*
Y1600200D03*
X451561Y1621796D03*
Y1626788D03*
X448776Y1622266D03*
Y1617166D03*
Y1619766D03*
X452500Y1637559D03*
X447387Y1641441D03*
X454099Y1649575D03*
X461535Y49379D03*
X457502Y87011D03*
X464456Y93101D03*
X457056D03*
X464051Y224799D03*
X460624Y244103D03*
X465925Y489925D03*
X457724Y1462595D03*
X459634Y1459995D03*
X464414D03*
X466334Y1450295D03*
X464424Y1452895D03*
X466334Y1455495D03*
X459634Y1465195D03*
X464414D03*
X457714Y1469695D03*
Y1474895D03*
X461876Y1550897D03*
X457151Y1550797D03*
X466600Y1550697D03*
X468577Y1589884D03*
Y1594876D03*
X456517Y1589884D03*
X463621D03*
Y1594876D03*
X456517D03*
X457591Y1599884D03*
X462547D03*
Y1604876D03*
X457591D03*
X462547Y1611796D03*
X457591D03*
X469651D03*
Y1599884D03*
Y1604876D03*
X462547Y1616788D03*
X457591D03*
X469651D03*
X468577Y1621796D03*
Y1626788D03*
X463621Y1621796D03*
Y1626788D03*
X456517Y1621796D03*
Y1626788D03*
X457240Y1629500D03*
X462500Y1655500D03*
X468350Y1645351D03*
X461000Y1650000D03*
X470309Y1689000D03*
X470500Y1674075D03*
X462500Y1701000D03*
X468500Y1708500D03*
X467416Y1724808D03*
X469975D03*
X464734Y1730518D03*
X483535Y49379D03*
X478949Y60029D03*
Y55135D03*
Y64975D03*
X470895Y128020D03*
X478295D03*
X482255Y127322D03*
Y135722D03*
X479630Y141942D03*
X471371Y231764D03*
X477203Y1015474D03*
X484784D03*
X477203Y1019017D03*
X484784D03*
X477203Y1022560D03*
X484784D03*
X484524Y1462595D03*
X471114Y1450295D03*
Y1455495D03*
X477824Y1472295D03*
X484514Y1469695D03*
X479734D03*
X484514Y1474895D03*
X479734D03*
X480774Y1550697D03*
X476049Y1550897D03*
X471325D03*
X480637Y1589884D03*
Y1594876D03*
X475681D03*
Y1589884D03*
X481711Y1611796D03*
Y1599884D03*
Y1604876D03*
X474607Y1611796D03*
Y1599884D03*
Y1604876D03*
X481711Y1616788D03*
X474607D03*
X475681Y1621796D03*
X480637D03*
X475681Y1626788D03*
X480637D03*
X478500Y1655500D03*
X476000Y1680000D03*
X478500Y1701000D03*
Y1714500D03*
X487590Y105969D03*
X494810D03*
X492300Y121389D03*
X487880Y131442D03*
X496280D03*
X492300Y124389D03*
X488580Y141942D03*
X494200Y158800D03*
X488260Y418980D03*
X488405Y578572D03*
X492284Y1015474D03*
Y1019017D03*
Y1022560D03*
X491224Y1452895D03*
X497914Y1450295D03*
X493134D03*
X497914Y1455495D03*
X493134D03*
X486434Y1459995D03*
X491214D03*
X486434Y1465195D03*
X491214D03*
X485498Y1550797D03*
X490223Y1550897D03*
X494947D03*
X499672D03*
X499801Y1594876D03*
X492697Y1589884D03*
X487741Y1594876D03*
X492697D03*
X499801Y1589884D03*
X487741D03*
X498727Y1611796D03*
Y1599884D03*
Y1604876D03*
X486667Y1611796D03*
X493771D03*
Y1599884D03*
Y1604876D03*
X486667Y1599884D03*
Y1604876D03*
X498727Y1616788D03*
X499801Y1621796D03*
Y1626788D03*
X486667Y1616788D03*
X493771D03*
X492697Y1621796D03*
X487741D03*
X492697Y1626788D03*
X487741D03*
X510815Y69562D03*
X502815Y106984D03*
X512654Y94967D03*
X500836Y119092D03*
X511140Y109829D03*
X511170Y224930D03*
Y227882D03*
X501500Y433000D03*
X511324Y1462595D03*
X513234Y1459995D03*
X504624Y1472295D03*
X513234Y1465195D03*
X511314Y1469695D03*
X506534D03*
X511314Y1474895D03*
X506534D03*
X513844Y1550897D03*
X509120Y1550697D03*
X504396Y1550897D03*
X511861Y1594876D03*
X504757Y1589884D03*
Y1594876D03*
X511861Y1589884D03*
X505831Y1611796D03*
X510787D03*
X505831Y1599884D03*
Y1604876D03*
X510787Y1599884D03*
Y1604876D03*
X511861Y1621796D03*
Y1626788D03*
X505831Y1616788D03*
X510787D03*
X504757Y1621796D03*
Y1626788D03*
X518843Y23788D03*
X517907Y69507D03*
X524993D03*
X516020Y102870D03*
X519240Y94967D03*
X521420Y109829D03*
X516020Y111770D03*
X518418Y137171D03*
X522831Y443712D03*
X518024Y1452895D03*
X519934Y1450295D03*
X524714D03*
X519934Y1455495D03*
X524714D03*
X518014Y1459995D03*
Y1465195D03*
X523293Y1550797D03*
X518569Y1550897D03*
X528940Y1548260D03*
X528877Y1589884D03*
Y1594876D03*
X516817Y1589884D03*
Y1594876D03*
X523921D03*
Y1589884D03*
X529951Y1611796D03*
Y1599790D03*
Y1604876D03*
X517891Y1611796D03*
X522847D03*
Y1599884D03*
X517891D03*
X522847Y1604876D03*
X517891D03*
X529951Y1616788D03*
X528877Y1621796D03*
Y1626788D03*
X517891Y1616788D03*
X522847D03*
X523921Y1621796D03*
X516817D03*
X523921Y1626788D03*
X516817D03*
X540843Y23788D03*
X542723Y39562D03*
X532080Y69507D03*
X539166D03*
X535170Y108730D03*
Y117630D03*
X533097Y246780D03*
X532000Y426500D03*
X544844Y439701D03*
X543500Y463500D03*
X540106Y657325D03*
X531424Y1452895D03*
X533334Y1450295D03*
X538114D03*
X533334Y1455495D03*
X538114D03*
X544814Y1459995D03*
X540810Y1523953D03*
X540937Y1589884D03*
Y1594876D03*
X535981D03*
Y1589884D03*
X542011Y1611796D03*
Y1599884D03*
Y1604876D03*
X534907Y1611796D03*
Y1599790D03*
Y1604876D03*
X542011Y1616788D03*
X540937Y1621796D03*
Y1626788D03*
X534907Y1616788D03*
X535981Y1621796D03*
Y1626788D03*
X548610Y57990D03*
X546253Y69507D03*
X553340D03*
X545935Y77516D03*
X553821D03*
X546400Y120700D03*
X553780Y118740D03*
Y127140D03*
X547196Y195256D03*
X546800Y262800D03*
X548856Y440452D03*
X556993Y616406D03*
X550993D03*
X553993D03*
X547993D03*
X558986Y1462595D03*
X545931Y1451344D03*
X559090Y1452185D03*
X548119Y1530595D03*
X550619D03*
X552997Y1589884D03*
X548041Y1594876D03*
X552997D03*
X548041Y1589884D03*
X559027Y1611796D03*
Y1599884D03*
Y1604876D03*
X546967Y1611796D03*
X554071D03*
Y1599884D03*
Y1604876D03*
X546967Y1599884D03*
Y1604876D03*
X559027Y1616788D03*
X546967D03*
X554071D03*
X552997Y1621796D03*
Y1626788D03*
X548041D03*
Y1621796D03*
X562843Y23788D03*
X560426Y69507D03*
X570860Y118310D03*
X565210Y125819D03*
X570860Y127510D03*
X564603Y197778D03*
Y200304D03*
X573911Y212196D03*
X569004Y228571D03*
X563230Y426508D03*
X563575Y448425D03*
X569464Y462140D03*
X559993Y616406D03*
X561580Y1242740D03*
X565686Y1452895D03*
X567596Y1450295D03*
X572376D03*
X567596Y1455495D03*
X572376D03*
X565676Y1459995D03*
X560896D03*
X565676Y1465195D03*
X560896D03*
X562860Y1499360D03*
X565723Y1510800D03*
Y1514420D03*
Y1518040D03*
X566215Y1528731D03*
X572161Y1594876D03*
X565057Y1589884D03*
X560101Y1594876D03*
X565057D03*
X572161Y1589884D03*
X560101D03*
X571087Y1611796D03*
Y1599884D03*
Y1604876D03*
X566131Y1611796D03*
Y1599884D03*
Y1604876D03*
X571087Y1616788D03*
X572161Y1621796D03*
Y1626788D03*
X566131Y1616788D03*
X565057Y1621796D03*
X560101D03*
X565057Y1626788D03*
X560101D03*
X584843Y23788D03*
X580098Y96439D03*
X576510Y125819D03*
X588554Y221277D03*
X577859Y212196D03*
X588554Y229277D03*
X575917Y421390D03*
X583505Y457925D03*
X587812Y474353D03*
X577801Y466000D03*
X578830Y1238075D03*
X578071Y1244425D03*
X588630Y1255075D03*
X583630D03*
X585786Y1462595D03*
X587696Y1459995D03*
X579086Y1472295D03*
X587696Y1465195D03*
X580996Y1469695D03*
X585776D03*
X580996Y1474895D03*
X585776D03*
X585213Y1550797D03*
X580489D03*
X589177Y1589884D03*
Y1594876D03*
X577117Y1589884D03*
Y1594876D03*
X584221D03*
Y1589884D03*
X578191Y1611796D03*
X583147D03*
Y1599884D03*
X578191D03*
X583147Y1604876D03*
X578191D03*
X589177Y1621796D03*
Y1626788D03*
X578191Y1616788D03*
X583147D03*
X584221Y1621796D03*
X577117D03*
X584221Y1626788D03*
X577117D03*
X603379Y70512D03*
X594430Y463600D03*
X592612Y805986D03*
X594330Y1238075D03*
X595671Y1245688D03*
X595598Y1251075D03*
X599659Y1241734D03*
X603947Y1258575D03*
X595947D03*
X592476Y1459995D03*
X594396Y1450295D03*
X599176D03*
X592486Y1452895D03*
X594396Y1455495D03*
X599176D03*
X592476Y1465195D03*
X599387Y1550897D03*
X604111D03*
X589938D03*
X594662Y1550697D03*
X601237Y1589884D03*
Y1594876D03*
X596281D03*
Y1589884D03*
X602311Y1611796D03*
Y1599884D03*
Y1604876D03*
X590251Y1611796D03*
X595207D03*
Y1599884D03*
X590251D03*
X595207Y1604876D03*
X590251D03*
X602311Y1616788D03*
X601237Y1621796D03*
Y1626788D03*
X590251Y1616788D03*
X595207D03*
X596281Y1621796D03*
Y1626788D03*
X606843Y23788D03*
X615190Y70533D03*
X607834Y222611D03*
X612414Y227041D03*
X605796Y425585D03*
X612969Y447260D03*
X616171Y780364D03*
X606559Y796116D03*
X612871Y1248488D03*
X612947Y1252075D03*
X609159Y1240234D03*
X612447Y1258575D03*
X616527Y1390732D03*
X619286Y1452895D03*
X612586Y1462595D03*
X614496Y1459995D03*
X619276D03*
X605886Y1472295D03*
X614496Y1465195D03*
X619276D03*
X612576Y1469695D03*
X607796D03*
X612576Y1474895D03*
X607796D03*
X613560Y1550797D03*
X618285Y1550897D03*
X608836Y1550697D03*
X613297Y1589884D03*
X608341Y1594876D03*
X613297D03*
X608341Y1589884D03*
X619327Y1611796D03*
Y1599884D03*
Y1604876D03*
X607267Y1611796D03*
X614371D03*
Y1599884D03*
Y1604876D03*
X607267Y1599884D03*
Y1604876D03*
X619327Y1616788D03*
X607267D03*
X614371D03*
X613297Y1621796D03*
X608341D03*
X613297Y1626788D03*
X608341D03*
X628843Y23788D03*
X625574Y150177D03*
X623605Y219277D03*
Y228777D03*
X624760Y424569D03*
X621916Y465088D03*
X632996Y478309D03*
X621309Y483346D03*
X634288Y766646D03*
X625976Y1450295D03*
X621196D03*
X625976Y1455495D03*
X621196D03*
X632686Y1472295D03*
X632458Y1550897D03*
X623009D03*
X627734D03*
X632461Y1594876D03*
X625357Y1589884D03*
X620401Y1594876D03*
X625357D03*
X632461Y1589884D03*
X620401D03*
X631387Y1611796D03*
Y1599790D03*
Y1604876D03*
X626431Y1611796D03*
Y1599790D03*
Y1604876D03*
X631387Y1616788D03*
X632461Y1626788D03*
Y1621796D03*
X626431Y1616788D03*
X620401Y1621796D03*
X625357D03*
X620401Y1626788D03*
X625357D03*
X627958Y1654114D03*
X645151Y69507D03*
X642394Y131172D03*
X642481Y184862D03*
X643012Y201913D03*
Y199313D03*
X635200Y415425D03*
X644673Y425816D03*
X637504Y454352D03*
X636614Y512597D03*
X647354Y776911D03*
Y783604D03*
Y807029D03*
Y813722D03*
Y820415D03*
Y843840D03*
Y850533D03*
Y857226D03*
Y880651D03*
Y887344D03*
Y894037D03*
Y917462D03*
Y924155D03*
Y930848D03*
Y954273D03*
Y960966D03*
Y967659D03*
Y974352D03*
Y981045D03*
Y987737D03*
Y994430D03*
Y1004470D03*
Y1034588D03*
Y1041281D03*
Y1047974D03*
Y1054667D03*
Y1061360D03*
Y1071399D03*
Y1078092D03*
Y1101517D03*
Y1108210D03*
Y1114903D03*
Y1138328D03*
Y1145021D03*
Y1151714D03*
Y1175139D03*
Y1181832D03*
Y1188525D03*
Y1211950D03*
Y1218643D03*
Y1225336D03*
Y1248761D03*
Y1255454D03*
X642436Y1350877D03*
X646236D03*
X638436D03*
X643563Y1392581D03*
X647445Y1392605D03*
X646086Y1452895D03*
X639386Y1462595D03*
X647996Y1450295D03*
Y1455495D03*
X641296Y1459995D03*
X646076D03*
X641296Y1465195D03*
X646076D03*
X639376Y1469695D03*
X634596D03*
X639376Y1474895D03*
X634596D03*
X646631Y1550897D03*
X637182Y1550697D03*
X641906Y1550897D03*
X637417Y1589884D03*
Y1594876D03*
X643447Y1599884D03*
X638491D03*
X643447Y1604876D03*
X638491D03*
X643447Y1611796D03*
X638491D03*
X643447Y1616788D03*
X637417Y1626788D03*
X638491Y1616788D03*
X637417Y1621796D03*
X640520Y1635483D03*
X649266Y1650126D03*
X642151Y1649961D03*
X639284Y1683049D03*
X647500Y1682850D03*
X635210Y1721545D03*
X650843Y23788D03*
X649585Y29298D03*
X663703Y32574D03*
X653570Y58363D03*
X660775Y78330D03*
X649441Y177003D03*
X662740Y375240D03*
X649500Y382500D03*
X660885Y412588D03*
X650268Y479141D03*
X649771Y505736D03*
X659398Y516260D03*
X658946Y756766D03*
X651904D03*
Y760266D03*
X663496Y773564D03*
X658946Y763766D03*
X651904Y767266D03*
X658046Y786950D03*
X663496Y780257D03*
X651754Y795316D03*
X658046Y796989D03*
X663496Y803682D03*
Y810375D03*
Y817068D03*
X651754Y832127D03*
X658046Y833800D03*
Y823761D03*
X663496Y840493D03*
Y847186D03*
X658046Y860572D03*
X663496Y853879D03*
X651754Y868938D03*
X658046Y870611D03*
X663496Y877304D03*
Y883997D03*
Y890690D03*
X651754Y905750D03*
X658046Y897383D03*
Y907423D03*
X663496Y914115D03*
Y920808D03*
X658046Y934194D03*
X663496Y927501D03*
X651754Y942561D03*
X658046Y944234D03*
X663496Y950926D03*
Y957619D03*
Y964312D03*
Y971005D03*
Y977698D03*
Y984391D03*
Y991084D03*
Y997777D03*
Y1004470D03*
Y1031241D03*
Y1037934D03*
Y1044627D03*
Y1051320D03*
Y1058013D03*
Y1068052D03*
Y1074745D03*
X651754Y1089805D03*
X658046Y1081438D03*
Y1091478D03*
X663496Y1098171D03*
Y1104863D03*
X658046Y1118249D03*
X663496Y1111556D03*
X651754Y1126616D03*
X658046Y1128289D03*
X663496Y1134982D03*
Y1141675D03*
Y1148367D03*
X651754Y1163427D03*
X658046Y1155060D03*
Y1165100D03*
X663496Y1171793D03*
Y1178486D03*
X658046Y1191871D03*
X663496Y1185178D03*
X651754Y1200238D03*
X658046Y1201911D03*
X663496Y1208604D03*
Y1215297D03*
Y1221989D03*
X651754Y1237049D03*
X658046Y1238722D03*
Y1228682D03*
X663496Y1245415D03*
Y1252108D03*
X657836Y1350877D03*
X653836D03*
X650036D03*
X661713Y1373981D03*
X655702Y1391107D03*
X659559Y1391027D03*
X655873Y1428844D03*
X652189Y1421276D03*
X659486Y1452895D03*
X661396Y1450295D03*
X652776D03*
X661396Y1455495D03*
X652776D03*
X662374Y1548563D03*
X651355Y1550797D03*
X651840Y1567752D03*
X660542Y1638169D03*
X657392Y1628137D03*
X652274Y1630366D03*
X650895Y1648115D03*
X655914Y1668744D03*
X659436Y1694697D03*
X649526Y1709274D03*
X663997Y1703111D03*
X659673Y1722174D03*
X661845Y1717340D03*
X654508Y1728000D03*
X654527Y1718229D03*
X659673Y1732836D03*
X672843Y23788D03*
X668739Y45262D03*
X677594Y36205D03*
X675887Y45262D03*
X666411Y69507D03*
X678664Y88080D03*
X673751Y78092D03*
X673691Y200672D03*
X673301Y211332D03*
X671753Y397936D03*
X670000Y457844D03*
X669955Y495468D03*
X671500Y529500D03*
X677055Y776911D03*
X667896Y791970D03*
X677055Y783604D03*
Y807029D03*
Y813722D03*
Y820415D03*
X667896Y828781D03*
X677055Y843840D03*
Y850533D03*
X667896Y865592D03*
X677055Y857226D03*
Y880651D03*
Y887344D03*
Y894037D03*
X667896Y902403D03*
X677055Y917462D03*
Y924155D03*
X667896Y939214D03*
X677055Y930848D03*
Y954273D03*
Y960966D03*
Y967659D03*
Y974352D03*
Y981045D03*
Y987737D03*
Y994430D03*
Y1004470D03*
Y1034588D03*
Y1041281D03*
Y1047974D03*
Y1054667D03*
Y1061360D03*
Y1071399D03*
X667896Y1086458D03*
X677055Y1078092D03*
Y1101517D03*
Y1108210D03*
Y1114903D03*
X667896Y1123269D03*
X677055Y1138328D03*
Y1145021D03*
X667896Y1160080D03*
X677055Y1151714D03*
Y1175139D03*
Y1181832D03*
Y1188525D03*
X667896Y1196891D03*
X677055Y1211950D03*
Y1218643D03*
X667896Y1233702D03*
X677055Y1225336D03*
Y1248761D03*
Y1255454D03*
X674552Y1351988D03*
Y1349488D03*
X666176Y1450295D03*
Y1455495D03*
X666050Y1501670D03*
X672684Y1522690D03*
X674687Y1519726D03*
X665800Y1530575D03*
X674620Y1535271D03*
Y1542125D03*
X672617Y1545089D03*
Y1538235D03*
X674894Y1629042D03*
X673982Y1639289D03*
X665802Y1652337D03*
X674486Y1647842D03*
X673480Y1662668D03*
X671631Y1690786D03*
X693672Y32684D03*
X686855Y43701D03*
X679719Y59066D03*
X682946Y69982D03*
X682891Y72642D03*
X688552Y79166D03*
X681895Y82212D03*
X685783Y78768D03*
X684954Y104968D03*
X691058Y131408D03*
X684521Y152482D03*
X688521D03*
X692521D03*
X682264Y224116D03*
X691547Y386834D03*
X688249Y405628D03*
X679862Y409320D03*
X679500Y526834D03*
X691496Y575081D03*
X688078Y675493D03*
X681605Y756766D03*
X681671Y760178D03*
X688647Y756766D03*
X693197Y773564D03*
X688647Y763766D03*
X681605Y767266D03*
X687747Y786950D03*
X693197Y780257D03*
X681455Y795316D03*
X687747Y796989D03*
X693197Y803682D03*
Y810375D03*
Y817068D03*
X681455Y832127D03*
X687747Y833800D03*
Y823761D03*
X693197Y840493D03*
Y847186D03*
X687747Y860572D03*
X693197Y853879D03*
X681455Y868938D03*
X687747Y870611D03*
X693197Y877304D03*
Y883997D03*
Y890690D03*
X681455Y905750D03*
X687747Y897383D03*
Y907423D03*
X693197Y914115D03*
Y920808D03*
X687747Y934194D03*
X693197Y927501D03*
X681455Y942561D03*
X687747Y944234D03*
X693197Y950926D03*
Y957619D03*
Y964312D03*
Y971005D03*
Y977698D03*
Y984391D03*
Y991084D03*
Y997777D03*
Y1004470D03*
Y1031241D03*
Y1037934D03*
Y1044627D03*
Y1051320D03*
Y1058013D03*
Y1068052D03*
Y1074745D03*
X681455Y1089805D03*
X687747Y1081438D03*
Y1091478D03*
X693197Y1098171D03*
Y1104863D03*
X687747Y1118249D03*
X693197Y1111556D03*
X681455Y1126616D03*
X687747Y1128289D03*
X693197Y1134982D03*
Y1141675D03*
Y1148367D03*
X681455Y1163427D03*
X687747Y1155060D03*
Y1165100D03*
X693197Y1171793D03*
Y1178486D03*
X687747Y1191871D03*
X693197Y1185178D03*
X681455Y1200238D03*
X687747Y1201911D03*
X693197Y1208604D03*
Y1215297D03*
Y1221989D03*
X681455Y1237049D03*
X687747Y1238722D03*
Y1228682D03*
X693197Y1245415D03*
Y1252108D03*
X688076Y1297506D03*
Y1305206D03*
Y1300006D03*
Y1302606D03*
X683052Y1352048D03*
Y1349548D03*
X685187Y1368700D03*
Y1363500D03*
Y1366100D03*
X687577Y1425054D03*
X688120Y1519601D03*
X683352Y1530526D03*
Y1526526D03*
X682016Y1539067D03*
X688308Y1631636D03*
X693150Y1640773D03*
X682925Y1657116D03*
X686825Y1647430D03*
X685485Y1682259D03*
X694843Y23788D03*
X701839Y45112D03*
X707608Y69718D03*
X705570Y133760D03*
X704144Y122602D03*
X707243Y123946D03*
X701927Y166535D03*
Y172441D03*
Y178346D03*
Y184252D03*
Y196063D03*
Y190157D03*
Y201968D03*
Y207874D03*
Y213779D03*
Y219685D03*
X696105Y364149D03*
X696500Y529862D03*
X700500Y545862D03*
X704500Y555862D03*
X701496Y580556D03*
X697392Y601686D03*
X697642Y733401D03*
X706756Y776911D03*
X697597Y791970D03*
X706756Y783604D03*
Y807029D03*
Y813722D03*
Y820415D03*
X697597Y828781D03*
X706756Y843840D03*
Y850533D03*
X697597Y865592D03*
X706756Y857226D03*
Y880651D03*
Y887344D03*
Y894037D03*
X697597Y902403D03*
X706756Y924155D03*
Y917462D03*
X697597Y939214D03*
X706756Y930848D03*
Y954273D03*
Y960966D03*
Y967659D03*
Y974352D03*
Y981045D03*
Y987737D03*
Y994430D03*
Y1004470D03*
Y1041281D03*
Y1034588D03*
Y1047974D03*
Y1054667D03*
Y1071399D03*
Y1061360D03*
Y1078092D03*
X697597Y1086458D03*
X706756Y1101517D03*
Y1114903D03*
Y1108210D03*
X697597Y1123269D03*
X706756Y1145021D03*
Y1138328D03*
Y1151714D03*
X697597Y1160080D03*
X706756Y1175139D03*
Y1181832D03*
Y1188525D03*
X697597Y1196891D03*
X706756Y1211950D03*
Y1218643D03*
Y1225336D03*
X697597Y1233702D03*
X706756Y1248761D03*
Y1255454D03*
X697483Y1297506D03*
Y1305206D03*
Y1300006D03*
Y1302606D03*
X701771Y1351988D03*
Y1349488D03*
X699467Y1368710D03*
Y1363510D03*
Y1366110D03*
X703568Y1379476D03*
X699610Y1580523D03*
X706681Y1627361D03*
X705833Y1633568D03*
X706089Y1643411D03*
X705815Y1654918D03*
X703473Y1663001D03*
X695400Y1685887D03*
X705366Y1684064D03*
X723479Y-28508D03*
X716843Y23788D03*
X717342Y57098D03*
X720328Y344824D03*
X711500Y360862D03*
X719500D03*
X711556Y575081D03*
X714583Y587642D03*
X715037Y603278D03*
X713280Y636897D03*
X712319Y654954D03*
X711306Y756766D03*
Y760178D03*
X718348Y756766D03*
X722898Y773564D03*
X718348Y763766D03*
X711306Y767266D03*
X722898Y780257D03*
X717448Y786950D03*
X722898Y803682D03*
X711156Y795316D03*
X717448Y796989D03*
X722898Y810375D03*
Y817068D03*
X717448Y823761D03*
Y833800D03*
X711156Y832127D03*
X722898Y847186D03*
Y840493D03*
Y853879D03*
X717448Y860572D03*
X722898Y877304D03*
X717448Y870611D03*
X711156Y868938D03*
X722898Y883997D03*
Y890690D03*
X717448Y897383D03*
Y907423D03*
X711156Y905750D03*
X722898Y920808D03*
Y914115D03*
Y927501D03*
X717448Y934194D03*
X722898Y950926D03*
X717448Y944234D03*
X711156Y942561D03*
X722898Y957619D03*
Y971005D03*
Y964312D03*
Y984391D03*
Y977698D03*
Y991084D03*
Y997777D03*
Y1004470D03*
Y1031241D03*
Y1037934D03*
Y1044627D03*
Y1051320D03*
Y1058013D03*
Y1068052D03*
Y1074745D03*
X717448Y1081438D03*
X711156Y1089805D03*
X717448Y1091478D03*
X722898Y1098171D03*
Y1104863D03*
Y1111556D03*
X717448Y1118249D03*
Y1128289D03*
X711156Y1126616D03*
X722898Y1134982D03*
Y1148367D03*
Y1141675D03*
X717448Y1165100D03*
X711156Y1163427D03*
X717448Y1155060D03*
X722898Y1178486D03*
Y1171793D03*
Y1185178D03*
X717448Y1191871D03*
X722898Y1208604D03*
X711156Y1200238D03*
X717448Y1201911D03*
X722898Y1215297D03*
Y1221989D03*
X717448Y1228682D03*
Y1238722D03*
X711156Y1237049D03*
X722898Y1252108D03*
Y1245415D03*
X721361Y1297546D03*
X711954D03*
X721361Y1305246D03*
Y1302646D03*
Y1300046D03*
X711954Y1305246D03*
Y1302646D03*
Y1300046D03*
X710221Y1351988D03*
Y1349488D03*
X716707Y1385281D03*
X719137D03*
X720233Y1378525D03*
Y1381482D03*
Y1375418D03*
X722833D03*
X714277Y1385281D03*
X715033Y1378525D03*
X717633D03*
X712433D03*
X717633Y1381482D03*
X715033Y1375418D03*
X717633D03*
X712433D03*
X719186Y1403296D03*
X719137Y1390881D03*
X714277D03*
X716707D03*
X709551Y1406578D03*
X716770Y1531459D03*
X715122Y1533378D03*
X716989Y1537249D03*
X713357Y1535212D03*
X715224Y1539083D03*
X713459Y1540917D03*
X722876Y1611343D03*
X717749Y1654921D03*
X709771Y1654927D03*
X712354Y1682279D03*
X738843Y23788D03*
X728981Y39872D03*
X736791Y39832D03*
X730131Y60757D03*
X736524Y58069D03*
X730958Y71014D03*
X738044Y71526D03*
X727944Y88972D03*
X727986Y101979D03*
X729900Y98090D03*
X727986Y105477D03*
X737624Y98858D03*
X734524Y98758D03*
X735734Y111988D03*
X726720Y574910D03*
X724001Y636790D03*
X726952Y648667D03*
X736457Y776911D03*
Y783604D03*
X727298Y791970D03*
X736457Y807029D03*
Y813722D03*
Y820415D03*
X727298Y828781D03*
X736457Y843840D03*
Y850533D03*
X727298Y865592D03*
X736457Y857226D03*
Y880651D03*
Y887344D03*
Y894037D03*
X727298Y902403D03*
X736457Y924155D03*
Y917462D03*
X727298Y939214D03*
X736457Y930848D03*
Y954273D03*
Y960966D03*
Y967659D03*
Y974352D03*
Y981045D03*
Y987737D03*
Y994430D03*
Y1004470D03*
Y1034588D03*
Y1041281D03*
Y1047974D03*
Y1054667D03*
Y1071399D03*
Y1061360D03*
X727298Y1086458D03*
X736457Y1078092D03*
Y1101517D03*
Y1114903D03*
Y1108210D03*
X727298Y1123269D03*
X736457Y1145021D03*
Y1138328D03*
X727298Y1160080D03*
X736457Y1151714D03*
Y1175139D03*
Y1181832D03*
Y1188525D03*
X727298Y1196891D03*
X736457Y1211950D03*
Y1218643D03*
X727298Y1233702D03*
X736457Y1225336D03*
Y1248761D03*
Y1255454D03*
X735954Y1297546D03*
Y1305246D03*
Y1302646D03*
Y1300046D03*
X727098Y1351977D03*
X730900Y1352131D03*
X727098Y1349077D03*
X730900Y1349231D03*
X734047Y1372880D03*
X731447D03*
X734047Y1370280D03*
Y1367680D03*
X731447D03*
Y1370280D03*
X728348Y1380832D03*
Y1377875D03*
X736280Y1379580D03*
X732797Y1375380D03*
X725333Y1375418D03*
X727777Y1375434D03*
X738230Y1402898D03*
X734925Y1657826D03*
X730302Y1658050D03*
X726302Y1658022D03*
X738370Y1677909D03*
X736001Y1695509D03*
X728454Y1690491D03*
X732434Y1690660D03*
X738550Y1693215D03*
X742841Y39832D03*
X744477Y58373D03*
X744988Y49062D03*
X747488D03*
X752261Y59782D03*
X745131Y69507D03*
X750090Y72820D03*
X745712Y212760D03*
X746705Y315647D03*
X742278Y566667D03*
X753500Y675800D03*
X748049Y756766D03*
X741007D03*
Y760266D03*
X752599Y773564D03*
X741007Y767266D03*
X748049Y763766D03*
X752599Y780257D03*
X747149Y786950D03*
X752599Y803682D03*
X747149Y796989D03*
X740857Y795316D03*
X752599Y810375D03*
Y817068D03*
X747149Y823761D03*
Y833800D03*
X740857Y832127D03*
X752599Y840493D03*
Y847186D03*
Y853879D03*
X747149Y860572D03*
X752599Y877304D03*
X747149Y870611D03*
X740857Y868938D03*
X752599Y890690D03*
Y883997D03*
X747149Y897383D03*
Y907423D03*
X740857Y905750D03*
X752599Y920808D03*
Y914115D03*
X747149Y934194D03*
X752599Y927501D03*
Y950926D03*
X747149Y944234D03*
X740857Y942561D03*
X752599Y957619D03*
Y971005D03*
Y964312D03*
Y984391D03*
Y977698D03*
Y991084D03*
Y997777D03*
Y1004470D03*
Y1031241D03*
Y1037934D03*
Y1044627D03*
Y1051320D03*
Y1058013D03*
Y1068052D03*
Y1074745D03*
X747149Y1081438D03*
X740857Y1089805D03*
X752599Y1098171D03*
Y1104863D03*
X747149Y1091478D03*
X752599Y1111556D03*
X747149Y1118249D03*
Y1128289D03*
X740857Y1126616D03*
X752599Y1134982D03*
Y1148367D03*
Y1141675D03*
X740857Y1163427D03*
X747149Y1165100D03*
Y1155060D03*
X752599Y1178486D03*
Y1171793D03*
Y1185178D03*
X747149Y1191871D03*
X752599Y1208604D03*
X740857Y1200238D03*
X747149Y1201911D03*
X752599Y1215297D03*
Y1221989D03*
X747149Y1228682D03*
Y1238722D03*
X740857Y1237049D03*
X752599Y1252108D03*
Y1245415D03*
X745475Y1297246D03*
Y1304946D03*
Y1302346D03*
Y1299746D03*
X739500Y1352031D03*
Y1349131D03*
X753015Y1381582D03*
Y1378625D03*
Y1375518D03*
X747059Y1385381D03*
X745215Y1378625D03*
X747815D03*
Y1375518D03*
X745215D03*
X750415Y1381582D03*
Y1378625D03*
Y1375518D03*
X749489Y1385381D03*
X751919D03*
X751968Y1403396D03*
X751919Y1390981D03*
X747059D03*
X749489D03*
X739888Y1404849D03*
X743740Y1657327D03*
X743039Y1643326D03*
X760843Y23788D03*
X754621Y74562D03*
X754634Y105288D03*
Y108288D03*
X762173Y123898D03*
X770073Y143438D03*
X756083Y220240D03*
X757464Y284087D03*
X754556Y283976D03*
X755335Y295589D03*
X758959Y319596D03*
X753959Y343790D03*
X766158Y776911D03*
Y783604D03*
X756999Y791970D03*
X766158Y807029D03*
Y813722D03*
Y820415D03*
X756999Y828781D03*
X766158Y843840D03*
Y850533D03*
Y857226D03*
X756999Y865592D03*
X766158Y880651D03*
Y887344D03*
Y894037D03*
X756999Y902403D03*
X766158Y924155D03*
Y917462D03*
X756999Y939214D03*
X766158Y930848D03*
Y954273D03*
Y960966D03*
Y967659D03*
Y974352D03*
Y981045D03*
Y987737D03*
Y994430D03*
Y1004470D03*
Y1041281D03*
Y1034588D03*
Y1047974D03*
Y1054667D03*
Y1071399D03*
Y1061360D03*
X756999Y1086458D03*
X766158Y1078092D03*
Y1101517D03*
Y1114903D03*
Y1108210D03*
X756999Y1123269D03*
X766158Y1145021D03*
Y1138328D03*
X756999Y1160080D03*
X766158Y1151714D03*
Y1175139D03*
Y1181832D03*
Y1188525D03*
X756999Y1196891D03*
X766158Y1211950D03*
Y1218643D03*
Y1225336D03*
X756999Y1233702D03*
X766158Y1248761D03*
Y1255454D03*
X759854Y1297246D03*
Y1304946D03*
Y1302346D03*
Y1299746D03*
X761800Y1352031D03*
Y1349131D03*
X764229Y1372880D03*
X766829D03*
Y1370380D03*
Y1367780D03*
X764229D03*
Y1370380D03*
X761130Y1380932D03*
Y1377975D03*
X755615Y1375518D03*
X758115D03*
X760559Y1375534D03*
X765579Y1375480D03*
X767381Y1676594D03*
X769475Y75360D03*
X771356Y167518D03*
X773221Y296262D03*
X780618Y296345D03*
X779121Y306155D03*
X773944Y312588D03*
X780808Y419865D03*
X777900Y756766D03*
X770708D03*
Y760266D03*
X782300Y773564D03*
X770708Y767266D03*
X777900Y763766D03*
X776850Y786950D03*
X782300Y780257D03*
X776850Y796989D03*
X770558Y795316D03*
X782300Y803682D03*
Y810375D03*
Y817068D03*
X770558Y832127D03*
X776850Y823761D03*
Y833800D03*
X782300Y847186D03*
Y840493D03*
X776850Y860572D03*
X782300Y853879D03*
Y877304D03*
X776850Y870611D03*
X770558Y868938D03*
X782300Y890690D03*
Y883997D03*
X776850Y897383D03*
Y907423D03*
X770558Y905750D03*
X782300Y920808D03*
Y914115D03*
X776850Y934194D03*
X782300Y927501D03*
X776850Y944234D03*
X770558Y942561D03*
X782300Y950926D03*
Y957619D03*
Y971005D03*
Y964312D03*
Y984391D03*
Y977698D03*
Y991084D03*
Y997777D03*
Y1004470D03*
Y1031241D03*
Y1037934D03*
Y1044627D03*
Y1051320D03*
Y1058013D03*
Y1068052D03*
Y1074745D03*
X776850Y1081438D03*
X770558Y1089805D03*
X782300Y1098171D03*
Y1104863D03*
X776850Y1091478D03*
Y1118249D03*
X782300Y1111556D03*
X776850Y1128289D03*
X770558Y1126616D03*
X782300Y1134982D03*
Y1148367D03*
Y1141675D03*
X776850Y1165100D03*
X770558Y1163427D03*
X776850Y1155060D03*
X782300Y1178486D03*
Y1171793D03*
Y1185178D03*
X776850Y1191871D03*
X782300Y1208604D03*
X770558Y1200238D03*
X776850Y1201911D03*
X782300Y1215297D03*
Y1221989D03*
X776850Y1228682D03*
Y1238722D03*
X770558Y1237049D03*
X782300Y1252108D03*
Y1245415D03*
X769521Y1297199D03*
Y1304899D03*
Y1299699D03*
Y1302299D03*
X770990Y1349091D03*
Y1351991D03*
X773069Y1375500D03*
X770469D03*
X776010Y1380750D03*
X787456Y49379D03*
X797594Y282233D03*
X797444Y271469D03*
X795668Y298801D03*
X792488Y377452D03*
X797252Y459344D03*
Y471344D03*
X794425Y541425D03*
X794059Y553559D03*
X791500Y560000D03*
X785000Y563500D03*
X795858Y776911D03*
Y783604D03*
X786700Y791970D03*
X795858Y807029D03*
Y820415D03*
Y813722D03*
X786700Y828781D03*
X795858Y843840D03*
Y850533D03*
X786700Y865592D03*
X795858Y857226D03*
Y880651D03*
Y894037D03*
Y887344D03*
X786700Y902403D03*
X795858Y924155D03*
Y917462D03*
X786700Y939214D03*
X795858Y930848D03*
Y954273D03*
Y960966D03*
Y967659D03*
Y981045D03*
Y974352D03*
Y994430D03*
Y987737D03*
Y1004470D03*
Y1041281D03*
Y1034588D03*
Y1054667D03*
Y1047974D03*
Y1071399D03*
Y1061360D03*
X786700Y1086458D03*
X795858Y1078092D03*
Y1101517D03*
Y1114903D03*
Y1108210D03*
X786700Y1123269D03*
X795858Y1145021D03*
Y1138328D03*
X786700Y1160080D03*
X795858Y1151714D03*
Y1175139D03*
Y1181832D03*
Y1188525D03*
X786700Y1196891D03*
X795858Y1218643D03*
Y1211950D03*
X786700Y1233702D03*
X795858Y1225336D03*
Y1248761D03*
Y1255454D03*
X809456Y49379D03*
X806984Y265653D03*
X798621Y312773D03*
X803264Y330102D03*
X808401Y341670D03*
X811569Y387674D03*
X813175Y422687D03*
X810360Y442079D03*
X802752Y455344D03*
X812500Y504000D03*
X807450Y756766D03*
X800408D03*
Y760266D03*
X812000Y773564D03*
X800408Y767266D03*
X812000Y780257D03*
X806550Y786950D03*
X812000Y803682D03*
X806550Y796989D03*
X800258Y795316D03*
X812000Y817068D03*
Y810375D03*
X800258Y832127D03*
X806550Y833800D03*
Y823761D03*
X812000Y847186D03*
Y840493D03*
X806550Y860572D03*
X812000Y853879D03*
Y877304D03*
X806550Y870611D03*
X800258Y868938D03*
X812000Y890690D03*
Y883997D03*
X806550Y897383D03*
Y907423D03*
X800258Y905750D03*
X812000Y920808D03*
Y914115D03*
Y927501D03*
X806550Y934194D03*
X812000Y950926D03*
X800258Y942561D03*
X806550Y944234D03*
X812000Y957619D03*
Y971005D03*
Y964312D03*
Y984391D03*
Y977698D03*
Y997777D03*
Y991084D03*
Y1004470D03*
Y1044627D03*
Y1037934D03*
Y1031241D03*
Y1058013D03*
Y1051320D03*
Y1068052D03*
Y1074745D03*
X806550Y1081438D03*
X800258Y1089805D03*
X812000Y1098171D03*
Y1104863D03*
X806550Y1091478D03*
X812000Y1111556D03*
X806550Y1118249D03*
Y1128289D03*
X800258Y1126616D03*
X812000Y1134982D03*
Y1148367D03*
Y1141675D03*
X806550Y1165100D03*
X800258Y1163427D03*
X806550Y1155060D03*
X812000Y1178486D03*
Y1171793D03*
Y1185178D03*
X806550Y1191871D03*
X812000Y1208604D03*
X806550Y1201911D03*
X800258Y1200238D03*
X812000Y1221989D03*
Y1215297D03*
X806550Y1228682D03*
Y1238722D03*
X800258Y1237049D03*
X812000Y1245415D03*
Y1252108D03*
X822699Y56712D03*
X821119Y134632D03*
X825699Y139062D03*
X816322Y284369D03*
X826665Y423425D03*
X817426Y487232D03*
X824500Y514500D03*
X817441Y517941D03*
X822559Y530876D03*
X826552Y543612D03*
X823777Y560988D03*
X816400Y828781D03*
Y865592D03*
Y902403D03*
Y939214D03*
Y1086458D03*
Y1123269D03*
Y1160080D03*
Y1196891D03*
Y1233702D03*
X826112Y1269546D03*
X833407Y-26181D03*
X836660Y-26167D03*
Y-16167D03*
X833407Y-16181D03*
X839700Y-14972D03*
X833422Y-13666D03*
X836675Y-13652D03*
X833412Y-19948D03*
X836674D03*
X836675Y-23652D03*
X833422Y-23666D03*
X839700Y-24972D03*
X833412Y52D03*
X836674D03*
X833412Y-9948D03*
X836674D03*
X836675Y-3652D03*
X833422Y-3666D03*
X839700Y-4972D03*
X833407Y-6181D03*
X836660Y-6167D03*
X836675Y16348D03*
X833422Y16334D03*
X839700Y15028D03*
X833407Y13819D03*
X836660Y13833D03*
X836674Y10052D03*
X833412D03*
X836675Y6348D03*
X833422Y6334D03*
X839700Y5028D03*
X833407Y3819D03*
X836660Y3833D03*
X836659Y24250D03*
X836674Y26765D03*
X833406Y24236D03*
X839699Y25445D03*
X833421Y26751D03*
X833376Y19206D03*
X833391Y21721D03*
X831456Y49379D03*
X836127Y62681D03*
X837792Y85186D03*
X831298Y104206D03*
X834616Y94324D03*
X842865Y110296D03*
X830340Y228143D03*
X832525Y268579D03*
X829572Y296511D03*
X840288Y287593D03*
X829167Y288063D03*
X832686Y331028D03*
X836840Y382003D03*
X841862Y390441D03*
X834430Y434634D03*
X834251Y459578D03*
X835425Y477890D03*
X830743Y500740D03*
X831756Y901318D03*
X835554Y1281324D03*
X835682Y1285472D03*
X836670Y1291355D03*
X836587Y1295333D03*
X842500Y1310000D03*
Y1306000D03*
Y1302000D03*
X834017Y1333584D03*
X834071Y1342457D03*
X839188Y1348937D03*
X841203Y1361376D03*
X853456Y49379D03*
X854108Y91232D03*
X851895Y160141D03*
X853800Y265057D03*
X847939Y265092D03*
X854334Y276117D03*
X854225Y280027D03*
Y283527D03*
X857334Y276117D03*
X852780Y291559D03*
X852801Y288562D03*
X853201Y297462D03*
X856701Y304862D03*
X846275Y335575D03*
X849750Y401280D03*
X852240Y470946D03*
X849126Y530138D03*
X845126D03*
X848660Y651127D03*
X846725Y1269785D03*
X861351Y61672D03*
X858528Y262382D03*
X860834Y276817D03*
X863934Y276917D03*
X862044Y290047D03*
X862075Y398537D03*
X872020Y413300D03*
X867590Y642420D03*
X864700Y836100D03*
X859446Y1284288D03*
X875345Y51595D03*
X877462Y139540D03*
X878221Y192055D03*
X880944Y283347D03*
Y286347D03*
X875447Y301500D03*
X884740Y316000D03*
X874500Y328000D03*
X873884Y453383D03*
X886707Y1254742D03*
Y1251742D03*
X881807Y1248920D03*
Y1245920D03*
X881937Y1251857D03*
X877480Y1248844D03*
X886707Y1257742D03*
X885000Y1307500D03*
X877000Y1340241D03*
X884462Y1446974D03*
X876044Y1444317D03*
X898720Y145206D03*
X888560Y469527D03*
X902376Y594657D03*
X903556Y614062D03*
X899678Y601043D03*
X897824Y909093D03*
X891648Y1137843D03*
X900723Y1146553D03*
X896107Y1254742D03*
Y1251742D03*
X896907Y1245920D03*
Y1248920D03*
X896107Y1257742D03*
X917386Y179500D03*
Y177000D03*
Y169500D03*
Y172000D03*
Y174500D03*
Y167000D03*
X909298Y195925D03*
X909161Y203012D03*
X909320Y210098D03*
Y217185D03*
Y224271D03*
Y231358D03*
X914575Y560027D03*
X906597Y579695D03*
X907035Y590172D03*
X906597Y628426D03*
X906734Y619373D03*
X906570Y663930D03*
X906387Y818471D03*
X903941Y874000D03*
X917622Y887545D03*
X909000Y909000D03*
X905000D03*
X904719Y921792D03*
X911500Y931000D03*
X908500Y927500D03*
X909890Y950217D03*
X910066Y960332D03*
X909203Y970709D03*
X916763Y972343D03*
X908799Y985291D03*
X910707Y1254742D03*
Y1251742D03*
X905007Y1248920D03*
Y1245920D03*
X905074Y1252177D03*
X910707Y1257742D03*
X920720Y145206D03*
X919886Y167000D03*
Y169500D03*
Y172000D03*
Y174500D03*
Y177000D03*
Y179500D03*
X927134Y189386D03*
X925321Y203399D03*
X926983Y604751D03*
X927127Y619251D03*
X930926Y664791D03*
X923916Y843990D03*
X918500Y856925D03*
X930925Y860925D03*
X929603Y889000D03*
X931948Y891397D03*
X919916Y908916D03*
X920276Y900554D03*
X931877Y918168D03*
X928535Y913454D03*
X920409Y918274D03*
X918000Y928000D03*
X926062Y938727D03*
X926004Y952716D03*
X925200Y1110443D03*
Y1107843D03*
Y1117443D03*
Y1114843D03*
Y1124443D03*
Y1121843D03*
Y1131443D03*
Y1128843D03*
X920107Y1251742D03*
Y1254742D03*
Y1248920D03*
Y1245920D03*
Y1257742D03*
X924000Y1310000D03*
X920738Y1321363D03*
X927869Y1317417D03*
X923680Y1339520D03*
X919758Y1348990D03*
X931798Y1660762D03*
X923798D03*
X945006Y593609D03*
X935649Y590751D03*
X939391Y600571D03*
X946366Y668811D03*
X940391Y859947D03*
X944057Y882886D03*
X940514Y918134D03*
X933021Y933979D03*
X939670Y945169D03*
X942924Y982547D03*
X943135Y977129D03*
X938507Y1137843D03*
X945691Y1254742D03*
Y1251742D03*
X940791Y1248920D03*
Y1245920D03*
X940921Y1251857D03*
X936464Y1248844D03*
X945691Y1257742D03*
X938000Y1309500D03*
Y1301500D03*
Y1304500D03*
X933586Y1325501D03*
X933041Y1315920D03*
X939798Y1660762D03*
X955529Y614017D03*
X951839Y812730D03*
X958051Y859384D03*
X952425Y876575D03*
X948060Y891468D03*
X951367Y913648D03*
X951500Y930925D03*
X955091Y1254742D03*
Y1251742D03*
X955891Y1245920D03*
Y1248920D03*
X955000Y1267000D03*
X955091Y1257742D03*
X955000Y1271000D03*
Y1275000D03*
Y1279000D03*
X960518Y1656185D03*
X957758D03*
X957848Y1659375D03*
X960608D03*
X960558Y1662015D03*
X957798D03*
X947798Y1660762D03*
X964720Y145206D03*
X975689Y156950D03*
Y153950D03*
X971192Y219589D03*
X968692D03*
X973616Y317648D03*
X963134Y882936D03*
X968919Y1116177D03*
Y1118777D03*
Y1109177D03*
Y1111777D03*
X968800Y1130046D03*
Y1132646D03*
X968919Y1123177D03*
Y1125777D03*
X969691Y1254742D03*
Y1251742D03*
X963991Y1248920D03*
Y1245920D03*
X964058Y1252177D03*
X969691Y1257742D03*
X975000Y1307500D03*
X967500Y1340241D03*
X976858Y1656185D03*
X976898Y1662015D03*
X976948Y1659375D03*
X986720Y145206D03*
X988593Y189347D03*
X981445Y185389D03*
X982455Y264781D03*
Y275443D03*
X989227Y389311D03*
X992037Y485369D03*
X979091Y1251742D03*
Y1254742D03*
Y1248920D03*
Y1245920D03*
Y1257742D03*
X985318Y1656105D03*
X988078D03*
X979618Y1656185D03*
X985358Y1661935D03*
X988118D03*
X985408Y1659295D03*
X988168D03*
X979658Y1662015D03*
X979708Y1659375D03*
X995189Y263340D03*
Y274002D03*
X992915Y280389D03*
X1007083Y363461D03*
X996232Y424440D03*
X999304Y1282574D03*
Y1289215D03*
X999303Y1285693D03*
X1004418Y1656105D03*
X1007178D03*
X1004508Y1659295D03*
X1004458Y1661935D03*
X1008720Y145206D03*
X1020661Y146580D03*
X1023221Y191574D03*
X1019803Y218099D03*
X1017870Y294386D03*
X1009618Y396125D03*
X1021425Y404925D03*
X1013365Y433426D03*
X1008789Y488642D03*
Y493655D03*
X1012211Y547574D03*
X1015061D03*
X1015961Y554432D03*
X1007703Y759012D03*
X1007587Y800384D03*
Y802884D03*
Y811352D03*
Y813852D03*
Y822252D03*
Y824752D03*
Y833356D03*
Y835856D03*
Y844256D03*
X1021908Y1289124D03*
X1019314Y1289159D03*
X1017069Y1290346D03*
X1013500Y1312500D03*
X1013000Y1306500D03*
X1013500Y1325500D03*
X1011500Y1335000D03*
X1013500Y1344500D03*
X1007268Y1659295D03*
X1007218Y1661935D03*
X1023187Y146580D03*
X1027724Y397726D03*
X1030525Y391362D03*
X1027760Y451832D03*
X1022461Y558932D03*
X1027579D03*
X1032579Y559934D03*
X1025493Y768719D03*
X1035645Y773582D03*
X1033798Y1656675D03*
X1033748Y1659315D03*
X1040199Y49379D03*
X1040891Y406586D03*
X1045100Y427059D03*
X1045015Y444404D03*
X1041254Y523874D03*
X1043180Y547027D03*
X1040890Y735717D03*
X1050015Y756765D03*
Y760265D03*
X1045465Y776910D03*
X1050015Y767265D03*
X1045465Y783603D03*
X1041065Y795315D03*
X1045465Y807028D03*
Y813721D03*
Y820414D03*
X1041065Y832126D03*
X1045465Y850532D03*
Y843839D03*
Y857225D03*
X1041065Y868937D03*
X1045465Y880650D03*
Y887343D03*
Y894036D03*
X1041065Y905749D03*
X1045465Y917461D03*
Y924154D03*
Y930847D03*
X1041065Y942560D03*
X1045465Y954272D03*
Y967658D03*
Y960965D03*
Y974351D03*
Y981044D03*
Y987736D03*
Y994429D03*
Y1004469D03*
Y1041280D03*
Y1034587D03*
Y1047973D03*
Y1054666D03*
Y1061359D03*
Y1071398D03*
Y1078091D03*
X1041065Y1089804D03*
X1045465Y1101516D03*
Y1108209D03*
Y1114902D03*
X1041065Y1126615D03*
X1045465Y1138327D03*
Y1145020D03*
Y1151713D03*
X1041065Y1163426D03*
X1045465Y1175138D03*
Y1188524D03*
Y1181831D03*
X1041065Y1200237D03*
X1045465Y1211949D03*
Y1218642D03*
X1041065Y1237048D03*
X1045465Y1225335D03*
Y1248760D03*
Y1255453D03*
X1048684Y1350724D03*
X1051684D03*
X1050866Y1659548D03*
X1062199Y49379D03*
X1061456Y406560D03*
X1063614Y733409D03*
X1057057Y756765D03*
X1061607Y773563D03*
X1057057Y763765D03*
X1057207Y791969D03*
X1056157Y786949D03*
X1061607Y780256D03*
Y803681D03*
X1056157Y796988D03*
X1061607Y810374D03*
Y817067D03*
X1056157Y823760D03*
Y833799D03*
X1057207Y828780D03*
X1061607Y847185D03*
Y840492D03*
Y853878D03*
X1056157Y860571D03*
X1057207Y865591D03*
X1056157Y870610D03*
X1061607Y877303D03*
Y883996D03*
Y890689D03*
X1056157Y907422D03*
Y897382D03*
X1057207Y902402D03*
X1061607Y914114D03*
Y920807D03*
Y927500D03*
X1056157Y934193D03*
X1057207Y939213D03*
X1061607Y950925D03*
X1056157Y944233D03*
X1061607Y964311D03*
Y971004D03*
Y957618D03*
Y977697D03*
Y984390D03*
Y991083D03*
Y997776D03*
Y1004469D03*
Y1037933D03*
Y1044626D03*
Y1031240D03*
Y1051319D03*
Y1058012D03*
Y1074744D03*
Y1068051D03*
X1057207Y1086457D03*
X1056157Y1081437D03*
Y1091477D03*
X1061607Y1098170D03*
Y1104862D03*
X1056157Y1118248D03*
X1061607Y1111555D03*
Y1134981D03*
X1057207Y1123268D03*
X1056157Y1128288D03*
X1061607Y1141674D03*
Y1148366D03*
X1056157Y1155059D03*
Y1165099D03*
X1057207Y1160079D03*
X1061607Y1171792D03*
Y1178485D03*
X1056157Y1191870D03*
X1061607Y1185177D03*
X1056157Y1201910D03*
X1057207Y1196890D03*
X1061607Y1208603D03*
Y1215296D03*
Y1221988D03*
X1056157Y1238721D03*
X1057207Y1233701D03*
X1056157Y1228681D03*
X1061607Y1245414D03*
Y1252107D03*
X1060684Y1350724D03*
X1057684D03*
X1054684D03*
X1063751Y1653834D03*
X1064221Y1662726D03*
X1068221Y1662778D03*
X1068827Y389734D03*
X1074800Y391262D03*
X1077418Y411322D03*
Y416763D03*
Y421922D03*
X1081133Y461516D03*
X1071239Y479655D03*
X1081632Y648854D03*
X1079716Y756765D03*
Y760265D03*
Y767265D03*
X1075166Y776910D03*
Y783603D03*
X1070766Y795315D03*
X1075166Y807028D03*
Y813721D03*
Y820414D03*
X1070766Y832126D03*
X1075166Y850532D03*
Y843839D03*
Y857225D03*
X1070766Y868937D03*
X1075166Y880650D03*
Y887343D03*
Y894036D03*
X1070766Y905749D03*
X1075166Y917461D03*
Y924154D03*
Y930847D03*
X1070766Y942560D03*
X1075166Y954272D03*
Y967658D03*
Y960965D03*
Y974351D03*
Y981044D03*
Y987736D03*
Y994429D03*
Y1004469D03*
Y1034587D03*
Y1041280D03*
Y1047973D03*
Y1054666D03*
Y1061359D03*
Y1071398D03*
Y1078091D03*
X1070766Y1089804D03*
X1075166Y1101516D03*
Y1108209D03*
Y1114902D03*
X1070766Y1126615D03*
X1075166Y1138327D03*
Y1145020D03*
Y1151713D03*
X1070766Y1163426D03*
X1075166Y1175138D03*
Y1188524D03*
Y1181831D03*
X1070766Y1200237D03*
X1075166Y1211949D03*
Y1218642D03*
X1070766Y1237048D03*
X1075166Y1225335D03*
Y1248760D03*
Y1255453D03*
X1070949Y1337752D03*
X1067929Y1337702D03*
X1079215Y1357390D03*
X1076615D03*
X1071908Y1361660D03*
X1080889Y1367253D03*
X1076615Y1360497D03*
X1079215D03*
X1078459Y1367253D03*
Y1372853D03*
X1080889D03*
X1073733Y1388198D03*
X1068094Y1654099D03*
X1084199Y49379D03*
X1086936Y370532D03*
X1083583Y395195D03*
X1093722Y427960D03*
X1087000Y477500D03*
X1096473Y484391D03*
Y489391D03*
X1088730Y509362D03*
X1086758Y756765D03*
X1091308Y773563D03*
X1086758Y763765D03*
X1086908Y791969D03*
X1091308Y780256D03*
X1085858Y786949D03*
X1091308Y803681D03*
X1085858Y796988D03*
X1091308Y810374D03*
Y817067D03*
X1085858Y823760D03*
Y833799D03*
X1086908Y828780D03*
X1091308Y840492D03*
Y847185D03*
Y853878D03*
X1085858Y860571D03*
X1086908Y865591D03*
X1085858Y870610D03*
X1091308Y877303D03*
Y883996D03*
Y890689D03*
X1085858Y907422D03*
Y897382D03*
X1086908Y902402D03*
X1091308Y914114D03*
Y920807D03*
X1085858Y934193D03*
X1091308Y927500D03*
X1086908Y939213D03*
X1085858Y944233D03*
X1091308Y950925D03*
Y964311D03*
Y971004D03*
Y957618D03*
Y977697D03*
Y984390D03*
Y991083D03*
Y997776D03*
Y1004469D03*
Y1031240D03*
Y1037933D03*
Y1044626D03*
Y1051319D03*
Y1058012D03*
Y1074744D03*
Y1068051D03*
X1086908Y1086457D03*
X1085858Y1081437D03*
Y1091477D03*
X1091308Y1098170D03*
Y1104862D03*
X1085858Y1118248D03*
X1091308Y1111555D03*
Y1134981D03*
X1086908Y1123268D03*
X1085858Y1128288D03*
X1091308Y1141674D03*
Y1148366D03*
X1085858Y1155059D03*
Y1165099D03*
X1086908Y1160079D03*
X1091308Y1171792D03*
Y1178485D03*
X1085858Y1191870D03*
X1091308Y1185177D03*
X1085858Y1201910D03*
X1086908Y1196890D03*
X1091308Y1208603D03*
Y1215296D03*
Y1221988D03*
X1085858Y1238721D03*
Y1228681D03*
X1086908Y1233701D03*
X1091308Y1245414D03*
Y1252107D03*
X1095809Y1337824D03*
X1087015Y1357390D03*
X1095629Y1352252D03*
Y1349652D03*
Y1354852D03*
X1089515Y1357390D03*
X1091959Y1357406D03*
X1084415Y1357390D03*
X1081815D03*
X1092905Y1363394D03*
Y1360437D03*
X1083319Y1367253D03*
X1081815Y1360497D03*
X1084415D03*
X1081815Y1363454D03*
X1084415D03*
X1083319Y1372853D03*
X1083368Y1385268D03*
X1096469Y1643468D03*
X1090143Y1643625D03*
X1091026Y1653031D03*
X1092030Y1720841D03*
X1106199Y49379D03*
X1101942Y395361D03*
X1109416Y756765D03*
Y760265D03*
Y767265D03*
X1104866Y776910D03*
Y783603D03*
X1100466Y795315D03*
X1104866Y807028D03*
Y813721D03*
Y820414D03*
X1100466Y832126D03*
X1104866Y850532D03*
Y843839D03*
Y857225D03*
X1100466Y868937D03*
X1104866Y880650D03*
Y887343D03*
Y894036D03*
X1100466Y905749D03*
X1104866Y917461D03*
Y924154D03*
Y930847D03*
X1100466Y942560D03*
X1104866Y954272D03*
Y967658D03*
Y960965D03*
Y974351D03*
Y981044D03*
Y987736D03*
Y994429D03*
Y1004469D03*
Y1034587D03*
Y1041280D03*
Y1047973D03*
Y1054666D03*
Y1071398D03*
Y1061359D03*
Y1078091D03*
X1100466Y1089804D03*
X1104866Y1101516D03*
Y1108209D03*
Y1114902D03*
X1100466Y1126615D03*
X1104866Y1138327D03*
Y1145020D03*
Y1151713D03*
X1100466Y1163426D03*
X1104866Y1175138D03*
Y1188524D03*
Y1181831D03*
X1100466Y1200237D03*
X1104866Y1211949D03*
Y1218642D03*
X1100466Y1237048D03*
X1104866Y1225335D03*
Y1248760D03*
Y1255453D03*
X1103529Y1337792D03*
X1109289Y1337752D03*
X1098409Y1337824D03*
X1109215Y1357390D03*
X1098229Y1352252D03*
Y1349652D03*
X1096979Y1357352D03*
X1098229Y1354852D03*
X1104448Y1361680D03*
X1109215Y1360497D03*
X1111059Y1367253D03*
Y1372853D03*
X1103888Y1386721D03*
X1102230Y1384770D03*
X1105000Y1682132D03*
X1109521Y1724109D03*
X1113943Y452055D03*
X1116458Y756765D03*
X1121008Y773563D03*
X1116459Y763765D03*
X1116608Y791969D03*
X1121008Y780256D03*
X1115558Y786949D03*
X1121008Y803681D03*
X1115558Y796988D03*
X1121008Y810374D03*
Y817067D03*
X1115558Y823760D03*
Y833799D03*
X1116608Y828780D03*
X1121008Y847185D03*
Y840492D03*
Y853878D03*
X1115558Y860571D03*
X1116608Y865591D03*
X1115558Y870610D03*
X1121008Y877303D03*
Y883996D03*
Y890689D03*
X1115558Y907422D03*
Y897382D03*
X1116608Y902402D03*
X1121008Y914114D03*
Y920807D03*
X1115558Y934193D03*
X1121008Y927500D03*
X1116608Y939213D03*
X1115558Y944233D03*
X1121008Y950925D03*
Y964311D03*
Y971004D03*
Y957618D03*
Y977697D03*
Y984390D03*
Y991083D03*
Y997776D03*
Y1004469D03*
Y1031240D03*
Y1037933D03*
Y1044626D03*
Y1051319D03*
Y1058012D03*
Y1074744D03*
Y1068051D03*
X1116608Y1086457D03*
X1115558Y1081437D03*
Y1091477D03*
X1121008Y1098170D03*
Y1104862D03*
X1115558Y1118248D03*
X1121008Y1111555D03*
Y1134981D03*
X1116608Y1123268D03*
X1115558Y1128288D03*
X1121008Y1141674D03*
Y1148366D03*
X1115558Y1155059D03*
Y1165099D03*
X1116608Y1160079D03*
X1121008Y1171792D03*
Y1178485D03*
X1115558Y1191870D03*
X1121008Y1185177D03*
X1115558Y1201910D03*
X1116608Y1196890D03*
X1121008Y1208603D03*
Y1215296D03*
Y1221988D03*
X1115558Y1238721D03*
Y1228681D03*
X1116608Y1233701D03*
X1121008Y1245414D03*
Y1252107D03*
X1119615Y1357390D03*
X1122115D03*
X1124559Y1357406D03*
X1117015Y1357390D03*
X1111815D03*
X1114415D03*
X1117015Y1363454D03*
Y1360497D03*
X1115919Y1372853D03*
X1125505Y1363394D03*
Y1360437D03*
X1115919Y1367253D03*
X1113489D03*
X1114415Y1363454D03*
X1111815Y1360497D03*
X1114415D03*
X1113489Y1372853D03*
X1115968Y1385268D03*
X1117946Y1467955D03*
X1117828Y1473091D03*
X1118326Y1594118D03*
X1118004Y1584908D03*
X1113785Y1601462D03*
X1117263Y1601526D03*
X1115394Y1620306D03*
X1120376Y1641684D03*
X1125487Y1641754D03*
X1125771Y1652189D03*
X1120595Y1652037D03*
X1120200Y1646597D03*
X1116000Y1671029D03*
X1125732Y1666072D03*
X1120303Y1682055D03*
X1113948Y1714244D03*
X1128199Y49379D03*
X1142830Y53186D03*
X1139200Y380533D03*
Y385698D03*
X1127471Y404788D03*
X1132387Y615658D03*
X1139117Y756765D03*
Y760265D03*
Y767265D03*
X1134567Y776910D03*
Y783603D03*
X1130167Y795315D03*
X1134567Y807028D03*
Y813721D03*
Y820414D03*
X1130167Y832126D03*
X1134567Y850532D03*
Y843839D03*
Y857225D03*
X1130167Y868937D03*
X1134567Y880650D03*
Y887343D03*
Y894036D03*
X1130167Y905749D03*
X1134567Y917461D03*
Y924154D03*
Y930847D03*
X1130167Y942560D03*
X1134567Y954272D03*
Y967658D03*
Y960965D03*
Y974351D03*
Y981044D03*
Y987736D03*
Y994429D03*
Y1004469D03*
Y1034587D03*
Y1041280D03*
Y1047973D03*
Y1054666D03*
Y1061359D03*
Y1071398D03*
X1130167Y1089804D03*
X1134567Y1078091D03*
Y1101516D03*
Y1108209D03*
Y1114902D03*
X1130167Y1126615D03*
X1134567Y1138327D03*
Y1145020D03*
X1130167Y1163426D03*
X1134567Y1151713D03*
Y1175138D03*
Y1188524D03*
Y1181831D03*
X1130167Y1200237D03*
X1134567Y1211949D03*
Y1218642D03*
X1130167Y1237048D03*
X1134567Y1225335D03*
Y1248760D03*
Y1255453D03*
X1136219Y1337794D03*
X1133619D03*
X1130829Y1352252D03*
Y1349652D03*
Y1354852D03*
X1128229Y1352252D03*
Y1349652D03*
X1129579Y1357352D03*
X1128229Y1354852D03*
X1137218Y1361660D03*
X1136588Y1386721D03*
X1134930Y1384770D03*
X1137846Y1453487D03*
X1135043Y1553371D03*
X1137523Y1579453D03*
X1136173Y1573638D03*
X1131790Y1597984D03*
X1131832Y1607245D03*
X1132168Y1620860D03*
X1138752Y1624627D03*
X1130772Y1641753D03*
X1130684Y1646949D03*
X1130245Y1652189D03*
X1140117Y1671421D03*
X1132209Y1672033D03*
X1129230Y1666174D03*
X1137492Y1685240D03*
X1128934Y1688600D03*
X1150199Y49379D03*
X1155577Y73939D03*
X1147813Y492319D03*
X1146159Y756765D03*
X1150709Y773563D03*
X1146160Y763765D03*
X1146309Y791969D03*
X1145259Y786949D03*
X1150709Y780256D03*
X1145259Y796988D03*
X1150709Y803681D03*
Y810374D03*
Y817067D03*
X1146309Y828780D03*
X1145259Y823760D03*
Y833799D03*
X1150709Y840492D03*
Y847185D03*
X1146309Y865591D03*
X1145259Y860571D03*
X1150709Y853878D03*
X1145259Y870610D03*
X1150709Y877303D03*
Y883996D03*
Y890689D03*
X1145259Y907422D03*
X1146309Y902402D03*
X1145259Y897382D03*
X1150709Y914114D03*
Y920807D03*
X1145259Y934193D03*
X1146309Y939213D03*
X1150709Y927500D03*
X1145259Y944233D03*
X1150709Y950925D03*
Y964311D03*
Y971004D03*
Y957618D03*
Y977697D03*
Y984390D03*
Y991083D03*
Y997776D03*
Y1004469D03*
Y1031240D03*
Y1037933D03*
Y1044626D03*
Y1051319D03*
Y1058012D03*
Y1074744D03*
Y1068051D03*
X1146309Y1086457D03*
X1145259Y1081437D03*
Y1091477D03*
X1150709Y1098170D03*
Y1104862D03*
X1145259Y1118248D03*
X1150709Y1111555D03*
Y1134981D03*
X1146309Y1123268D03*
X1145259Y1128288D03*
X1150709Y1141674D03*
Y1148366D03*
X1145259Y1155059D03*
X1146309Y1160079D03*
X1145259Y1165099D03*
X1150709Y1171792D03*
Y1178485D03*
X1145259Y1191870D03*
X1150709Y1185177D03*
X1145259Y1201910D03*
X1146309Y1196890D03*
X1150709Y1208603D03*
Y1215296D03*
Y1221988D03*
X1145259Y1238721D03*
X1146309Y1233701D03*
X1145259Y1228681D03*
X1150709Y1245414D03*
Y1252107D03*
X1154839Y1337834D03*
X1145819D03*
X1143219D03*
X1152315Y1357390D03*
X1154815D03*
X1147115D03*
X1149715D03*
X1141915D03*
X1144515D03*
X1147115Y1360497D03*
X1149715Y1363454D03*
Y1360497D03*
X1147115Y1363454D03*
X1146189Y1372853D03*
X1148619D03*
Y1367253D03*
X1146189D03*
X1141915Y1360497D03*
X1144515D03*
X1143759Y1367253D03*
Y1372853D03*
X1148668Y1385268D03*
X1150458Y1433146D03*
X1144118Y1449628D03*
X1151384Y1556029D03*
X1143063Y1580334D03*
X1152186Y1570567D03*
X1149278Y1589453D03*
X1145060Y1588837D03*
X1141645Y1640017D03*
X1146316Y1649422D03*
X1143127Y1649068D03*
X1144107Y1671118D03*
X1146477Y1658441D03*
X1168687Y74202D03*
X1163113Y481691D03*
X1165589Y569118D03*
X1168818Y756765D03*
Y760265D03*
X1164268Y776910D03*
X1168818Y767265D03*
X1164268Y783603D03*
X1159868Y795315D03*
X1164268Y807028D03*
Y820414D03*
Y813721D03*
X1159868Y832126D03*
X1164268Y850532D03*
Y843839D03*
Y857225D03*
X1159868Y868937D03*
X1164268Y880650D03*
Y887343D03*
Y894036D03*
X1159868Y905749D03*
X1164268Y917461D03*
Y924154D03*
Y930847D03*
X1159868Y942560D03*
X1164268Y954272D03*
Y960965D03*
Y967658D03*
Y974351D03*
Y981044D03*
Y987736D03*
Y994429D03*
Y1004469D03*
Y1034587D03*
Y1041280D03*
Y1047973D03*
Y1054666D03*
Y1061359D03*
Y1071398D03*
X1159868Y1089804D03*
X1164268Y1078091D03*
Y1101516D03*
Y1108209D03*
Y1114902D03*
X1159868Y1126615D03*
X1164268Y1138327D03*
Y1145020D03*
X1159868Y1163426D03*
X1164268Y1151713D03*
Y1175138D03*
Y1181831D03*
Y1188524D03*
X1159868Y1200237D03*
X1164268Y1211949D03*
Y1218642D03*
X1159868Y1237048D03*
X1164268Y1225335D03*
Y1248760D03*
Y1255453D03*
X1167509Y1337884D03*
X1164909D03*
X1157439Y1337834D03*
X1160929Y1352252D03*
X1163529D03*
X1160929Y1349652D03*
X1163529D03*
X1162279Y1357352D03*
X1163529Y1354852D03*
X1157259Y1357406D03*
X1170138Y1361800D03*
X1158205Y1363394D03*
Y1360437D03*
X1169488Y1386721D03*
X1167830Y1384770D03*
X1161311Y1548204D03*
X1172523Y1573250D03*
X1160031Y1591163D03*
X1162144Y1658042D03*
X1159741Y1669759D03*
X1169187Y1687117D03*
X1174958Y-24648D03*
Y5352D03*
Y15352D03*
X1177429Y89556D03*
Y93556D03*
X1185952Y432202D03*
Y440202D03*
Y448202D03*
X1185707Y465272D03*
Y460202D03*
Y470392D03*
X1185117Y571807D03*
X1181445Y592868D03*
X1175860Y756765D03*
X1180410Y773563D03*
X1175860Y763765D03*
X1176010Y791969D03*
X1180410Y780256D03*
X1174960Y786949D03*
X1180410Y803681D03*
X1174960Y796988D03*
X1180410Y817067D03*
Y810374D03*
X1176010Y828780D03*
X1174960Y833799D03*
Y823760D03*
X1180410Y847185D03*
Y840492D03*
X1176010Y865591D03*
X1180410Y853878D03*
X1174960Y860571D03*
X1180410Y877303D03*
X1174960Y870610D03*
X1180410Y890689D03*
Y883996D03*
X1176010Y902402D03*
X1174960Y897382D03*
Y907422D03*
X1180410Y914114D03*
Y920807D03*
X1176010Y939213D03*
X1174960Y934193D03*
X1180410Y927500D03*
X1174960Y944233D03*
X1180410Y950925D03*
Y957618D03*
Y964311D03*
Y971004D03*
Y977697D03*
Y984390D03*
Y991083D03*
Y997776D03*
Y1004469D03*
Y1031240D03*
Y1037933D03*
Y1044626D03*
Y1051319D03*
Y1058012D03*
Y1068051D03*
Y1074744D03*
X1176010Y1086457D03*
X1174960Y1081437D03*
Y1091477D03*
X1180410Y1098170D03*
Y1104862D03*
X1174960Y1118248D03*
X1180410Y1111555D03*
X1176010Y1123268D03*
X1174960Y1128288D03*
X1180410Y1134981D03*
Y1141674D03*
Y1148366D03*
X1176010Y1160079D03*
X1174960Y1155059D03*
Y1165099D03*
X1180410Y1171792D03*
Y1178485D03*
X1174960Y1191870D03*
X1180410Y1185177D03*
X1176010Y1196890D03*
X1174960Y1201910D03*
X1180410Y1208603D03*
Y1215296D03*
Y1221988D03*
X1176010Y1233701D03*
X1174960Y1238721D03*
Y1228681D03*
X1180410Y1245414D03*
Y1252107D03*
X1182615Y1357390D03*
X1185215D03*
X1177415D03*
X1174815D03*
X1180015D03*
X1182615Y1363454D03*
Y1360497D03*
X1180015Y1363454D03*
X1174815Y1360497D03*
X1177415D03*
X1180015D03*
X1176659Y1367253D03*
Y1372853D03*
X1179089D03*
X1181519D03*
Y1367253D03*
X1179089D03*
X1181568Y1385268D03*
X1185000Y1396500D03*
Y1401000D03*
X1184100Y1410000D03*
X1185000Y1405500D03*
X1178400Y1433000D03*
X1181324Y1485895D03*
X1183234Y1483295D03*
Y1488495D03*
X1181314Y1492995D03*
X1176534D03*
X1174624Y1495595D03*
X1181314Y1498195D03*
X1176534D03*
X1180047Y1533247D03*
X1181853Y1561731D03*
X1172523Y1562350D03*
X1179187Y1666429D03*
X1175454Y1668046D03*
X1178932Y1686698D03*
X1185676Y1697249D03*
X1194199Y49379D03*
X1198694Y57015D03*
X1191488Y87125D03*
Y91125D03*
X1200518Y100875D03*
X1189701Y173187D03*
X1201157Y431875D03*
X1189540Y481691D03*
X1188192Y589263D03*
X1191646Y589567D03*
X1195729Y591022D03*
X1198519Y756765D03*
Y760265D03*
X1193969Y776910D03*
X1198519Y767265D03*
X1193969Y783603D03*
X1189569Y795315D03*
X1193969Y807028D03*
Y820414D03*
Y813721D03*
X1189569Y832126D03*
X1193969Y850532D03*
Y843839D03*
Y857225D03*
X1189569Y868937D03*
X1193969Y880650D03*
Y887343D03*
Y894036D03*
X1189569Y905749D03*
X1193969Y917461D03*
Y924154D03*
Y930847D03*
Y954272D03*
X1189569Y942560D03*
X1193969Y960965D03*
Y967658D03*
Y974351D03*
Y981044D03*
Y987736D03*
Y994429D03*
Y1004469D03*
Y1034587D03*
Y1041280D03*
Y1047973D03*
Y1054666D03*
Y1061359D03*
Y1071398D03*
X1189569Y1089804D03*
X1193969Y1078091D03*
Y1101516D03*
Y1108209D03*
Y1114902D03*
X1189569Y1126615D03*
X1193969Y1138327D03*
Y1145020D03*
X1189569Y1163426D03*
X1193969Y1151713D03*
Y1175138D03*
Y1181831D03*
Y1188524D03*
X1189569Y1200237D03*
X1193969Y1211949D03*
Y1218642D03*
X1189569Y1237048D03*
X1193969Y1225335D03*
Y1248760D03*
Y1255453D03*
X1196159Y1326549D03*
X1193659Y1326589D03*
Y1324049D03*
X1196259D03*
X1193659Y1321549D03*
X1196259D03*
X1199899Y1338065D03*
X1193829Y1352252D03*
X1196429D03*
X1193829Y1349652D03*
X1196429D03*
X1193829Y1354852D03*
X1190159Y1357406D03*
X1195179Y1357352D03*
X1196429Y1354852D03*
X1187715Y1357390D03*
X1191105Y1363394D03*
Y1360437D03*
X1200690Y1384572D03*
X1194000Y1418000D03*
X1187925Y1417000D03*
X1194000Y1428500D03*
Y1433000D03*
X1187925Y1440400D03*
X1188014Y1483295D03*
Y1488495D03*
X1194724Y1505295D03*
X1196634Y1502695D03*
Y1507895D03*
X1196127Y1583797D03*
X1195261Y1622884D03*
X1200217D03*
X1195050Y1620040D03*
X1195261Y1627876D03*
X1200217D03*
Y1654796D03*
X1195261D03*
X1200217Y1659788D03*
X1195261D03*
X1192903Y1666276D03*
X1189462Y1691366D03*
X1196767Y1712261D03*
X1196814Y1726261D03*
X1215528Y172395D03*
X1214156Y292066D03*
X1214856Y421018D03*
X1213866Y455376D03*
X1208400Y591631D03*
X1201440Y668138D03*
X1207177Y668115D03*
X1205561Y756765D03*
X1210111Y773563D03*
X1205561Y763765D03*
X1205711Y791969D03*
X1210111Y780256D03*
X1204661Y786949D03*
X1210111Y803681D03*
X1204661Y796988D03*
X1210111Y817067D03*
Y810374D03*
X1205711Y828780D03*
X1204661Y833799D03*
Y823760D03*
X1210111Y847185D03*
Y840492D03*
X1205711Y865591D03*
X1210111Y853878D03*
X1204661Y860571D03*
X1210111Y877303D03*
X1204661Y870610D03*
X1210111Y890689D03*
Y883996D03*
X1205711Y902402D03*
X1204661Y897382D03*
Y907422D03*
X1210111Y914114D03*
Y920807D03*
X1205711Y939213D03*
X1204661Y934193D03*
X1210111Y927500D03*
X1204661Y944233D03*
X1210111Y950925D03*
Y957618D03*
Y964311D03*
Y971004D03*
Y977697D03*
Y984390D03*
Y991083D03*
Y997776D03*
Y1004469D03*
Y1031240D03*
Y1037933D03*
Y1044626D03*
Y1051319D03*
Y1058012D03*
Y1068051D03*
Y1074744D03*
X1205711Y1086457D03*
X1204661Y1081437D03*
Y1091477D03*
X1210111Y1098170D03*
Y1104862D03*
X1204661Y1118248D03*
X1210111Y1111555D03*
X1205711Y1123268D03*
X1204661Y1128288D03*
X1210111Y1134981D03*
Y1141674D03*
Y1148366D03*
X1205711Y1160079D03*
X1204661Y1155059D03*
Y1165099D03*
X1210111Y1171792D03*
Y1178485D03*
X1204661Y1191870D03*
X1210111Y1185177D03*
X1205711Y1196890D03*
X1204661Y1201910D03*
X1210111Y1208603D03*
Y1215296D03*
Y1221988D03*
X1205711Y1233701D03*
X1204661Y1228681D03*
Y1238721D03*
X1210111Y1245414D03*
Y1252107D03*
X1205189Y1321492D03*
Y1323992D03*
X1202689Y1321492D03*
Y1324032D03*
X1211299Y1338105D03*
X1202399D03*
X1215415Y1357390D03*
X1212815D03*
X1210215D03*
X1207615D03*
X1202988Y1361490D03*
X1215415Y1363454D03*
Y1360497D03*
X1212815Y1363454D03*
Y1360497D03*
X1210215D03*
X1207615D03*
X1214319Y1372853D03*
X1211889D03*
X1209459D03*
Y1367253D03*
X1214319D03*
X1211889D03*
X1214368Y1385268D03*
X1202288Y1386721D03*
X1202484Y1402467D03*
X1203334Y1492995D03*
X1208114D03*
X1210034Y1483295D03*
X1214814D03*
X1208124Y1485895D03*
X1210034Y1488495D03*
X1214814D03*
X1201424Y1495595D03*
X1203334Y1498195D03*
X1208114D03*
X1201414Y1502695D03*
Y1507895D03*
X1200851Y1583797D03*
X1205576Y1583897D03*
X1210300Y1583697D03*
X1215025Y1583897D03*
X1207321Y1622884D03*
X1212277D03*
X1201291Y1637876D03*
Y1632884D03*
X1206247D03*
Y1637876D03*
X1213351D03*
Y1632884D03*
X1207321Y1627876D03*
X1212277D03*
X1207321Y1654796D03*
X1206247Y1649788D03*
X1201291D03*
X1212277Y1654796D03*
X1213351Y1649788D03*
X1206247Y1644796D03*
X1201291D03*
X1213351D03*
X1207321Y1659788D03*
X1212277D03*
X1204804Y1691375D03*
X1216199Y49379D03*
X1230156Y292066D03*
X1222094Y286948D03*
X1219463Y1338122D03*
X1229809Y1338105D03*
X1226629Y1352252D03*
X1229229D03*
X1226629Y1349652D03*
X1229229D03*
X1222959Y1357406D03*
X1227979Y1357352D03*
X1226629Y1354852D03*
X1229229D03*
X1220515Y1357390D03*
X1218015D03*
X1223905Y1363394D03*
Y1360437D03*
X1230134Y1492995D03*
X1228224Y1495595D03*
X1221524Y1505295D03*
X1230134Y1498195D03*
X1228214Y1502695D03*
X1223434D03*
Y1507895D03*
X1228214D03*
X1219749Y1583897D03*
X1224474Y1583697D03*
X1229198Y1583797D03*
X1219381Y1622884D03*
X1224337D03*
X1218307Y1637876D03*
Y1632884D03*
X1230367Y1637876D03*
X1225411D03*
X1230367Y1632884D03*
X1225411D03*
X1219381Y1627876D03*
X1224337D03*
Y1654796D03*
X1219381D03*
X1218307Y1649788D03*
X1225411D03*
X1230367D03*
X1218307Y1644796D03*
X1225411D03*
X1230367D03*
X1224337Y1659788D03*
X1219381D03*
X1219738Y1717011D03*
Y1731011D03*
X1236844Y-34348D03*
X1236829Y-36863D03*
X1236798Y-31476D03*
X1236813Y-28961D03*
X1240097Y-34334D03*
X1243122Y-35654D03*
X1240082Y-36849D03*
X1236877Y-26227D03*
X1236932Y-19948D03*
X1236942Y-13666D03*
X1236927Y-16181D03*
X1236892Y-23712D03*
X1240130Y-26213D03*
X1240194Y-19948D03*
X1240195Y-13652D03*
X1243220Y-14972D03*
X1240180Y-16167D03*
X1240145Y-23698D03*
X1243170Y-25018D03*
X1236932Y-9948D03*
Y52D03*
X1236942Y-3666D03*
X1236927Y-6181D03*
X1240194Y-9948D03*
Y52D03*
X1240195Y-3652D03*
X1243220Y-4972D03*
X1240180Y-6167D03*
X1236927Y13819D03*
X1236942Y16334D03*
X1236932Y10052D03*
X1236942Y6334D03*
X1236927Y3819D03*
X1240180Y13833D03*
X1243220Y15028D03*
X1240195Y16348D03*
X1240194Y10052D03*
X1240195Y6348D03*
X1243220Y5028D03*
X1240180Y3833D03*
X1236911Y21721D03*
X1236896Y19206D03*
X1236941Y26751D03*
X1236926Y24236D03*
X1243219Y25445D03*
X1240194Y26765D03*
X1240179Y24250D03*
X1238199Y49379D03*
X1245606Y1314351D03*
Y1311244D03*
X1240899Y1315460D03*
X1240240Y1339578D03*
X1232409Y1338105D03*
X1242500Y1430075D03*
X1237100Y1442500D03*
X1242500Y1437075D03*
X1234924Y1485895D03*
X1241614Y1483295D03*
X1236834D03*
X1241614Y1488495D03*
X1236834D03*
X1234914Y1492995D03*
Y1498195D03*
X1233923Y1583897D03*
X1238647D03*
X1243372D03*
X1231441Y1622884D03*
X1236397D03*
X1243501D03*
X1237471Y1637876D03*
Y1632884D03*
X1242427Y1637876D03*
Y1632884D03*
X1236397Y1627876D03*
X1231441D03*
X1243501D03*
X1231441Y1654796D03*
X1236397D03*
X1237471Y1649788D03*
X1243501Y1654796D03*
X1242427Y1649788D03*
X1237471Y1644796D03*
X1242427D03*
X1231441Y1659788D03*
X1236397D03*
X1243501D03*
X1260199Y49379D03*
X1256064Y101100D03*
X1254094Y286948D03*
X1245825Y305275D03*
X1260227Y407128D03*
Y411128D03*
X1248902Y470733D03*
X1257016Y467253D03*
X1246490Y483302D03*
X1257450Y1291721D03*
X1260050D03*
X1249650D03*
X1247050D03*
X1258506Y1311244D03*
X1256006D03*
X1253406Y1314351D03*
X1250806D03*
X1253406Y1311244D03*
X1250806D03*
X1248206Y1314351D03*
Y1311244D03*
X1252310Y1321107D03*
X1249880D03*
X1252310Y1326707D03*
X1253406Y1317308D03*
X1250806D03*
X1247450Y1326707D03*
Y1321107D03*
X1249880Y1326707D03*
X1252359Y1339122D03*
X1252315Y1417085D03*
X1254905Y1417026D03*
X1256934Y1492995D03*
X1255024Y1495595D03*
X1248324Y1505295D03*
X1256934Y1498195D03*
X1255014Y1502695D03*
X1250234D03*
X1255014Y1507895D03*
X1250234D03*
X1248096Y1583897D03*
X1252820Y1583697D03*
X1257544Y1583897D03*
X1248457Y1622884D03*
X1255561D03*
X1254487Y1637876D03*
Y1632884D03*
X1249531Y1637876D03*
Y1632884D03*
X1248457Y1627876D03*
X1255561D03*
X1248457Y1654796D03*
X1254487Y1649788D03*
X1249531D03*
X1255561Y1654796D03*
X1254487Y1644796D03*
X1249531D03*
X1248657Y1659588D03*
X1255561Y1659788D03*
X1266146Y121022D03*
X1263582Y164051D03*
Y160051D03*
Y180551D03*
Y176051D03*
Y172051D03*
Y168051D03*
Y185051D03*
X1270094Y286948D03*
X1262156Y292066D03*
X1270670Y1291624D03*
X1268070D03*
X1261896Y1314291D03*
X1260950Y1311260D03*
X1267220Y1306106D03*
Y1308706D03*
Y1303506D03*
X1265970Y1311206D03*
X1264620Y1303506D03*
Y1306106D03*
Y1308706D03*
X1273869Y1315300D03*
X1261896Y1317248D03*
X1273175Y1340547D03*
X1271517Y1338596D03*
X1275124Y1485895D03*
X1261724D03*
X1263634Y1483295D03*
X1268414D03*
X1263634Y1488495D03*
X1268414D03*
X1261714Y1492995D03*
Y1498195D03*
X1262269Y1583897D03*
X1266993Y1583797D03*
X1267621Y1622884D03*
X1260517D03*
X1272577D03*
X1261591Y1637876D03*
X1266547D03*
X1261591Y1632884D03*
X1266547D03*
X1273651Y1637876D03*
Y1632790D03*
X1267621Y1627876D03*
X1260517D03*
X1272577D03*
X1260517Y1654796D03*
X1267621D03*
X1266547Y1649788D03*
X1261591D03*
X1272577Y1654796D03*
X1273651Y1649788D03*
X1266547Y1644796D03*
X1261591D03*
X1273651D03*
X1260517Y1659788D03*
X1267621D03*
X1272577D03*
X1282199Y49379D03*
X1278111Y150030D03*
X1285391Y142553D03*
X1286094Y286948D03*
X1278156Y292066D03*
X1277598Y404428D03*
X1282165Y408987D03*
X1288202Y405741D03*
X1288902Y1311216D03*
X1286302Y1314323D03*
X1283702D03*
X1286302Y1311216D03*
X1283702D03*
X1278502Y1314323D03*
X1281102D03*
Y1311216D03*
X1278502D03*
X1285206Y1326679D03*
X1286302Y1317280D03*
X1283702D03*
X1285206Y1321079D03*
X1282776D03*
Y1326679D03*
X1280346Y1321079D03*
Y1326679D03*
X1285255Y1339094D03*
X1277034Y1483295D03*
X1281814D03*
X1277034Y1488495D03*
X1281814D03*
X1284510Y1556953D03*
X1278012Y1581563D03*
X1279681Y1622884D03*
X1284637D03*
X1278607Y1637876D03*
Y1632790D03*
X1285711Y1637876D03*
Y1632884D03*
X1279681Y1627876D03*
X1284637D03*
X1279681Y1654796D03*
X1278607Y1649788D03*
X1284637Y1654796D03*
X1285711Y1649788D03*
X1278607Y1644796D03*
X1285711D03*
X1279681Y1659788D03*
X1284637D03*
X1304199Y49379D03*
X1300668Y125739D03*
Y133739D03*
Y129739D03*
X1306431Y149330D03*
X1300668Y145739D03*
X1292082Y166051D03*
Y162051D03*
Y171551D03*
Y184051D03*
X1302094Y298066D03*
Y286948D03*
X1294156Y292066D03*
X1293277Y401125D03*
X1296228Y408125D03*
X1299076Y530023D03*
X1297487Y590607D03*
X1302890Y1291759D03*
X1298350Y1291721D03*
X1295750D03*
X1300116Y1306078D03*
Y1303478D03*
Y1308678D03*
X1298866Y1311178D03*
X1294792Y1314263D03*
X1297516Y1306078D03*
Y1303478D03*
Y1308678D03*
X1291402Y1311216D03*
X1293846Y1311232D03*
X1294792Y1317220D03*
X1304421Y1338539D03*
X1304596Y1492995D03*
X1302686Y1495595D03*
X1304596Y1498195D03*
X1291819Y1563595D03*
X1294319D03*
X1300560Y1554261D03*
X1291741Y1622884D03*
X1296697D03*
X1303801D03*
X1290667Y1637876D03*
Y1632884D03*
X1297771Y1637876D03*
Y1632884D03*
X1302727Y1637876D03*
Y1632884D03*
X1296697Y1627876D03*
X1291741D03*
X1303801D03*
X1291741Y1654796D03*
X1296697D03*
X1297771Y1649788D03*
X1290667D03*
X1303801Y1654796D03*
X1302727Y1649788D03*
X1297771Y1644796D03*
X1290667D03*
X1302727D03*
X1291741Y1659788D03*
X1296697D03*
X1303801D03*
X1306449Y92185D03*
X1306431Y152830D03*
X1310156Y292066D03*
X1305600Y1291759D03*
X1316606Y1314266D03*
Y1311159D03*
X1314006Y1314266D03*
Y1311159D03*
X1319206Y1314266D03*
Y1311159D03*
X1311406Y1314266D03*
Y1311159D03*
X1306799Y1315440D03*
X1315680Y1326622D03*
X1318110D03*
X1316606Y1317223D03*
X1319206D03*
X1318110Y1321022D03*
X1315680D03*
X1313250D03*
Y1326622D03*
X1318159Y1339037D03*
X1306079Y1340490D03*
X1314580Y1425240D03*
X1310580D03*
X1318580D03*
X1309386Y1485895D03*
X1311296Y1483295D03*
X1316076D03*
X1311296Y1488495D03*
X1316076D03*
X1309376Y1492995D03*
Y1498195D03*
X1308290Y1533380D03*
X1309423Y1543800D03*
Y1547420D03*
Y1551040D03*
X1309915Y1561731D03*
X1308757Y1622884D03*
X1315861D03*
X1309831Y1637876D03*
Y1632884D03*
X1314787Y1637876D03*
Y1632884D03*
X1308757Y1627876D03*
X1315861D03*
X1308757Y1654796D03*
X1309831Y1649788D03*
X1315861Y1654796D03*
X1314787Y1649788D03*
X1309831Y1644796D03*
X1314787D03*
X1308757Y1659788D03*
X1315861D03*
X1326199Y49379D03*
X1334156Y292066D03*
X1326094Y286948D03*
X1330277Y857388D03*
X1329477Y1222158D03*
X1331202Y1211488D03*
X1332680Y1291861D03*
X1330080D03*
X1333020Y1308621D03*
X1331770Y1311121D03*
X1333020Y1306021D03*
Y1303421D03*
X1330420Y1306021D03*
Y1303421D03*
Y1308621D03*
X1327696Y1314206D03*
X1321806Y1311159D03*
X1324306D03*
X1326750Y1311175D03*
X1327696Y1317163D03*
X1334580Y1425240D03*
X1330580D03*
X1326580D03*
X1322580D03*
X1331396Y1492995D03*
X1322786Y1505295D03*
X1329486Y1495595D03*
X1331396Y1498195D03*
X1324696Y1502695D03*
X1329476D03*
X1324696Y1507895D03*
X1329476D03*
X1328913Y1583797D03*
X1333638Y1583897D03*
X1324189Y1583797D03*
X1327921Y1622884D03*
X1320817D03*
X1332877D03*
X1321891Y1637876D03*
X1326847D03*
X1321891Y1632884D03*
X1326847D03*
X1333951Y1637876D03*
Y1632884D03*
X1327921Y1627876D03*
X1320817D03*
X1332877D03*
X1320817Y1654796D03*
X1327921D03*
X1326847Y1649788D03*
X1321891D03*
X1332877Y1654796D03*
X1333951Y1649788D03*
X1326847Y1644796D03*
X1321891D03*
X1333951D03*
X1320817Y1659788D03*
X1327921D03*
X1332877D03*
X1348199Y49379D03*
X1351750Y72826D03*
X1339840Y72860D03*
X1342094Y286948D03*
X1339347Y857388D03*
X1337975Y1177999D03*
X1338142Y1181642D03*
X1338440Y1291949D03*
X1335670Y1291899D03*
X1346806Y1311359D03*
X1349406D03*
X1346806Y1314466D03*
X1349406D03*
X1344206Y1311359D03*
Y1314466D03*
X1339429Y1315570D03*
X1348480Y1326822D03*
X1349406Y1317423D03*
X1346050Y1321222D03*
Y1326822D03*
X1348480Y1321222D03*
X1338879Y1340690D03*
X1337221Y1338739D03*
X1346580Y1425240D03*
X1342580D03*
X1338580D03*
X1336176Y1492995D03*
X1338096Y1483295D03*
X1342876D03*
X1336186Y1485895D03*
X1338096Y1488495D03*
X1342876D03*
X1349586Y1505295D03*
X1336176Y1498195D03*
X1343087Y1583897D03*
X1347811D03*
X1338362Y1583697D03*
X1339981Y1622884D03*
X1344937D03*
X1338907Y1637876D03*
Y1632884D03*
X1346011Y1637876D03*
Y1632884D03*
X1339981Y1627876D03*
X1344937D03*
X1339981Y1654796D03*
X1338907Y1649788D03*
X1344937Y1654796D03*
X1346011Y1649788D03*
X1338907Y1644796D03*
X1346011D03*
X1339981Y1659788D03*
X1344937D03*
X1361550Y67264D03*
X1350156Y292066D03*
X1358094Y286948D03*
X1354257Y675765D03*
X1364490Y1293694D03*
X1361830Y1291809D03*
X1360496Y1314406D03*
X1363220Y1308821D03*
X1364570Y1311321D03*
X1363220Y1306221D03*
Y1303621D03*
X1359550Y1311375D03*
X1352006Y1311359D03*
X1357106D03*
X1354606D03*
X1352006Y1314466D03*
X1360496Y1317363D03*
X1350910Y1326822D03*
X1352006Y1317423D03*
X1350910Y1321222D03*
X1350959Y1339237D03*
X1362580Y1425240D03*
X1358580D03*
X1354580D03*
X1350580D03*
X1362986Y1485895D03*
X1364896Y1483295D03*
Y1488495D03*
X1358196Y1492995D03*
X1362976D03*
X1356286Y1495595D03*
X1358196Y1498195D03*
X1362976D03*
X1356276Y1502695D03*
X1351496D03*
X1356276Y1507895D03*
X1351496D03*
X1357260Y1583797D03*
X1361985Y1583897D03*
X1352536Y1583697D03*
X1352041Y1622884D03*
X1356997D03*
X1364101D03*
X1350967Y1637876D03*
Y1632884D03*
X1358071Y1637876D03*
Y1632884D03*
X1363027Y1637876D03*
Y1632884D03*
X1356997Y1627876D03*
X1352041D03*
X1364101D03*
X1352041Y1654796D03*
X1356997D03*
X1358071Y1649788D03*
X1350967D03*
X1364101Y1654796D03*
X1363027Y1649788D03*
X1358071Y1644796D03*
X1350967D03*
X1363027D03*
X1352041Y1659788D03*
X1356997D03*
X1364101D03*
X1370199Y49379D03*
X1371259Y98000D03*
X1366156Y292066D03*
X1377862Y485552D03*
Y511052D03*
X1368305Y1307340D03*
X1365820Y1308821D03*
X1368305Y1309840D03*
X1365820Y1306221D03*
Y1303621D03*
X1372149Y1334890D03*
X1379388Y1330690D03*
Y1333797D03*
X1378632Y1340553D03*
X1376788Y1330690D03*
Y1333797D03*
X1378632Y1346153D03*
X1371422Y1359024D03*
X1368922D03*
X1379101Y1418621D03*
X1368299Y1425240D03*
X1372164Y1423810D03*
X1375341Y1421268D03*
X1369676Y1483295D03*
Y1488495D03*
X1376386Y1505295D03*
X1378296Y1502695D03*
Y1507895D03*
X1376158Y1583897D03*
X1366709D03*
X1371434D03*
X1369057Y1622884D03*
X1376161D03*
X1370131Y1637876D03*
Y1632790D03*
X1375087Y1637876D03*
Y1632790D03*
X1369057Y1627876D03*
X1376161D03*
X1369057Y1654796D03*
X1370131Y1649788D03*
X1376161Y1654796D03*
X1375087Y1649788D03*
X1370131Y1644796D03*
X1375087D03*
X1369057Y1659788D03*
X1376161D03*
X1392199Y49379D03*
X1389688Y1330690D03*
X1392132Y1330706D03*
X1393078Y1333737D03*
Y1336694D03*
X1383492Y1340553D03*
X1381062D03*
X1381988Y1336754D03*
X1384588D03*
X1387188Y1330690D03*
X1381988D03*
Y1333797D03*
X1384588Y1330690D03*
Y1333797D03*
X1383541Y1358568D03*
X1381062Y1346153D03*
X1383492D03*
X1383284Y1415973D03*
X1387308Y1413643D03*
X1392021Y1410360D03*
X1389786Y1485895D03*
X1391696Y1483295D03*
Y1488495D03*
X1384996Y1492995D03*
X1389776D03*
X1383086Y1495595D03*
X1384996Y1498195D03*
X1389776D03*
X1383076Y1502695D03*
Y1507895D03*
X1390331Y1583897D03*
X1380882Y1583697D03*
X1385606Y1583897D03*
X1381117Y1622884D03*
X1382191Y1637876D03*
X1387147D03*
X1382191Y1632884D03*
X1387147D03*
X1381117Y1627876D03*
Y1654796D03*
X1382191Y1649788D03*
X1387147D03*
X1382191Y1644796D03*
X1387147D03*
X1392068Y1667907D03*
X1381918D03*
X1381117Y1659788D03*
X1387620Y1721418D03*
X1385061D03*
X1403500Y458377D03*
X1402452Y642825D03*
X1405716Y1310618D03*
X1401740Y1311980D03*
X1399240D03*
X1408690Y1324803D03*
X1396302Y1328152D03*
Y1325552D03*
X1398902Y1328152D03*
Y1325552D03*
X1396302Y1322952D03*
X1398902D03*
X1401406Y1334918D03*
X1397652Y1330652D03*
X1398375Y1403688D03*
X1401764Y1399928D03*
X1405207Y1395480D03*
X1408543Y1391826D03*
X1395463Y1406918D03*
X1403186Y1485895D03*
X1405096Y1483295D03*
X1396476D03*
X1405096Y1488495D03*
X1396476D03*
X1409456Y1537872D03*
X1406074Y1581563D03*
X1395055Y1583797D03*
X1398058Y1619683D03*
X1409660Y1619853D03*
X1397367Y1639951D03*
X1402425Y1649532D03*
X1414199Y49379D03*
X1414000Y460362D03*
X1415426Y1042765D03*
Y1038765D03*
X1424561Y1305566D03*
X1420690Y1324803D03*
X1417690D03*
X1414690D03*
X1411690D03*
X1424163Y1373240D03*
X1411508Y1388384D03*
X1414950Y1384942D03*
X1417491Y1381183D03*
X1420774Y1377106D03*
X1409876Y1483295D03*
Y1488495D03*
X1423735Y1536715D03*
X1412572Y1556953D03*
X1421232Y1606126D03*
X1422914Y1601663D03*
X1421392Y1621706D03*
X1416357Y1644027D03*
X1420042Y1649716D03*
X1433817Y-34648D03*
Y-4648D03*
Y5352D03*
X1436199Y49379D03*
X1434513Y106950D03*
X1439232Y596291D03*
X1425437Y1308184D03*
X1426202Y1310752D03*
X1427314Y1313482D03*
X1428458Y1316481D03*
X1429517Y1319447D03*
X1430312Y1322412D03*
X1431106Y1325219D03*
X1426441Y1369427D03*
X1428559Y1365296D03*
X1430465Y1361060D03*
X1438798Y1495595D03*
X1430431Y1563595D03*
X1427931D03*
X1424971Y1566764D03*
Y1564264D03*
X1435584Y1596545D03*
X1430075Y1613904D03*
X1430319Y1623504D03*
X1425390Y1635496D03*
X1433327Y1643287D03*
X1446869Y105129D03*
X1451353Y116158D03*
X1443551Y539318D03*
Y535318D03*
X1453345Y1015473D03*
Y1019016D03*
Y1022559D03*
X1445498Y1485895D03*
X1447408Y1483295D03*
X1452188D03*
X1447408Y1488495D03*
X1452188D03*
X1445488Y1492995D03*
X1440708D03*
X1445488Y1498195D03*
X1440708D03*
X1444200Y1533240D03*
X1445535Y1551040D03*
Y1547420D03*
Y1543800D03*
X1446027Y1561731D03*
X1445500Y1611500D03*
X1448500Y1601000D03*
X1442579Y1673303D03*
X1447579D03*
X1452579D03*
X1453950Y1681450D03*
X1458199Y49379D03*
X1459682Y450372D03*
X1468395Y487582D03*
X1464257Y552977D03*
Y564977D03*
X1468257Y696265D03*
X1460926Y1015473D03*
X1467926D03*
X1460926Y1019016D03*
Y1022559D03*
X1467926Y1019016D03*
Y1022559D03*
X1467508Y1492995D03*
X1458898Y1505295D03*
X1465598Y1495595D03*
X1467508Y1498195D03*
X1460808Y1502695D03*
X1465588D03*
X1460808Y1507895D03*
X1465588D03*
X1465025Y1583797D03*
X1460301D03*
X1464391Y1622884D03*
X1459435D03*
X1465465Y1637876D03*
Y1632884D03*
X1459435Y1627876D03*
X1464391D03*
Y1654796D03*
X1465465Y1649788D03*
Y1644796D03*
X1459435Y1654796D03*
X1464391Y1659788D03*
X1466500Y1666000D03*
X1469034Y1667794D03*
X1459435Y1659788D03*
X1456852Y1673320D03*
X1466599Y1679401D03*
X1466260Y1675155D03*
X1460457Y1685160D03*
X1480199Y49379D03*
X1483820Y122713D03*
X1482257Y552977D03*
Y560477D03*
Y567977D03*
X1481934Y699670D03*
X1480300Y697750D03*
X1472288Y1492995D03*
X1474208Y1483295D03*
X1478988D03*
X1472298Y1485895D03*
X1474208Y1488495D03*
X1478988D03*
X1472288Y1498195D03*
X1479199Y1583897D03*
X1483923D03*
X1469750D03*
X1474474Y1583697D03*
X1476451Y1622884D03*
X1471495D03*
X1483555D03*
X1470421Y1632884D03*
Y1637876D03*
X1482481D03*
X1477525D03*
X1482481Y1632884D03*
X1477525D03*
X1471495Y1627876D03*
X1483555D03*
X1476451D03*
X1471495Y1654796D03*
X1470421Y1649788D03*
X1476451Y1654796D03*
X1483555D03*
X1482481Y1649788D03*
X1477525D03*
X1470421Y1644796D03*
X1477525D03*
X1482481D03*
X1471495Y1659788D03*
X1476451D03*
X1483555D03*
X1471616Y1670098D03*
X1479375Y1685984D03*
X1495539Y131237D03*
X1492237Y123842D03*
X1489757Y552977D03*
X1497257D03*
Y560477D03*
X1489757Y567977D03*
X1497257D03*
X1494371Y594462D03*
X1492673Y828513D03*
X1494386Y1178743D03*
X1499098Y1485895D03*
X1494308Y1492995D03*
X1499088D03*
X1492398Y1495595D03*
X1485698Y1505295D03*
X1494308Y1498195D03*
X1499088D03*
X1492388Y1502695D03*
X1487608D03*
X1492388Y1507895D03*
X1487608D03*
X1493372Y1583797D03*
X1498097Y1583897D03*
X1488648Y1583697D03*
X1488511Y1622884D03*
X1495615D03*
X1494541Y1637876D03*
X1489585D03*
X1494541Y1632884D03*
X1489585D03*
X1488511Y1627876D03*
X1495615D03*
X1488511Y1654796D03*
X1495615D03*
X1489585Y1649788D03*
X1494541D03*
X1489585Y1644796D03*
X1494541D03*
X1488511Y1659788D03*
X1495615D03*
X1502199Y49379D03*
X1514576Y219730D03*
X1513348Y253954D03*
X1500757Y537438D03*
X1504757Y537378D03*
X1508757Y537456D03*
X1512757Y537477D03*
X1513382Y697750D03*
X1499243Y803513D03*
X1501730Y811872D03*
X1501338Y825147D03*
X1513470Y1178265D03*
X1504470D03*
X1505788Y1483295D03*
X1501008D03*
X1505788Y1488495D03*
X1501008D03*
X1512498Y1505295D03*
X1512270Y1583897D03*
X1502821D03*
X1507546D03*
X1500571Y1622884D03*
X1512631D03*
X1507675D03*
X1501645Y1637876D03*
Y1632884D03*
X1506601Y1637876D03*
Y1632884D03*
X1513705Y1637876D03*
Y1632884D03*
X1500571Y1627876D03*
X1512631D03*
X1507675D03*
X1500571Y1654796D03*
X1501645Y1649788D03*
X1507675Y1654796D03*
X1512631D03*
X1513705Y1649788D03*
X1506601D03*
X1501645Y1644796D03*
X1513705D03*
X1506601D03*
X1500571Y1659788D03*
X1507675D03*
X1512831Y1659588D03*
X1524124Y47570D03*
X1522917Y119912D03*
X1529384Y201245D03*
X1516452Y249724D03*
X1514900Y251839D03*
X1515016Y699670D03*
X1515192Y814294D03*
X1525898Y1485895D03*
X1527808Y1483295D03*
Y1488495D03*
X1521108Y1492995D03*
X1525888D03*
X1525898Y1505295D03*
X1519198Y1495595D03*
X1521108Y1498195D03*
X1525888D03*
X1519188Y1502695D03*
X1527808D03*
X1514408D03*
X1519188Y1507895D03*
X1514408D03*
X1526443Y1583897D03*
X1516994Y1583697D03*
X1521718Y1583897D03*
X1524691Y1622884D03*
X1519735D03*
X1518661Y1637876D03*
Y1632884D03*
X1525765Y1637876D03*
Y1632884D03*
X1519735Y1627876D03*
X1524691D03*
X1518661Y1649788D03*
X1524691Y1654796D03*
X1519735D03*
X1525765Y1649788D03*
X1518661Y1644796D03*
X1525765D03*
X1524991Y1659788D03*
X1519735D03*
X1530064Y-27930D03*
X1530049Y-30445D03*
X1533317Y-27916D03*
X1536342Y-29236D03*
X1533302Y-30431D03*
X1530048Y-20028D03*
X1530063Y-17513D03*
X1530018Y-25058D03*
X1530033Y-22543D03*
X1533301Y-20014D03*
X1533316Y-17499D03*
X1536341Y-18819D03*
X1543862Y75343D03*
X1539756Y71839D03*
X1534776D03*
X1539756Y66847D03*
X1534776D03*
X1532866Y69340D03*
X1536542Y300819D03*
Y304819D03*
X1539693Y535212D03*
X1542902Y543641D03*
X1540850Y1240863D03*
X1539298Y1485895D03*
X1541208Y1483295D03*
X1532588D03*
X1541208Y1488495D03*
X1532588D03*
X1542186Y1581563D03*
X1531167Y1583797D03*
X1536751Y1622884D03*
X1531795D03*
X1530721Y1637876D03*
Y1632884D03*
X1537825Y1637876D03*
X1542781D03*
X1537825Y1632790D03*
X1542781D03*
X1531795Y1627876D03*
X1536751D03*
X1531795Y1654796D03*
X1530721Y1649788D03*
X1536751Y1654796D03*
X1542781Y1649788D03*
X1537825D03*
X1530721Y1644796D03*
X1542781D03*
X1537825D03*
X1531795Y1659788D03*
X1536751D03*
X1550965Y3001D03*
X1555568Y17045D03*
Y22037D03*
X1553601Y19541D03*
X1555452Y25977D03*
X1553452Y23981D03*
X1548496D03*
X1546496Y25977D03*
X1554520Y37106D03*
X1547434D03*
X1554520Y48720D03*
X1547434D03*
X1556776Y71839D03*
X1550756Y72850D03*
X1545776D03*
X1554866Y69340D03*
X1556776Y66847D03*
X1550756Y77842D03*
X1545776D03*
X1552981Y220826D03*
X1555481Y218326D03*
X1553913Y298119D03*
X1558480Y302678D03*
X1545960Y565162D03*
X1551887Y606938D03*
X1555570Y1235968D03*
X1555367Y1248078D03*
X1555303Y1242557D03*
X1547062Y1258468D03*
X1553811Y1264488D03*
X1545988Y1483295D03*
Y1488495D03*
X1548684Y1556953D03*
X1555993Y1563595D03*
X1558493D03*
X1548811Y1622884D03*
X1543855D03*
X1555915D03*
X1549885Y1637876D03*
X1554841D03*
X1549885Y1632884D03*
X1554841D03*
X1543855Y1627876D03*
X1548811D03*
X1555915D03*
X1543855Y1654796D03*
X1555915D03*
X1548811D03*
X1554841Y1649788D03*
X1549885D03*
X1554841Y1644796D03*
X1549885D03*
X1543855Y1659788D03*
X1555915D03*
X1548811D03*
X1572965Y3001D03*
X1569742Y17045D03*
X1560548D03*
X1567774Y19541D03*
X1569742Y22037D03*
X1560548D03*
X1562669Y23981D03*
X1567625D03*
X1560669Y25977D03*
X1569625D03*
X1562557Y19541D03*
X1561607Y37106D03*
X1568693D03*
Y48720D03*
X1561607D03*
X1572756Y72847D03*
X1561756Y71839D03*
X1565866Y75340D03*
X1567776Y72847D03*
X1561756Y66847D03*
X1572756Y77839D03*
X1567776D03*
X1564517Y299432D03*
X1569592Y294816D03*
X1572283Y301816D03*
X1562995Y789522D03*
X1569518Y806684D03*
X1564267Y1253158D03*
X1573560Y1485895D03*
X1573550Y1492995D03*
X1568770D03*
X1566860Y1495595D03*
X1573550Y1498195D03*
X1568770D03*
X1572230Y1533000D03*
X1573597Y1543800D03*
Y1547420D03*
Y1551040D03*
X1564839Y1554561D03*
X1560871Y1622884D03*
X1572931D03*
X1567975D03*
X1561945Y1637876D03*
Y1632884D03*
X1566901Y1637876D03*
Y1632884D03*
X1560871Y1627876D03*
X1572931D03*
X1567975D03*
X1560871Y1654796D03*
X1561945Y1649788D03*
X1567975Y1654796D03*
X1572931D03*
X1566901Y1649788D03*
X1561945Y1644796D03*
X1566901D03*
X1560871Y1659788D03*
X1567975D03*
X1572931D03*
X1583915Y17045D03*
X1574722D03*
X1581947Y19541D03*
X1583915Y22037D03*
X1576730Y19541D03*
X1574722Y22037D03*
X1576842Y23981D03*
X1581798D03*
X1574842Y25977D03*
X1583798D03*
X1575780Y37106D03*
X1582867D03*
Y48720D03*
X1575780D03*
X1587866Y75340D03*
X1578776Y71839D03*
X1583756D03*
X1576866Y69340D03*
X1578776Y66847D03*
X1583756D03*
X1574546Y251294D03*
X1575370Y1252770D03*
X1581327Y1252858D03*
X1586835Y1271918D03*
X1583007Y1288958D03*
X1577913Y1341623D03*
X1575504Y1356103D03*
X1578336D03*
X1575470Y1483295D03*
X1580250D03*
X1575470Y1488495D03*
X1580250D03*
X1586960Y1505295D03*
X1574089Y1561731D03*
X1588363Y1583797D03*
X1584991Y1622884D03*
X1580035D03*
X1574005Y1637876D03*
Y1632884D03*
X1578961Y1637876D03*
Y1632884D03*
X1586065Y1637876D03*
Y1632884D03*
X1580035Y1627876D03*
X1584991D03*
X1574005Y1649788D03*
X1580035Y1654796D03*
X1578961Y1649788D03*
X1584991Y1654796D03*
X1586065Y1649788D03*
X1574005Y1644796D03*
X1578961D03*
X1586065D03*
X1580035Y1659788D03*
X1584991D03*
X1594965Y3001D03*
X1603072Y17045D03*
X1598092D03*
X1588895D03*
X1603072Y22037D03*
X1598092D03*
X1596121Y19541D03*
X1590903D03*
X1588895Y22037D03*
X1595972Y23981D03*
X1591016D03*
X1589016Y25977D03*
X1597972D03*
X1589953Y37106D03*
X1597040D03*
Y48720D03*
X1589953D03*
X1589776Y72847D03*
X1594756D03*
X1600776Y71842D03*
X1598866Y69343D03*
X1600776Y66850D03*
X1589776Y77839D03*
X1594756D03*
X1597562Y555463D03*
X1595036D03*
X1591962D03*
X1589436D03*
X1589557Y1252778D03*
X1590097Y1246768D03*
X1603507Y1306262D03*
X1601772Y1337293D03*
X1601959Y1351773D03*
X1599139Y1400464D03*
X1595570Y1492995D03*
X1600350D03*
X1602270Y1483295D03*
X1600360Y1485895D03*
X1602270Y1488495D03*
X1593660Y1495595D03*
X1595570Y1498195D03*
X1600350D03*
X1588870Y1502695D03*
X1593650D03*
X1588870Y1507895D03*
X1593650D03*
X1593087Y1583797D03*
X1597812Y1583897D03*
X1602536Y1583697D03*
X1597051Y1622884D03*
X1592095D03*
X1591021Y1637876D03*
Y1632884D03*
X1598125Y1637876D03*
X1603081D03*
X1598125Y1632884D03*
X1603081D03*
X1592095Y1627876D03*
X1597051D03*
X1592095Y1654796D03*
X1591021Y1649788D03*
X1597051Y1654796D03*
X1603081Y1649788D03*
X1598125D03*
X1591021Y1644796D03*
X1603081D03*
X1598125D03*
X1592095Y1659788D03*
X1597051D03*
X1616965Y3001D03*
X1605077Y19541D03*
X1604127Y37106D03*
Y48720D03*
X1609866Y75340D03*
X1611776Y72847D03*
X1616756D03*
X1605756Y71842D03*
Y66850D03*
X1611776Y77839D03*
X1616756D03*
X1608640Y640660D03*
X1607050Y1483295D03*
Y1488495D03*
X1613760Y1505295D03*
X1615670Y1502695D03*
Y1507895D03*
X1607261Y1583897D03*
X1611985D03*
X1616710Y1583697D03*
X1609111Y1622884D03*
X1604155D03*
X1616215D03*
X1610185Y1637876D03*
X1615141D03*
X1610185Y1632884D03*
X1615141D03*
X1604155Y1627876D03*
X1609111D03*
X1616215D03*
X1604155Y1654796D03*
X1616215D03*
X1609111D03*
X1615141Y1649788D03*
X1610185D03*
X1615141Y1644796D03*
X1610185D03*
X1604155Y1659788D03*
X1616215D03*
X1609111D03*
X1631987Y19541D03*
X1626882Y23981D03*
X1631838D03*
X1624882Y25977D03*
X1632906Y37106D03*
X1625819D03*
X1632906Y48720D03*
X1625819D03*
X1629662Y69343D03*
X1633070Y75340D03*
X1627756Y71842D03*
X1622776D03*
X1627756Y66850D03*
X1622776D03*
X1620862Y69343D03*
X1627410Y172008D03*
X1632500Y381500D03*
X1630927Y398002D03*
X1628046Y756765D03*
Y760265D03*
Y767265D03*
X1623496Y776910D03*
Y783603D03*
X1627896Y795315D03*
X1623496Y807028D03*
Y813721D03*
Y820414D03*
X1627896Y832126D03*
X1623496Y843839D03*
Y850532D03*
Y857225D03*
X1627896Y868937D03*
X1623496Y880650D03*
Y887343D03*
Y894036D03*
X1627896Y905749D03*
X1623496Y917461D03*
Y924154D03*
Y930847D03*
X1627896Y942560D03*
X1623496Y954272D03*
Y960965D03*
Y967658D03*
Y974351D03*
Y981044D03*
Y987736D03*
Y994429D03*
Y1004469D03*
Y1034587D03*
Y1041280D03*
Y1047973D03*
Y1054666D03*
Y1061359D03*
Y1071398D03*
X1627896Y1089804D03*
X1623496Y1078091D03*
Y1101516D03*
Y1108209D03*
Y1114902D03*
X1627896Y1126615D03*
X1623496Y1138327D03*
Y1145020D03*
X1627896Y1163426D03*
X1623496Y1151713D03*
Y1175138D03*
Y1181831D03*
Y1188524D03*
X1627896Y1200237D03*
X1623496Y1211949D03*
Y1218642D03*
X1627896Y1237048D03*
X1623496Y1225335D03*
Y1248760D03*
Y1255453D03*
X1627052Y1424716D03*
X1627160Y1485895D03*
X1629070Y1483295D03*
Y1488495D03*
X1622370Y1492995D03*
X1627150D03*
X1620460Y1495595D03*
X1622370Y1498195D03*
X1627150D03*
X1620450Y1502695D03*
Y1507895D03*
X1621434Y1583797D03*
X1626159Y1583897D03*
X1630883D03*
X1621171Y1622884D03*
X1628275D03*
X1622245Y1637876D03*
Y1632884D03*
X1627201Y1637876D03*
Y1632884D03*
X1621171Y1627876D03*
X1628275D03*
X1621171Y1654796D03*
X1622245Y1649788D03*
X1628275Y1654796D03*
X1627201Y1649788D03*
X1622245Y1644796D03*
X1627201D03*
X1621171Y1659788D03*
X1628275D03*
X1638965Y3001D03*
X1648128Y17045D03*
X1633954D03*
X1638934D03*
X1648128Y22037D03*
X1648011Y25977D03*
X1633954Y22037D03*
X1638934D03*
X1646160Y19541D03*
X1640943D03*
X1641055Y23981D03*
X1646011D03*
X1639055Y25977D03*
X1633838D03*
X1647079Y37106D03*
X1639993D03*
X1647079Y48720D03*
X1639993D03*
X1634980Y72847D03*
X1639960D03*
X1645980Y71839D03*
X1644070Y69340D03*
X1645980Y66847D03*
X1634980Y77839D03*
X1639960D03*
X1642240Y399603D03*
X1642135Y414202D03*
X1639800Y426982D03*
X1636800D03*
X1639800Y429982D03*
X1636800D03*
X1639800Y432982D03*
X1636800D03*
X1647110Y434177D03*
X1639800Y435982D03*
X1636800D03*
X1639800Y438982D03*
X1636800D03*
X1635088Y756765D03*
Y763765D03*
X1639638Y773563D03*
X1644038Y791969D03*
X1634188Y786949D03*
X1639638Y780256D03*
X1634188Y796988D03*
X1639638Y803681D03*
Y810374D03*
Y817067D03*
X1644038Y828780D03*
X1634188Y823760D03*
Y833799D03*
X1639638Y840492D03*
Y847185D03*
X1644038Y865591D03*
X1634188Y860571D03*
X1639638Y853878D03*
X1634188Y870610D03*
X1639638Y877303D03*
Y883996D03*
Y890689D03*
X1644038Y902402D03*
X1634188Y897382D03*
Y907422D03*
X1639638Y914114D03*
Y920807D03*
X1644038Y939213D03*
X1634188Y934193D03*
X1639638Y927500D03*
X1634188Y944233D03*
X1639638Y950925D03*
Y957618D03*
Y964311D03*
Y971004D03*
Y977697D03*
Y984390D03*
Y991083D03*
Y997776D03*
Y1004469D03*
Y1031240D03*
Y1037933D03*
Y1044626D03*
Y1051319D03*
Y1058012D03*
Y1068051D03*
Y1074744D03*
X1644038Y1086457D03*
X1634188Y1081437D03*
Y1091477D03*
X1639638Y1098170D03*
Y1104862D03*
X1634188Y1118248D03*
X1639638Y1111555D03*
X1644038Y1123268D03*
X1634188Y1128288D03*
X1639638Y1134981D03*
Y1141674D03*
Y1148366D03*
X1644038Y1160079D03*
X1634188Y1155059D03*
Y1165099D03*
X1639638Y1171792D03*
Y1178485D03*
X1634188Y1191870D03*
X1639638Y1185177D03*
X1644038Y1196890D03*
X1634188Y1201910D03*
X1639638Y1208603D03*
Y1215296D03*
Y1221988D03*
X1644038Y1233701D03*
X1634188Y1228681D03*
Y1238721D03*
X1639638Y1245414D03*
Y1252107D03*
X1641904Y1351467D03*
Y1348567D03*
X1633850Y1483295D03*
Y1488495D03*
X1647260Y1495595D03*
X1640560Y1505295D03*
X1647250Y1502695D03*
X1642470D03*
X1647250Y1507895D03*
X1642470D03*
X1640332Y1583897D03*
X1645056Y1583697D03*
X1635608Y1583897D03*
X1633231Y1622884D03*
X1645291D03*
X1640335D03*
X1634305Y1637876D03*
Y1632790D03*
X1639261Y1637876D03*
Y1632790D03*
X1646365Y1637876D03*
Y1632884D03*
X1633231Y1627876D03*
X1640335D03*
X1645291D03*
X1633231Y1654796D03*
X1634305Y1649788D03*
X1640335Y1654796D03*
X1639261Y1649788D03*
X1645291Y1654796D03*
X1646365Y1649788D03*
X1634305Y1644796D03*
X1639261D03*
X1646365D03*
X1633231Y1659788D03*
X1640335D03*
X1645291D03*
X1647700Y1674228D03*
X1648013Y1713684D03*
Y1728834D03*
X1660965Y3001D03*
X1653108Y17045D03*
X1655116Y19541D03*
X1653108Y22037D03*
X1654166Y37106D03*
Y48720D03*
X1650960Y66847D03*
X1655066Y75343D03*
X1662065Y72850D03*
X1656980D03*
X1650960Y71839D03*
X1662065Y77842D03*
X1656980D03*
X1652610Y394727D03*
X1659610D03*
X1652810Y407402D03*
X1661110Y434177D03*
X1657747Y756765D03*
Y760265D03*
Y767265D03*
X1653197Y776910D03*
Y783603D03*
X1657597Y795315D03*
X1653197Y807028D03*
Y813721D03*
Y820414D03*
X1657597Y832126D03*
X1653197Y843839D03*
Y850532D03*
Y857225D03*
X1657597Y868937D03*
X1653197Y880650D03*
Y887343D03*
Y894036D03*
X1657597Y905749D03*
X1653197Y917461D03*
Y924154D03*
Y930847D03*
X1657597Y942560D03*
X1653197Y954272D03*
Y960965D03*
Y967658D03*
Y974351D03*
Y981044D03*
Y987736D03*
Y994429D03*
Y1004469D03*
Y1034587D03*
Y1041280D03*
Y1047973D03*
Y1054666D03*
Y1061359D03*
Y1071398D03*
X1657597Y1089804D03*
X1653197Y1078091D03*
Y1101516D03*
Y1108209D03*
Y1114902D03*
X1657597Y1126615D03*
X1653197Y1138327D03*
Y1145020D03*
X1657597Y1163426D03*
X1653197Y1151713D03*
Y1175138D03*
Y1188524D03*
Y1181831D03*
X1657597Y1200237D03*
X1653197Y1211949D03*
Y1218642D03*
X1657597Y1237048D03*
X1653197Y1225335D03*
Y1248760D03*
Y1255453D03*
X1660594Y1298735D03*
X1651187D03*
X1660594Y1303935D03*
Y1306535D03*
Y1301335D03*
X1651187Y1303935D03*
Y1306535D03*
Y1301335D03*
X1650177Y1351467D03*
Y1348567D03*
X1658904Y1351467D03*
Y1348567D03*
X1662010Y1384570D03*
X1662766Y1377814D03*
X1660166D03*
X1662766Y1374707D03*
X1660166D03*
X1651301Y1378765D03*
X1662010Y1390170D03*
X1654774Y1402619D03*
X1648857Y1403424D03*
X1662465Y1444358D03*
X1653960Y1485895D03*
X1655870Y1483295D03*
X1660650D03*
X1655870Y1488495D03*
X1660650D03*
X1649170Y1492995D03*
X1653950D03*
X1649170Y1498195D03*
X1653950D03*
X1654505Y1583897D03*
X1659229Y1583797D03*
X1649780Y1583897D03*
X1651321Y1637876D03*
Y1632884D03*
Y1649788D03*
Y1644796D03*
X1653464Y1668416D03*
X1661101Y1671631D03*
X1651101Y1700478D03*
X1660541Y1704237D03*
X1677972Y25977D03*
X1676121Y19541D03*
X1675972Y23981D03*
X1671016D03*
X1669016Y25977D03*
X1677040Y37106D03*
X1669953D03*
X1677040Y48720D03*
X1669953D03*
X1677204Y75340D03*
X1672960Y71839D03*
X1667980Y66847D03*
X1672960D03*
X1667980Y71839D03*
X1666070Y69340D03*
X1663610Y394727D03*
X1664789Y756765D03*
Y763765D03*
X1669339Y773563D03*
X1673739Y791969D03*
X1663889Y786949D03*
X1669339Y780256D03*
X1663889Y796988D03*
X1669339Y803681D03*
Y810374D03*
Y817067D03*
X1673739Y828780D03*
X1663889Y823760D03*
Y833799D03*
X1669339Y840492D03*
Y847185D03*
X1673739Y865591D03*
X1663889Y860571D03*
X1669339Y853878D03*
X1663889Y870610D03*
X1669339Y877303D03*
Y883996D03*
Y890689D03*
X1673739Y902402D03*
X1663889Y897382D03*
Y907422D03*
X1669339Y914114D03*
Y920807D03*
X1673739Y939213D03*
X1663889Y934193D03*
X1669339Y927500D03*
X1663889Y944233D03*
X1669339Y950925D03*
Y957618D03*
Y964311D03*
Y971004D03*
Y977697D03*
Y984390D03*
Y991083D03*
Y997776D03*
Y1004469D03*
Y1031240D03*
Y1037933D03*
Y1044626D03*
Y1051319D03*
Y1058012D03*
Y1068051D03*
Y1074744D03*
X1673739Y1086457D03*
X1663889Y1081437D03*
Y1091477D03*
X1669339Y1098170D03*
Y1104862D03*
X1663889Y1118248D03*
X1669339Y1111555D03*
X1673739Y1123268D03*
X1663889Y1128288D03*
X1669339Y1134981D03*
Y1141674D03*
Y1148366D03*
X1673739Y1160079D03*
X1663889Y1155059D03*
Y1165099D03*
X1669339Y1171792D03*
Y1178485D03*
X1663889Y1191870D03*
X1669339Y1185177D03*
X1673739Y1196890D03*
X1663889Y1201910D03*
X1669339Y1208603D03*
Y1215296D03*
Y1221988D03*
X1673739Y1233701D03*
X1663889Y1228681D03*
Y1238721D03*
X1669339Y1245414D03*
Y1252107D03*
X1675187Y1298735D03*
Y1303935D03*
Y1306535D03*
Y1301335D03*
X1674831Y1351266D03*
Y1348366D03*
X1675901Y1377594D03*
Y1380551D03*
X1666870Y1384570D03*
X1664440D03*
X1675510Y1374723D03*
X1667966Y1374707D03*
X1670566D03*
X1665366Y1377814D03*
Y1380771D03*
Y1374707D03*
X1667966Y1377814D03*
Y1380771D03*
X1673066Y1374707D03*
X1666870Y1390170D03*
X1664440D03*
X1666919Y1402585D03*
X1671067Y1405418D03*
X1672277Y1407694D03*
X1674777D03*
X1672907Y1429928D03*
X1672273Y1420567D03*
X1666290Y1444391D03*
X1667360Y1485895D03*
X1669270Y1483295D03*
X1674050D03*
X1669270Y1488495D03*
X1674050D03*
X1673674Y1563575D03*
X1670248Y1581563D03*
X1670534Y1670149D03*
X1673245Y1673475D03*
X1664256Y1690794D03*
X1673132Y1690741D03*
X1665520Y1716877D03*
Y1732027D03*
X1682965Y3001D03*
X1692262Y17045D03*
X1678088D03*
X1683068D03*
X1692262Y22037D03*
X1692145Y25977D03*
X1678088Y22037D03*
X1683068D03*
X1690294Y19541D03*
X1685077D03*
X1690145Y23981D03*
X1685189D03*
X1683189Y25977D03*
X1684127Y37106D03*
X1691213D03*
Y48720D03*
X1684127D03*
X1679114Y72847D03*
X1688200Y69343D03*
X1690114Y66850D03*
Y71842D03*
X1684094Y72847D03*
X1679114Y77839D03*
X1684094D03*
X1687448Y756765D03*
Y760265D03*
X1682898Y776910D03*
X1687448Y767265D03*
X1682898Y783603D03*
X1687298Y795315D03*
X1682898Y807028D03*
Y820414D03*
Y813721D03*
X1687298Y832126D03*
X1682898Y850532D03*
Y843839D03*
Y857225D03*
X1687298Y868937D03*
X1682898Y880650D03*
Y894036D03*
Y887343D03*
X1687298Y905749D03*
X1682898Y917461D03*
Y924154D03*
Y930847D03*
X1687298Y942560D03*
X1682898Y954272D03*
Y967658D03*
Y960965D03*
Y981044D03*
Y974351D03*
Y994429D03*
Y987736D03*
Y1004469D03*
Y1041280D03*
Y1034587D03*
Y1054666D03*
Y1047973D03*
Y1061359D03*
Y1071398D03*
Y1078091D03*
X1687298Y1089804D03*
X1682898Y1101516D03*
Y1108209D03*
Y1114902D03*
X1687298Y1126615D03*
X1682898Y1138327D03*
Y1145020D03*
Y1151713D03*
X1687298Y1163426D03*
X1682898Y1175138D03*
Y1188524D03*
Y1181831D03*
X1687298Y1200237D03*
X1682898Y1211949D03*
Y1218642D03*
Y1225335D03*
X1687298Y1237048D03*
X1682898Y1248760D03*
Y1255453D03*
X1684708Y1298435D03*
Y1303635D03*
Y1306235D03*
Y1301035D03*
X1687233Y1351320D03*
X1679133Y1351420D03*
X1687233Y1348420D03*
X1679133Y1348520D03*
X1679180Y1372169D03*
X1681780D03*
X1679180Y1366969D03*
X1681780D03*
Y1369569D03*
X1679180D03*
X1683896Y1378765D03*
X1692948Y1377914D03*
Y1374807D03*
X1680530Y1374669D03*
X1685963Y1402187D03*
X1687621Y1404138D03*
X1684172Y1538135D03*
X1682561Y1552726D03*
X1691226Y1563526D03*
X1680558Y1555690D03*
X1691226Y1559526D03*
X1682494Y1568271D03*
Y1575125D03*
X1680491Y1578089D03*
Y1571235D03*
X1689880Y1572067D03*
X1679420Y1683597D03*
X1683013Y1713684D03*
X1680519Y1726825D03*
X1689383Y1729187D03*
X1704965Y3001D03*
X1697242Y17045D03*
X1699250Y19541D03*
X1697242Y22037D03*
X1698300Y37106D03*
X1705381Y37108D03*
X1698300Y48720D03*
X1705386D03*
X1701114Y72847D03*
X1706094D03*
X1699204Y75340D03*
X1695094Y66850D03*
Y71842D03*
X1706094Y77839D03*
X1701114D03*
X1694490Y756765D03*
Y763765D03*
X1699040Y773563D03*
X1703440Y791969D03*
X1699040Y780256D03*
X1693590Y786949D03*
X1699040Y803681D03*
X1693590Y796988D03*
X1699040Y817067D03*
Y810374D03*
X1693590Y823760D03*
X1703440Y828780D03*
X1693590Y833799D03*
X1699040Y847185D03*
Y840492D03*
Y853878D03*
X1693590Y860571D03*
X1703440Y865591D03*
X1693590Y870610D03*
X1699040Y877303D03*
Y883996D03*
Y890689D03*
X1693590Y907422D03*
X1703440Y902402D03*
X1693590Y897382D03*
X1699040Y914114D03*
Y920807D03*
X1693590Y934193D03*
X1699040Y927500D03*
X1703440Y939213D03*
X1693590Y944233D03*
X1699040Y950925D03*
Y964311D03*
Y971004D03*
Y957618D03*
Y977697D03*
Y984390D03*
Y997776D03*
Y991083D03*
Y1004469D03*
Y1044626D03*
Y1037933D03*
Y1031240D03*
Y1058012D03*
Y1051319D03*
Y1074744D03*
Y1068051D03*
X1703440Y1086457D03*
X1693590Y1081437D03*
Y1091477D03*
X1699040Y1104862D03*
Y1098170D03*
Y1111555D03*
X1693590Y1118248D03*
X1699040Y1134981D03*
X1703440Y1123268D03*
X1693590Y1128288D03*
X1699040Y1141674D03*
Y1148366D03*
X1693590Y1155059D03*
Y1165099D03*
X1703440Y1160079D03*
X1699040Y1171792D03*
Y1178485D03*
X1693590Y1191870D03*
X1699040Y1185177D03*
X1693590Y1201910D03*
X1703440Y1196890D03*
X1699040Y1208603D03*
Y1221988D03*
Y1215296D03*
X1693590Y1228681D03*
Y1238721D03*
X1703440Y1233701D03*
X1699040Y1245414D03*
Y1252107D03*
X1699087Y1298435D03*
Y1303635D03*
Y1306235D03*
Y1301035D03*
X1695533Y1351320D03*
Y1348420D03*
X1694792Y1384670D03*
X1700748Y1377914D03*
Y1380871D03*
Y1374807D03*
X1703348D03*
X1705848D03*
X1698148Y1377914D03*
X1695548D03*
X1698148Y1380871D03*
X1695548Y1374807D03*
X1698148D03*
X1699652Y1384670D03*
X1697222D03*
X1699652Y1390270D03*
X1694792D03*
X1697222D03*
X1699701Y1402685D03*
X1700520Y1716877D03*
X1702777Y1723593D03*
X1695166Y1717606D03*
X1720148Y22910D03*
X1710886Y82208D03*
X1715550Y102923D03*
X1721400Y374462D03*
X1718241Y652105D03*
X1717149Y756765D03*
Y760265D03*
X1712599Y776910D03*
X1717149Y767265D03*
X1712599Y783603D03*
Y807028D03*
X1716999Y795315D03*
X1712599Y820414D03*
Y813721D03*
X1716999Y832126D03*
X1712599Y850532D03*
Y843839D03*
Y857225D03*
X1716999Y868937D03*
X1712599Y880650D03*
Y894036D03*
Y887343D03*
X1716999Y905749D03*
X1712599Y917461D03*
Y924154D03*
Y930847D03*
X1716999Y942560D03*
X1712599Y954272D03*
Y967658D03*
Y960965D03*
Y981044D03*
Y974351D03*
Y994429D03*
Y987736D03*
Y1004469D03*
Y1041280D03*
Y1034587D03*
Y1054666D03*
Y1047973D03*
Y1061359D03*
Y1071398D03*
Y1078091D03*
X1716999Y1089804D03*
X1712599Y1101516D03*
Y1108209D03*
Y1114902D03*
X1716999Y1126615D03*
X1712599Y1138327D03*
Y1145020D03*
Y1151713D03*
X1716999Y1163426D03*
X1712599Y1175138D03*
Y1188524D03*
Y1181831D03*
X1716999Y1200237D03*
X1712599Y1218642D03*
Y1211949D03*
Y1225335D03*
X1716999Y1237048D03*
X1712599Y1248760D03*
Y1255453D03*
X1721754Y1299488D03*
X1708754Y1298388D03*
X1721847Y1307298D03*
X1721754Y1304688D03*
X1708754Y1300988D03*
X1721754Y1302088D03*
X1708754Y1303588D03*
Y1306188D03*
X1718813Y1348450D03*
Y1351350D03*
X1709533Y1351520D03*
Y1348620D03*
X1711962Y1367069D03*
X1714562D03*
X1711962Y1369669D03*
X1714562D03*
X1719902Y1368509D03*
Y1365909D03*
Y1363409D03*
X1708678Y1380621D03*
Y1377664D03*
X1716267Y1375178D03*
X1713312Y1374769D03*
X1708292Y1374823D03*
X1720210Y1435330D03*
X1719893Y1594940D03*
Y1612940D03*
Y1599740D03*
Y1603040D03*
Y1606340D03*
Y1609640D03*
X1722133Y1725340D03*
X1727111Y-38849D03*
Y-28849D03*
X1726965Y3001D03*
X1732286Y28208D03*
X1728786D03*
X1725286D03*
X1727336Y57024D03*
X1726596Y61784D03*
X1729836Y57024D03*
X1726596Y64284D03*
X1726814Y102968D03*
X1733344Y134953D03*
X1736474D03*
X1730364Y177588D03*
X1725400Y372062D03*
X1737260Y368132D03*
X1732660Y372692D03*
X1725500Y383662D03*
X1723259Y653641D03*
X1726334Y670345D03*
X1724191Y756765D03*
Y763765D03*
X1728741Y773563D03*
X1733141Y791969D03*
X1723291Y786949D03*
X1728741Y780256D03*
Y803681D03*
X1723291Y796988D03*
X1728741Y817067D03*
Y810374D03*
X1733141Y828780D03*
X1723291Y823760D03*
Y833799D03*
X1728741Y847185D03*
Y840492D03*
Y853878D03*
X1733141Y865591D03*
X1723291Y860571D03*
Y870610D03*
X1728741Y877303D03*
Y883996D03*
Y890689D03*
X1723291Y907422D03*
X1733141Y902402D03*
X1723291Y897382D03*
X1728741Y914114D03*
Y920807D03*
X1723291Y934193D03*
X1728741Y927500D03*
X1733141Y939213D03*
X1723291Y944233D03*
X1728741Y950925D03*
Y964311D03*
Y971004D03*
Y957618D03*
Y977697D03*
Y984390D03*
Y997776D03*
Y991083D03*
Y1004469D03*
Y1044626D03*
Y1037933D03*
Y1031240D03*
Y1058012D03*
Y1051319D03*
Y1074744D03*
Y1068051D03*
X1733141Y1086457D03*
X1723291Y1081437D03*
Y1091477D03*
X1728741Y1104862D03*
Y1098170D03*
Y1111555D03*
X1723291Y1118248D03*
X1728741Y1134981D03*
X1733141Y1123268D03*
X1723291Y1128288D03*
X1728741Y1141674D03*
Y1148366D03*
X1723291Y1155059D03*
X1733141Y1160079D03*
X1723291Y1165099D03*
X1728741Y1171792D03*
Y1178485D03*
X1723291Y1191870D03*
X1728741Y1185177D03*
X1723291Y1201910D03*
X1733141Y1196890D03*
X1728741Y1208603D03*
Y1221988D03*
Y1215296D03*
X1733141Y1233701D03*
X1723291Y1228681D03*
Y1238721D03*
X1728741Y1245414D03*
Y1252107D03*
X1732624Y1299718D03*
X1732717Y1307528D03*
X1732624Y1302318D03*
Y1304918D03*
X1735202Y1368279D03*
Y1365679D03*
Y1363179D03*
X1723917Y1380518D03*
Y1377178D03*
X1737126Y1403838D03*
Y1401238D03*
X1722810Y1435330D03*
X1737541Y1543707D03*
X1734575Y1562068D03*
X1724323Y1676965D03*
X1748965Y3001D03*
X1752008Y25146D03*
X1748116Y37058D03*
X1745451Y119585D03*
X1747448Y121413D03*
X1750325Y179827D03*
X1750851Y216427D03*
X1748325D03*
X1752461Y255337D03*
Y252337D03*
X1742652Y671494D03*
X1746850Y756765D03*
Y760265D03*
X1742300Y776910D03*
X1746850Y767265D03*
X1742300Y783603D03*
X1746700Y795315D03*
X1742300Y807028D03*
Y820414D03*
Y813721D03*
X1746700Y832126D03*
X1742300Y850532D03*
Y843839D03*
Y857225D03*
X1746700Y868937D03*
X1742300Y880650D03*
Y894036D03*
Y887343D03*
X1746700Y905749D03*
X1742300Y917461D03*
Y924154D03*
Y930847D03*
X1746700Y942560D03*
X1742300Y954272D03*
Y960965D03*
Y967658D03*
Y981044D03*
Y974351D03*
Y994429D03*
Y987736D03*
Y1004469D03*
Y1041280D03*
Y1034587D03*
Y1054666D03*
Y1047973D03*
Y1061359D03*
Y1071398D03*
Y1078091D03*
X1746700Y1089804D03*
X1742300Y1101516D03*
Y1108209D03*
Y1114902D03*
X1746700Y1126615D03*
X1742300Y1138327D03*
Y1145020D03*
Y1151713D03*
X1746700Y1163426D03*
X1742300Y1175138D03*
Y1188524D03*
Y1181831D03*
X1746700Y1200237D03*
X1742300Y1218642D03*
Y1211949D03*
Y1225335D03*
X1746700Y1237048D03*
X1742300Y1248760D03*
Y1255453D03*
X1743072Y1432211D03*
X1743188Y1543871D03*
Y1547871D03*
X1740587Y1547946D03*
X1737738Y1548021D03*
X1740400Y1543682D03*
X1752364Y1556323D03*
Y1559430D03*
X1744564Y1556323D03*
Y1559430D03*
X1749764Y1556323D03*
Y1559430D03*
X1747164Y1556323D03*
Y1559430D03*
X1752564Y1562537D03*
X1751518Y1566186D03*
X1740079Y1559505D03*
X1740188Y1556371D03*
X1746558Y1566186D03*
X1749038D03*
X1749964Y1562537D03*
X1751518Y1571786D03*
X1746558D03*
X1749038D03*
X1739640Y1713383D03*
Y1728533D03*
X1762420Y17031D03*
X1763840Y37790D03*
X1753398Y48720D03*
X1760485D03*
X1759666Y57708D03*
X1764366Y57508D03*
X1758047Y68637D03*
X1758539Y87153D03*
Y83653D03*
X1758534Y79743D03*
X1765034Y80443D03*
X1766244Y93673D03*
X1766911Y179890D03*
X1752851Y179827D03*
X1757385Y179890D03*
X1764385D03*
X1759911D03*
X1757951Y216427D03*
X1755425D03*
X1762485Y216490D03*
X1765011D03*
X1758859Y251544D03*
Y248544D03*
X1766399Y251361D03*
Y248361D03*
X1753892Y756765D03*
Y763765D03*
X1758442Y773563D03*
X1762842Y791969D03*
X1752992Y786949D03*
X1758442Y780256D03*
Y803681D03*
X1752992Y796988D03*
X1758442Y817067D03*
Y810374D03*
X1752992Y823760D03*
Y833799D03*
X1762842Y828780D03*
X1758442Y847185D03*
Y840492D03*
X1752992Y860571D03*
X1758442Y853878D03*
X1762842Y865591D03*
X1752992Y870610D03*
X1758442Y877303D03*
Y883996D03*
Y890689D03*
X1752992Y907422D03*
Y897382D03*
X1762842Y902402D03*
X1758442Y914114D03*
Y920807D03*
X1752992Y934193D03*
X1758442Y927500D03*
X1762842Y939213D03*
X1752992Y944233D03*
X1758442Y950925D03*
Y964311D03*
Y971004D03*
Y957618D03*
Y977697D03*
Y984390D03*
Y997776D03*
Y991083D03*
Y1004469D03*
Y1044626D03*
Y1037933D03*
Y1031240D03*
Y1058012D03*
Y1051319D03*
Y1074744D03*
Y1068051D03*
X1752992Y1081437D03*
X1762842Y1086457D03*
X1752992Y1091477D03*
X1758442Y1104862D03*
Y1098170D03*
X1752992Y1118248D03*
X1758442Y1111555D03*
Y1134981D03*
X1752992Y1128288D03*
X1762842Y1123268D03*
X1758442Y1141674D03*
Y1148366D03*
X1752992Y1155059D03*
Y1165099D03*
X1762842Y1160079D03*
X1758442Y1171792D03*
Y1178485D03*
X1752992Y1191870D03*
X1758442Y1185177D03*
X1752992Y1201910D03*
X1762842Y1196890D03*
X1758442Y1208603D03*
Y1221988D03*
Y1215296D03*
X1752992Y1228681D03*
Y1238721D03*
X1762842Y1233701D03*
X1758442Y1245414D03*
Y1252107D03*
X1758238Y1556238D03*
X1761108Y1556339D03*
Y1559446D03*
X1761079Y1562605D03*
X1755038Y1556238D03*
X1765709Y1556050D03*
X1754479Y1585905D03*
X1754763Y1641665D03*
X1752864Y1716383D03*
X1770965Y3001D03*
X1772886Y37430D03*
X1768134Y80543D03*
X1771385Y179890D03*
X1773911D03*
X1778500Y183790D03*
X1769585Y215090D03*
X1772111D03*
X1776585D03*
X1779111D03*
X1778874Y253799D03*
Y256799D03*
X1770520Y364148D03*
Y368148D03*
X1771236Y557224D03*
X1776550Y756765D03*
Y760265D03*
X1772000Y776910D03*
X1776550Y767265D03*
X1772000Y783603D03*
Y807028D03*
X1776400Y795315D03*
X1772000Y813721D03*
Y820414D03*
X1776400Y832126D03*
X1772000Y850532D03*
Y843839D03*
Y857225D03*
X1776400Y868937D03*
X1772000Y880650D03*
Y894036D03*
Y887343D03*
X1776400Y905749D03*
X1772000Y917461D03*
Y924154D03*
Y930847D03*
X1776400Y942560D03*
X1772000Y954272D03*
Y967658D03*
Y960965D03*
Y981044D03*
Y974351D03*
Y994429D03*
Y987736D03*
Y1004469D03*
Y1041280D03*
Y1034587D03*
Y1047973D03*
Y1054666D03*
Y1061359D03*
Y1071398D03*
Y1078091D03*
X1776400Y1089804D03*
X1772000Y1101516D03*
Y1108209D03*
Y1114902D03*
X1776400Y1126615D03*
X1772000Y1138327D03*
Y1145020D03*
Y1151713D03*
X1776400Y1163426D03*
X1772000Y1175138D03*
Y1188524D03*
Y1181831D03*
X1776400Y1200237D03*
X1772000Y1218642D03*
Y1211949D03*
Y1225335D03*
X1776400Y1237048D03*
X1772000Y1248760D03*
Y1255453D03*
X1776188Y1543871D03*
Y1546871D03*
X1769188D03*
Y1543871D03*
X1768688Y1552871D03*
Y1549871D03*
X1772688Y1543871D03*
Y1546871D03*
X1776113Y1541172D03*
X1769113D03*
X1772613D03*
X1780307Y1559430D03*
Y1556323D03*
X1775979Y1556805D03*
Y1559805D03*
X1782301Y1566186D03*
X1768209Y1556000D03*
X1769826Y1562559D03*
X1782301Y1571786D03*
X1792965Y3001D03*
X1796781Y46686D03*
X1785144Y86973D03*
Y89973D03*
X1783448Y212957D03*
X1795794Y253719D03*
X1787534Y253769D03*
X1795794Y256719D03*
X1787534Y256769D03*
X1795479Y408056D03*
X1795468Y421334D03*
X1783592Y756765D03*
X1788142Y773563D03*
X1792542Y791969D03*
X1782692Y786949D03*
X1788142Y780256D03*
X1782692Y796988D03*
X1788142Y803681D03*
Y817067D03*
Y810374D03*
X1782692Y823760D03*
Y833799D03*
X1792542Y828780D03*
X1788142Y847185D03*
Y840492D03*
Y853878D03*
X1792542Y865591D03*
X1782692Y860571D03*
Y870610D03*
X1788142Y877303D03*
Y883996D03*
Y890689D03*
X1782692Y907422D03*
Y897382D03*
X1792542Y902402D03*
X1788142Y914114D03*
Y920807D03*
X1782692Y934193D03*
X1788142Y927500D03*
X1792542Y939213D03*
X1782692Y944233D03*
X1788142Y950925D03*
Y964311D03*
Y971004D03*
Y957618D03*
Y977697D03*
Y984390D03*
Y997776D03*
Y991083D03*
Y1004469D03*
Y1044626D03*
Y1037933D03*
Y1031240D03*
Y1058012D03*
Y1051319D03*
Y1074744D03*
Y1068051D03*
X1782692Y1081437D03*
X1792542Y1086457D03*
X1782692Y1091477D03*
X1788142Y1098170D03*
Y1104862D03*
X1782692Y1118248D03*
X1788142Y1111555D03*
Y1134981D03*
X1782692Y1128288D03*
X1792542Y1123268D03*
X1788142Y1141674D03*
Y1148366D03*
X1782692Y1155059D03*
Y1165099D03*
X1792542Y1160079D03*
X1788142Y1171792D03*
Y1178485D03*
X1782692Y1191870D03*
X1788142Y1185177D03*
X1782692Y1201910D03*
X1792542Y1196890D03*
X1788142Y1208603D03*
Y1221988D03*
Y1215296D03*
X1782692Y1228681D03*
Y1238721D03*
X1792542Y1233701D03*
X1788142Y1245414D03*
Y1252107D03*
X1796838Y1556125D03*
X1788107Y1556323D03*
X1793833Y1556195D03*
X1790633D03*
X1788107Y1559430D03*
X1788307Y1562537D03*
X1787261Y1566186D03*
X1782907Y1559430D03*
Y1556323D03*
X1784781Y1566186D03*
X1785507Y1559430D03*
Y1556323D03*
X1785707Y1562537D03*
X1796257Y1561255D03*
Y1558755D03*
X1787261Y1571786D03*
X1784781D03*
X1788679Y1585805D03*
X1807515Y56461D03*
X1807546Y59443D03*
X1807296Y255033D03*
X1804174Y253739D03*
Y256739D03*
X1803129Y362293D03*
X1802929Y385293D03*
X1804688Y1545871D03*
Y1542371D03*
Y1552871D03*
Y1549371D03*
X1801688Y1545871D03*
Y1542371D03*
Y1552871D03*
Y1549371D03*
X1804688Y1555871D03*
X1801688D03*
X1804688Y1559371D03*
X1818615Y49379D03*
X1818155Y149325D03*
X1819529Y320321D03*
X1820307Y373829D03*
X1820656Y388051D03*
X1820144Y398052D03*
X1819374Y410432D03*
X1818874Y423932D03*
X1840615Y49379D03*
X1853692Y308447D03*
G54D38*
X311115Y1214093D03*
X310957Y1219126D03*
X388805Y1218420D03*
X388647Y1223453D03*
X386461Y1235718D03*
X386303Y1240751D03*
X1898799Y1810398D03*
X1908799D03*
X1931395Y572237D03*
X1921395D03*
X1942395Y1184617D03*
X1940886Y1810370D03*
X1963362Y572379D03*
X1952395Y1184617D03*
X1950886Y1810370D03*
X1973362Y572379D03*
X1984482Y1184589D03*
X1992856Y1810550D03*
X1982856D03*
X2005452Y572389D03*
X1994482Y1184589D03*
X2015452Y572389D03*
X2036452Y1184769D03*
X2026452D03*
X2047419Y572531D03*
X2057419D03*
X2078539Y1184741D03*
X2068539D03*
G54D55*
X828780Y1684890D03*
X818780D03*
X828780Y1694890D03*
X818780D03*
X828780Y1704890D03*
X818780D03*
X828780Y1714890D03*
X818780D03*
X853780Y1684890D03*
Y1694890D03*
Y1704890D03*
Y1714890D03*
X863780Y1684890D03*
Y1694890D03*
Y1704890D03*
Y1714890D03*
X888780Y1684890D03*
Y1694890D03*
Y1704890D03*
Y1714890D03*
X898780Y1684890D03*
Y1694890D03*
Y1704890D03*
Y1714890D03*
X918780Y1704890D03*
X958780Y1684890D03*
Y1694890D03*
Y1704890D03*
Y1714890D03*
X968780Y1684890D03*
Y1694890D03*
Y1704890D03*
Y1714890D03*
X993780Y1684890D03*
Y1694890D03*
Y1704890D03*
Y1714890D03*
X1003780Y1684890D03*
Y1694890D03*
Y1704890D03*
Y1714890D03*
X1028780Y1684890D03*
X1038780D03*
X1028780Y1694890D03*
X1038780D03*
X1028780Y1704890D03*
Y1714890D03*
X1038780Y1704890D03*
Y1714890D03*
G54D29*
X182947Y1507512D03*
X186530Y1521453D03*
X185688Y1519195D03*
X186860Y1514243D03*
X186579Y1536063D03*
X177579Y1528725D03*
Y1523810D03*
X183051Y1542425D03*
X185966Y1592380D03*
Y1624292D03*
X188254Y1507295D03*
X192979D03*
X197703D03*
X191254Y1521453D03*
X195979D03*
X200703D03*
X196309Y1514243D03*
X201033D03*
X191584D03*
X187081Y1528853D03*
X191805D03*
X196530D03*
X201254D03*
X196029Y1536063D03*
X200753D03*
X191304D03*
X197703Y1542641D03*
X188254D03*
X192979D03*
X198026Y1592380D03*
X193766D03*
X192006Y1602380D03*
X199786D03*
X193766Y1624292D03*
X198026D03*
X199786Y1614292D03*
X192006D03*
X202427Y1507295D03*
X207152D03*
X211876D03*
X216601D03*
X205427Y1521453D03*
X210152D03*
X214876D03*
X205758Y1514243D03*
X215206D03*
X210482D03*
X205978Y1528853D03*
X210703D03*
X215427D03*
X214926Y1536063D03*
X211876Y1542641D03*
X202427D03*
X207152D03*
X216601D03*
X210086Y1592380D03*
X205826D03*
X216126Y1602380D03*
X204066D03*
X211846D03*
X205826Y1624292D03*
X210086D03*
X216126Y1614292D03*
X211846D03*
X204066D03*
X221325Y1507295D03*
X226049D03*
X230774D03*
X219601Y1521453D03*
X224325D03*
X229049D03*
X219931Y1514243D03*
X224655D03*
X229380D03*
X220152Y1528853D03*
X224876D03*
X229600D03*
X224375Y1536063D03*
X226049Y1542641D03*
X230774D03*
X221325D03*
X229946Y1592380D03*
X217886D03*
X222146D03*
X223906Y1602380D03*
X228186D03*
X229946Y1624292D03*
X222146D03*
X217886D03*
X228186Y1614292D03*
X223906D03*
X235498Y1507295D03*
X240223D03*
X244947D03*
X243223Y1521453D03*
X238498D03*
X233774D03*
X234104Y1514243D03*
X238828D03*
X243553D03*
X243774Y1528853D03*
X239049D03*
X234325D03*
X238548Y1536063D03*
X240223Y1542641D03*
X235498D03*
X244947D03*
X242006Y1592380D03*
X234206D03*
X246266D03*
X235966Y1602380D03*
X240246D03*
X246266Y1624292D03*
X242006D03*
X234206D03*
X240246Y1614292D03*
X235966D03*
X241141Y1679320D03*
Y1683857D03*
X233267Y1675383D03*
Y1679920D03*
Y1684454D03*
X241141Y1688391D03*
Y1693493D03*
Y1698030D03*
X233267Y1689556D03*
Y1694093D03*
Y1698627D03*
X241141Y1702564D03*
Y1707666D03*
Y1712203D03*
Y1716737D03*
X233267Y1703729D03*
Y1708266D03*
Y1712800D03*
X241141Y1721840D03*
Y1726377D03*
Y1730911D03*
X233267Y1717903D03*
Y1722440D03*
Y1726974D03*
X259120Y1507295D03*
X249671D03*
X254396D03*
X257396Y1521453D03*
X252672D03*
X247947D03*
X248277Y1514243D03*
X257726D03*
X257947Y1528853D03*
X253223D03*
X248498D03*
X257446Y1536063D03*
X247997D03*
X254396Y1542641D03*
X259120D03*
X249671D03*
X258326Y1592380D03*
X254066D03*
X248026Y1602380D03*
X252306D03*
X260086D03*
X258326Y1624292D03*
X254066D03*
X248026Y1614292D03*
X252306D03*
X260086D03*
X256889Y1679320D03*
Y1683857D03*
X249015Y1684454D03*
Y1679920D03*
Y1675383D03*
X256889Y1688391D03*
Y1693493D03*
Y1698030D03*
X249015Y1698627D03*
Y1694093D03*
Y1689556D03*
X256889Y1702564D03*
Y1707666D03*
Y1712203D03*
Y1716737D03*
X249015Y1712800D03*
Y1708266D03*
Y1703729D03*
X256889Y1721840D03*
Y1726377D03*
Y1730911D03*
X249015Y1726974D03*
Y1722440D03*
Y1717903D03*
X262141Y1521453D03*
X262777Y1536063D03*
X270386Y1592380D03*
X266126D03*
X264366Y1602380D03*
X272146D03*
X270386Y1624292D03*
X266126D03*
X272146Y1614292D03*
X264366D03*
X272637Y1679320D03*
Y1683857D03*
X264763Y1684454D03*
Y1679920D03*
Y1675383D03*
X272637Y1688391D03*
Y1693493D03*
Y1698030D03*
X264763Y1698627D03*
Y1694093D03*
Y1689556D03*
X272637Y1702564D03*
Y1707666D03*
Y1712203D03*
Y1716737D03*
X264763Y1712800D03*
Y1708266D03*
Y1703729D03*
X272637Y1721840D03*
Y1726377D03*
Y1730911D03*
X264763Y1726974D03*
Y1722440D03*
Y1717903D03*
X290246Y1592380D03*
X278186D03*
X282446D03*
X276426Y1602380D03*
X284206D03*
X288486D03*
X290236Y1624292D03*
X282446D03*
X278186D03*
X288486Y1614292D03*
X284206D03*
X276426D03*
X288385Y1683857D03*
Y1679320D03*
X280511Y1684454D03*
Y1679920D03*
Y1675383D03*
X288385Y1688391D03*
Y1693494D03*
Y1698031D03*
X280511Y1698627D03*
Y1694093D03*
Y1689556D03*
X288385Y1712204D03*
Y1716738D03*
Y1702565D03*
Y1707667D03*
X280511Y1712800D03*
Y1708266D03*
Y1703729D03*
X288385Y1721840D03*
Y1726377D03*
Y1730911D03*
X280511Y1726974D03*
Y1722440D03*
Y1717903D03*
X305641Y1528725D03*
Y1523810D03*
X302306Y1592380D03*
X294506D03*
X296266Y1602380D03*
X300546D03*
X302306Y1624292D03*
X294516D03*
X300546Y1614292D03*
X296266D03*
X300196Y1675383D03*
Y1679920D03*
Y1684454D03*
Y1689556D03*
Y1694093D03*
Y1698627D03*
Y1703729D03*
Y1708266D03*
Y1712800D03*
Y1717903D03*
Y1722440D03*
Y1726974D03*
X309886Y1028056D03*
X315437Y1031245D03*
X317288Y1040812D03*
X309886D03*
X317288Y1034434D03*
X309886D03*
X315437Y1044001D03*
X309886Y1047190D03*
X311736Y1056757D03*
X309886Y1053568D03*
X315437Y1050379D03*
X317288Y1053568D03*
Y1059946D03*
X309886D03*
X313587D03*
X315437Y1063135D03*
X317288Y1072702D03*
X309886D03*
Y1066324D03*
X315437Y1069513D03*
X317288Y1079080D03*
X309886D03*
X315437Y1082269D03*
Y1088647D03*
X309886Y1085458D03*
Y1091836D03*
X317288D03*
X309886Y1104592D03*
X315437Y1101403D03*
X317288Y1098214D03*
X309886D03*
X315437Y1107781D03*
X309886Y1110970D03*
X317288D03*
X309886Y1117348D03*
X317288D03*
X309886Y1123726D03*
X315437Y1120537D03*
Y1126915D03*
X309886Y1130103D03*
X317288D03*
X309886Y1136481D03*
X315437Y1139670D03*
X317288Y1136481D03*
X309886Y1142859D03*
X317288Y1149237D03*
X309886D03*
X315437Y1146048D03*
X317288Y1155615D03*
X309886D03*
X313587D03*
X308036Y1158804D03*
X311736Y1165182D03*
X320988Y1155615D03*
Y1161993D03*
X311009Y1507514D03*
X316316Y1507295D03*
X321041D03*
X319316Y1521453D03*
X314592D03*
X313750Y1519195D03*
X314922Y1514243D03*
X319646D03*
X319867Y1528853D03*
X315143D03*
X319366Y1536063D03*
X314641D03*
X311113Y1542425D03*
X316316Y1542641D03*
X321041D03*
X318626Y1592380D03*
X306566D03*
X314366D03*
X308326Y1602380D03*
X312606D03*
X320386D03*
X314366Y1624292D03*
X318626D03*
X306566D03*
X320386Y1614292D03*
X312606D03*
X308326D03*
X315944Y1675383D03*
Y1679920D03*
Y1684454D03*
X308070Y1683857D03*
Y1679320D03*
X315944Y1689556D03*
Y1694093D03*
Y1698627D03*
X308070Y1698030D03*
Y1693493D03*
Y1688391D03*
X315944Y1703729D03*
Y1708266D03*
Y1712800D03*
X308070Y1716737D03*
Y1712203D03*
Y1707666D03*
Y1702564D03*
X315944Y1722440D03*
Y1726974D03*
X308070Y1730911D03*
Y1726377D03*
Y1721840D03*
X315944Y1717903D03*
X328390Y1028056D03*
X335791D03*
X322839Y1031245D03*
Y1037623D03*
Y1044001D03*
X328390Y1040812D03*
Y1034434D03*
X330240Y1031245D03*
Y1037623D03*
Y1044001D03*
X335791Y1040812D03*
Y1034434D03*
X328390Y1047190D03*
X322839Y1050379D03*
Y1056757D03*
X326539D03*
X328390Y1053568D03*
Y1059946D03*
X324689D03*
X330240Y1050379D03*
Y1056757D03*
X335791Y1047190D03*
Y1053568D03*
Y1059946D03*
X328390Y1072702D03*
X330240Y1069513D03*
X335791Y1072702D03*
Y1066324D03*
X322839Y1063135D03*
X330240D03*
X322839Y1069513D03*
X328390Y1066324D03*
X322839Y1075891D03*
X330240D03*
X328390Y1079080D03*
X322839Y1088647D03*
X328390Y1085458D03*
X330240Y1088647D03*
X322839Y1082269D03*
X330240D03*
X335791Y1079080D03*
Y1085458D03*
X328390Y1091836D03*
X322839Y1095025D03*
X330240D03*
X328390Y1104592D03*
Y1098214D03*
X322839Y1101403D03*
X330240D03*
X335791Y1091836D03*
Y1104592D03*
Y1098214D03*
X322839Y1107781D03*
X330240D03*
X328390Y1110970D03*
Y1117348D03*
X330240Y1114159D03*
X322839D03*
X335791Y1110970D03*
Y1117348D03*
X330240Y1126915D03*
X322839D03*
X328390Y1123726D03*
X330240Y1120537D03*
X322839D03*
Y1133293D03*
X330240D03*
X328390Y1130103D03*
X335791Y1123726D03*
X335792Y1130105D03*
X328390Y1142859D03*
X322839Y1139670D03*
X328390Y1136481D03*
X330240Y1139670D03*
X328390Y1149237D03*
X330240Y1146048D03*
X322839D03*
X335791Y1136481D03*
Y1142859D03*
Y1149237D03*
X328390Y1155615D03*
X330240Y1152426D03*
X322839D03*
X326539Y1158804D03*
X330240D03*
X333941D03*
X322839D03*
X328390Y1161993D03*
X330240Y1165182D03*
X335791Y1155615D03*
Y1161993D03*
X330489Y1507295D03*
X335214D03*
X325765D03*
X333489Y1521453D03*
X328765D03*
X324041D03*
X324371Y1514243D03*
X329095D03*
X333820D03*
X334040Y1528853D03*
X329316D03*
X324592D03*
X324091Y1536063D03*
X328815D03*
X325765Y1542641D03*
X330489D03*
X335214D03*
X330686Y1592380D03*
X326426D03*
X324666Y1602380D03*
X332446D03*
X326426Y1624292D03*
X330686D03*
X332446Y1614292D03*
X324666D03*
X331692Y1675383D03*
Y1679920D03*
Y1684454D03*
X323818Y1683857D03*
Y1679320D03*
X331692Y1689556D03*
Y1694093D03*
Y1698627D03*
X323818Y1698030D03*
Y1693493D03*
Y1688391D03*
X331692Y1703729D03*
Y1708266D03*
Y1712800D03*
X323818Y1716737D03*
Y1712203D03*
Y1707666D03*
Y1702564D03*
Y1721840D03*
X331692Y1717903D03*
Y1722440D03*
Y1726974D03*
X323818Y1730911D03*
Y1726377D03*
X348744Y1031245D03*
X341343D03*
X343193Y1040812D03*
X348744Y1037623D03*
X343193Y1034434D03*
X348744Y1044001D03*
X341343D03*
X350595Y1059946D03*
X337642Y1056757D03*
X348744D03*
X343193Y1053568D03*
X341343Y1050379D03*
X348744D03*
X343193Y1059946D03*
X339492D03*
X341343Y1063135D03*
X348744D03*
X341343Y1069513D03*
X343193Y1072702D03*
X348744Y1069513D03*
X343193Y1079080D03*
X348744Y1075891D03*
X341343Y1082269D03*
X348744D03*
X341343Y1088647D03*
X348744D03*
Y1095025D03*
X343193Y1091836D03*
X348744Y1101403D03*
X341343D03*
X343193Y1098214D03*
X341343Y1107781D03*
X348744D03*
X343193Y1110970D03*
Y1117348D03*
X348744Y1114159D03*
Y1120537D03*
X341343D03*
Y1126915D03*
X348744D03*
Y1133293D03*
X343193Y1130103D03*
X341343Y1139670D03*
X343193Y1136481D03*
X348744Y1139670D03*
X343193Y1149237D03*
X348744Y1146048D03*
X341343D03*
X348744Y1152426D03*
X337642Y1158804D03*
X341343D03*
X348744D03*
X339492Y1155615D03*
X343193D03*
X346894D03*
X337642Y1165182D03*
X343193Y1161993D03*
X346894D03*
X348744Y1165182D03*
X339938Y1507295D03*
X344663D03*
X349387D03*
X347663Y1521453D03*
X342938D03*
X338214D03*
X338544Y1514243D03*
X343268D03*
X347993D03*
X348214Y1528853D03*
X343489D03*
X338765D03*
X342988Y1536063D03*
X339938Y1542641D03*
X344663D03*
X349387D03*
X338486Y1592380D03*
X342746D03*
X350546D03*
X336726Y1602380D03*
X344506D03*
X348786D03*
X350546Y1624292D03*
X342746D03*
X338486D03*
X348786Y1614292D03*
X344506D03*
X336726D03*
X347440Y1675383D03*
Y1679920D03*
Y1684454D03*
X339566Y1683857D03*
Y1679320D03*
X347440Y1694093D03*
Y1698627D03*
X339566Y1698030D03*
Y1693493D03*
Y1688391D03*
X347440Y1689556D03*
Y1703729D03*
Y1708266D03*
Y1712800D03*
X339566Y1716737D03*
Y1712203D03*
Y1707666D03*
Y1702564D03*
X347440Y1717903D03*
Y1722440D03*
Y1726974D03*
X339566Y1730911D03*
Y1726377D03*
Y1721840D03*
X354295Y1028056D03*
X361697D03*
Y1040812D03*
X356146Y1044001D03*
X354295Y1040812D03*
Y1034434D03*
X356146Y1031245D03*
Y1037623D03*
X361697Y1034434D03*
X354295Y1047190D03*
X361697D03*
X354295Y1053568D03*
Y1059946D03*
X363547Y1056757D03*
X356146D03*
Y1050379D03*
X361697Y1053568D03*
X365398Y1059946D03*
X361697D03*
X352445Y1056757D03*
X356146Y1063135D03*
X354295Y1072702D03*
Y1066324D03*
X356146Y1069513D03*
X361697Y1066324D03*
Y1072702D03*
X356146Y1075891D03*
X354295Y1079080D03*
X361697D03*
X354295Y1085458D03*
X356146Y1088647D03*
X361697Y1085458D03*
X356146Y1082269D03*
X354295Y1091836D03*
X361697D03*
X356146Y1095025D03*
X354295Y1104592D03*
Y1098214D03*
X361697Y1104592D03*
X356146Y1101403D03*
X361697Y1098214D03*
X356146Y1107781D03*
X354295Y1110970D03*
X361697D03*
Y1117348D03*
X356146Y1114159D03*
X354295Y1117348D03*
Y1123726D03*
X356146Y1126915D03*
Y1120537D03*
X361697Y1123726D03*
X356146Y1133293D03*
X361697Y1130103D03*
X354296Y1130105D03*
X354295Y1136481D03*
X356146Y1139670D03*
X361697Y1136481D03*
X354295Y1142859D03*
X361697D03*
Y1149237D03*
X356146Y1146048D03*
X354295Y1149237D03*
X363547Y1165182D03*
X356146D03*
X361697Y1161993D03*
X363547Y1158804D03*
X356146D03*
X359847D03*
X352445D03*
X365398Y1155615D03*
X356146Y1152426D03*
X361697Y1155615D03*
X354295D03*
Y1161993D03*
X354111Y1507295D03*
X358836D03*
X363560D03*
X361836Y1521453D03*
X357111D03*
X352387D03*
X352717Y1514243D03*
X357442D03*
X362166D03*
X362387Y1528853D03*
X357662D03*
X352938D03*
X352437Y1536063D03*
X354111Y1542641D03*
X358836D03*
X363560D03*
X362606Y1592380D03*
X354806D03*
X356566Y1602380D03*
X360846D03*
X354806Y1624292D03*
X360846Y1614292D03*
X356566D03*
X362606Y1624292D03*
X355314Y1683857D03*
Y1679320D03*
Y1688391D03*
Y1698030D03*
Y1693493D03*
Y1716737D03*
Y1712203D03*
Y1707666D03*
Y1702564D03*
Y1730911D03*
Y1726377D03*
Y1721840D03*
X380201Y1028056D03*
X367248Y1031245D03*
Y1044001D03*
X369099Y1034434D03*
Y1040812D03*
X374650Y1031245D03*
X380201Y1040812D03*
Y1034434D03*
X374650Y1037623D03*
Y1044001D03*
X367248Y1050379D03*
X380201Y1047190D03*
X369099Y1053568D03*
Y1059946D03*
X380201Y1053568D03*
X378351Y1056757D03*
X374650Y1050379D03*
Y1056757D03*
X380201Y1059946D03*
X376500D03*
X367248Y1063135D03*
Y1069513D03*
X374650Y1063135D03*
X369099Y1072702D03*
X380201D03*
X374650Y1069513D03*
X367248Y1088647D03*
Y1082269D03*
X374650Y1075891D03*
X369099Y1079080D03*
X380201Y1085458D03*
X374650Y1088647D03*
Y1082269D03*
X367248Y1101403D03*
X369099Y1091836D03*
X374650Y1095025D03*
X369099Y1098214D03*
X380201Y1104592D03*
Y1098214D03*
X374650Y1101403D03*
X367248Y1107781D03*
X374650D03*
X369099Y1110970D03*
Y1117348D03*
X380201D03*
X374650Y1114159D03*
X367248Y1120537D03*
Y1126915D03*
X374650Y1120537D03*
Y1126915D03*
X380201Y1130103D03*
X374650Y1133293D03*
X369099Y1130103D03*
X367248Y1139670D03*
Y1146048D03*
X380201Y1142859D03*
X374650Y1139670D03*
X369099Y1136481D03*
Y1149237D03*
X374650Y1146048D03*
X380201Y1155615D03*
X369099D03*
X372799D03*
X374650Y1152426D03*
X378351Y1158804D03*
X374650D03*
X376500Y1161993D03*
X377523Y1222274D03*
X372730Y1216782D03*
X367697Y1216624D03*
X377733Y1507295D03*
X368285D03*
X373009D03*
X376009Y1521453D03*
X380734D03*
X366560D03*
X371285D03*
X376339Y1514243D03*
X366890D03*
X371615D03*
X376560Y1528853D03*
X367111D03*
X371836D03*
X376059Y1536063D03*
X366610D03*
X377733Y1542641D03*
X368285D03*
X373009D03*
X374666Y1592380D03*
X366866D03*
X380696Y1602380D03*
X368626Y1602286D03*
X372906Y1602380D03*
X374666Y1624292D03*
X380696Y1614292D03*
X372906D03*
X368626D03*
X366866Y1624292D03*
X387603Y1028056D03*
X395004D03*
X393154Y1044001D03*
X385752Y1031245D03*
Y1037623D03*
Y1044001D03*
X395004Y1040812D03*
X387603Y1034434D03*
Y1040812D03*
X395004Y1034434D03*
X393154Y1031245D03*
Y1037623D03*
X395004Y1047190D03*
X387603D03*
Y1053568D03*
X391303Y1059946D03*
X395004Y1053568D03*
X385752Y1050379D03*
X393154Y1056757D03*
Y1050379D03*
X382051Y1063135D03*
Y1069513D03*
X393154Y1063135D03*
X395004Y1066324D03*
X387603D03*
X383902D03*
X391303Y1072702D03*
Y1066324D03*
X393154Y1069513D03*
X382051Y1075891D03*
Y1088647D03*
Y1082269D03*
X393154Y1075891D03*
X387603Y1079080D03*
X383902D03*
X391303D03*
X395004D03*
X393154Y1082269D03*
X391303Y1085458D03*
X393154Y1088647D03*
X382051Y1095025D03*
X383902Y1091836D03*
X393154Y1095025D03*
X391303Y1091836D03*
X395004D03*
X387603D03*
X391303Y1098214D03*
Y1104592D03*
X395004D03*
X387603D03*
X383902D03*
X382051Y1107781D03*
Y1114159D03*
X383902Y1110970D03*
X387603D03*
X393154Y1107781D03*
X391303Y1110970D03*
X395004D03*
X391303Y1117348D03*
X393154Y1114159D03*
X391304Y1130105D03*
X382051Y1126915D03*
Y1120537D03*
Y1133293D03*
X383902Y1123726D03*
X387603D03*
X393154Y1126915D03*
X391303Y1123726D03*
X395004D03*
X393154Y1120537D03*
Y1133293D03*
X382051Y1139670D03*
Y1146048D03*
X393154Y1139670D03*
X395004Y1136481D03*
X391303D03*
X383902D03*
X387603D03*
X391303Y1142859D03*
X393154Y1146048D03*
X395004Y1149237D03*
X383902D03*
X387603D03*
X389453Y1158804D03*
X391303Y1155615D03*
X395004D03*
X383902D03*
X387603D03*
Y1161993D03*
X382458Y1507295D03*
X387182D03*
X390203Y1521453D03*
X385458D03*
X385788Y1514243D03*
X381285Y1528853D03*
X386009D03*
X385508Y1536063D03*
X390839D03*
X382458Y1542641D03*
X387182D03*
X398705Y1028056D03*
X409795Y1028064D03*
X398705Y1034434D03*
X402406Y1040812D03*
X400555Y1031245D03*
Y1037623D03*
Y1044001D03*
X409795Y1034442D03*
Y1040820D03*
X402406Y1047190D03*
X409807D03*
X402406Y1053568D03*
X407957Y1056757D03*
X402406Y1059946D03*
X409807Y1053568D03*
X400555Y1056757D03*
Y1050379D03*
X407957D03*
X398705Y1066324D03*
X404256Y1063135D03*
X402406Y1072702D03*
X404256Y1069513D03*
X406107Y1066324D03*
X409807D03*
X402406D03*
X398705Y1079080D03*
X404256Y1075891D03*
X406107Y1079080D03*
X409807D03*
X402406D03*
X404256Y1088647D03*
X402406Y1085458D03*
X404256Y1082269D03*
X398705Y1091836D03*
Y1104592D03*
X404256Y1095025D03*
X406107Y1091836D03*
X409807D03*
X402406D03*
Y1098214D03*
Y1104592D03*
X398705Y1110970D03*
X404256Y1107781D03*
X406107Y1110970D03*
X409807D03*
X402406D03*
X404256Y1114159D03*
X402406Y1117348D03*
X398705Y1123726D03*
X406107D03*
X409807D03*
X404256Y1120537D03*
X402406Y1123726D03*
X404256Y1126915D03*
Y1133293D03*
X402406Y1130103D03*
X398705Y1136481D03*
Y1149237D03*
X402406Y1142859D03*
X404256Y1139670D03*
X406107Y1136481D03*
X409807D03*
X402406D03*
X404256Y1146048D03*
X406107Y1149237D03*
X409807D03*
X398705Y1155615D03*
Y1161993D03*
X406107Y1155615D03*
X409807D03*
X402406D03*
X400555Y1158804D03*
X409807Y1161993D03*
X400555Y1165182D03*
X424598Y1040820D03*
X417197D03*
X413508Y1059946D03*
X417209Y1047190D03*
X424610D03*
Y1053568D03*
X422760Y1056757D03*
X424610Y1059946D03*
X417209Y1053568D03*
X415358Y1056757D03*
Y1050379D03*
X422760D03*
X413508Y1072702D03*
Y1066324D03*
X415358Y1063135D03*
X424610Y1072702D03*
Y1066324D03*
X420910D03*
X417209D03*
X415358Y1069513D03*
X413508Y1079080D03*
Y1085458D03*
X415358Y1075891D03*
X420910Y1079080D03*
X424610D03*
X417209D03*
X424610Y1085458D03*
X415358Y1088647D03*
Y1082269D03*
X413508Y1091836D03*
Y1098214D03*
Y1104592D03*
X415358Y1095025D03*
X420910Y1091836D03*
X424610D03*
X417209D03*
X420910Y1104592D03*
X424610D03*
Y1098214D03*
X417209Y1104592D03*
X415358Y1101403D03*
X413508Y1110970D03*
Y1117348D03*
X415358Y1107781D03*
X424610Y1110970D03*
X420910D03*
X417209D03*
X424610Y1117348D03*
X415358Y1114159D03*
Y1120537D03*
Y1126915D03*
X424610Y1123726D03*
X420910D03*
X417209D03*
X415358Y1133293D03*
X413508Y1123726D03*
Y1130103D03*
X424611Y1130105D03*
X413508Y1142859D03*
Y1136481D03*
X424610Y1142859D03*
Y1136481D03*
X420910D03*
X415358Y1139670D03*
X417209Y1136481D03*
X420910Y1149237D03*
X417209D03*
X415358Y1146048D03*
X413508Y1155615D03*
X411658Y1158804D03*
X424610Y1155615D03*
X420910D03*
X417209D03*
X422760Y1158804D03*
Y1165182D03*
X420910Y1161993D03*
X430162Y1056757D03*
Y1050379D03*
X432012Y1047190D03*
Y1053568D03*
X435713Y1059946D03*
X426461Y1063135D03*
X430162D03*
X426461Y1069513D03*
X433862Y1063135D03*
X435713Y1072702D03*
Y1066324D03*
X430162Y1075891D03*
X426461D03*
X430162Y1088647D03*
X426461D03*
Y1082269D03*
X433862Y1075891D03*
X435713Y1079080D03*
Y1085458D03*
X433862Y1088647D03*
X426461Y1095025D03*
X430162Y1101403D03*
X426461D03*
X435713Y1091836D03*
Y1098214D03*
Y1104592D03*
X433862Y1101403D03*
X430162Y1107781D03*
X426461D03*
Y1114159D03*
X433862Y1107781D03*
X435713Y1110970D03*
Y1117348D03*
X426461Y1126915D03*
X430162Y1120537D03*
X426461D03*
X430162Y1133293D03*
X426461D03*
X435713Y1123726D03*
X433862Y1120537D03*
X435713Y1130103D03*
X433862Y1133293D03*
X426461Y1139670D03*
Y1146048D03*
X428311Y1149237D03*
X435713Y1136481D03*
Y1142859D03*
Y1149237D03*
X432012D03*
X430162Y1158804D03*
X435713Y1155615D03*
Y1161993D03*
X454204Y1040820D03*
X446790Y1047190D03*
Y1053568D03*
Y1059946D03*
X454192Y1047190D03*
X448641Y1056757D03*
X454192Y1053568D03*
X448641Y1050379D03*
X446790Y1066324D03*
Y1072702D03*
X452341Y1063135D03*
X448641D03*
X446790Y1079080D03*
Y1085458D03*
X452341Y1075891D03*
X448641D03*
X452341Y1088647D03*
X448641D03*
X446790Y1091836D03*
Y1098214D03*
Y1104592D03*
X452341Y1101403D03*
X448641D03*
X446790Y1110970D03*
Y1117348D03*
X452341Y1107781D03*
X448641D03*
X446790Y1123726D03*
Y1130103D03*
X448641Y1120537D03*
X452341D03*
Y1133293D03*
X448641D03*
X446790Y1136481D03*
Y1142859D03*
Y1149237D03*
X454192D03*
X450491D03*
X446790Y1155615D03*
Y1161993D03*
X454192Y1155615D03*
X447120Y1507512D03*
X452427Y1507295D03*
X450703Y1521453D03*
X451033Y1514243D03*
X449861Y1519195D03*
X451254Y1528853D03*
X450752Y1536063D03*
X441752Y1523810D03*
Y1528725D03*
X452427Y1542641D03*
X447224Y1542425D03*
X450139Y1592380D03*
Y1624292D03*
X469007Y1040820D03*
X461606D03*
X461593Y1047190D03*
Y1053568D03*
X456042Y1056757D03*
X457893Y1059946D03*
X456042Y1050379D03*
X468995Y1047190D03*
Y1053568D03*
Y1059946D03*
X463444Y1056757D03*
Y1050379D03*
X456042Y1063135D03*
Y1069513D03*
X457893Y1072702D03*
Y1066324D03*
X461593D03*
X467145Y1063135D03*
X468995Y1072702D03*
Y1066324D03*
X467145Y1069513D03*
X465294Y1066324D03*
X456042Y1075891D03*
X461593Y1079080D03*
X457893D03*
X456042Y1088647D03*
X457893Y1085458D03*
X456042Y1082269D03*
X467145Y1075891D03*
X468995Y1079080D03*
X465294D03*
X468995Y1085458D03*
X467145Y1088647D03*
Y1082269D03*
X457893Y1091836D03*
X461593D03*
X456042Y1095025D03*
X457893Y1098214D03*
X456042Y1101403D03*
X457893Y1104592D03*
X461593D03*
X467145Y1095025D03*
X468995Y1091836D03*
X465294D03*
X468995Y1104592D03*
X465294D03*
X468995Y1098214D03*
X467145Y1101403D03*
X456042Y1107781D03*
X457893Y1110970D03*
X461593D03*
X457893Y1117348D03*
X456042Y1114159D03*
X468995Y1110970D03*
X465294D03*
X467145Y1107781D03*
Y1114159D03*
X468995Y1117348D03*
X456042Y1126915D03*
X461593Y1123726D03*
X457893D03*
X456042Y1120537D03*
Y1133293D03*
X468995Y1123726D03*
X467145Y1120537D03*
X465294Y1123726D03*
X467145Y1126915D03*
X468995Y1130103D03*
X467145Y1133293D03*
X457893Y1130104D03*
X456042Y1139670D03*
X461593Y1136481D03*
X457893D03*
Y1142859D03*
X456042Y1146048D03*
X461593Y1149237D03*
X468995Y1142859D03*
X467145Y1139670D03*
X468995Y1136481D03*
X465294D03*
X467145Y1146048D03*
X465294Y1149237D03*
X459743Y1158804D03*
Y1152426D03*
X465294Y1155615D03*
X457152Y1507295D03*
X461876D03*
X466600D03*
X469600Y1521453D03*
X464876D03*
X460152D03*
X455427D03*
X455757Y1514243D03*
X460482D03*
X465206D03*
X469931D03*
X470151Y1528853D03*
X465427D03*
X460703D03*
X455978D03*
X464926Y1536063D03*
X460202D03*
X455477D03*
X466600Y1542641D03*
X457152D03*
X461876D03*
X469999Y1592380D03*
X457939D03*
X462199D03*
X463959Y1602380D03*
X456179D03*
X468239D03*
X457939Y1624292D03*
X463959Y1614292D03*
X456179D03*
X468239D03*
X469999Y1624292D03*
X462199D03*
X480097Y1028056D03*
X478247Y1037623D03*
Y1044001D03*
X480097Y1034434D03*
X483798Y1040812D03*
X481948Y1031245D03*
X476400Y1040820D03*
X476397Y1047190D03*
Y1053568D03*
X470845Y1056757D03*
X478247D03*
X470845Y1050379D03*
X478247D03*
X483798Y1047190D03*
Y1053568D03*
X480097Y1059946D03*
X478247Y1063135D03*
X472696Y1066324D03*
X476397D03*
X478247Y1069513D03*
X483798Y1066324D03*
X480097Y1072702D03*
Y1066324D03*
X478247Y1075891D03*
X476397Y1079080D03*
X472696D03*
X478247Y1088647D03*
Y1082269D03*
X483798Y1079080D03*
X480097D03*
Y1085458D03*
Y1104592D03*
X483798D03*
X480097Y1098214D03*
X478247Y1095025D03*
X472696Y1091836D03*
X476397D03*
X480097D03*
X483798D03*
X472696Y1110970D03*
X476397D03*
X478247Y1107781D03*
Y1114159D03*
X483798Y1110970D03*
X480097D03*
Y1117348D03*
X476397Y1123726D03*
X472696D03*
X478247Y1120537D03*
Y1126915D03*
Y1133293D03*
X483798Y1123726D03*
X480097D03*
Y1130103D03*
X478247Y1139670D03*
X476397Y1136481D03*
X472696D03*
X476397Y1149237D03*
X472696D03*
X478247Y1146048D03*
X483798Y1136481D03*
X480097D03*
Y1142859D03*
X483798Y1149237D03*
X476397Y1155615D03*
X474546Y1152426D03*
X470845Y1158804D03*
X481948D03*
X471325Y1507295D03*
X476049D03*
X480774D03*
X483774Y1521453D03*
X479049D03*
X474325D03*
X474655Y1514243D03*
X479379D03*
X484104D03*
X484325Y1528853D03*
X479600D03*
X474876D03*
X479099Y1536063D03*
X476049Y1542641D03*
X471325D03*
X480774D03*
X482059Y1592380D03*
X474259D03*
X476019Y1602380D03*
X480299D03*
X482059Y1624292D03*
X476019Y1614292D03*
X474259Y1624292D03*
X480299Y1614292D03*
X494901Y1028056D03*
X487499D03*
X485649Y1044001D03*
X494901Y1034434D03*
X491200Y1040812D03*
X487499Y1034434D03*
X489349Y1031245D03*
X493050Y1037623D03*
X485649D03*
X493050Y1044001D03*
X496751Y1031245D03*
X498601Y1040812D03*
X491200Y1047190D03*
X493050Y1056757D03*
X491200Y1059946D03*
Y1053568D03*
X485649Y1056757D03*
X493050Y1050379D03*
X485649D03*
X498601Y1047190D03*
Y1053568D03*
X489349Y1063135D03*
X494901Y1066324D03*
X491200D03*
X487499D03*
X491200Y1072702D03*
X489349Y1069513D03*
X498601Y1066324D03*
X489349Y1082269D03*
X498601Y1079080D03*
X494901D03*
X489349Y1075891D03*
X487499Y1079080D03*
X491200D03*
Y1085458D03*
X489349Y1088647D03*
X494901Y1091836D03*
X487499D03*
X491200D03*
X489349Y1095025D03*
X494901Y1104592D03*
X491200Y1098214D03*
Y1104592D03*
X487499D03*
X498601Y1091836D03*
Y1104592D03*
X496751Y1101403D03*
X491200Y1110970D03*
X489349Y1114159D03*
X491200Y1117348D03*
X498601Y1110970D03*
X494901D03*
X489349Y1107781D03*
X487499Y1110970D03*
X494901Y1123726D03*
X489349Y1126915D03*
X491200Y1123726D03*
X487499D03*
X489349Y1120537D03*
X491200Y1130103D03*
X489349Y1133293D03*
X498601Y1123726D03*
X494901Y1136481D03*
X489349Y1139670D03*
X491200Y1136481D03*
X487499D03*
X491200Y1142859D03*
X494901Y1149237D03*
X489349Y1146048D03*
X487499Y1149237D03*
X498601Y1136481D03*
Y1149237D03*
X487499Y1155615D03*
X485649Y1152426D03*
X493050Y1158804D03*
X498601Y1155615D03*
X496751Y1152426D03*
X485498Y1507295D03*
X490222D03*
X499671D03*
X494947D03*
X497947Y1521453D03*
X493222D03*
X488498D03*
X488828Y1514243D03*
X493553D03*
X498277D03*
X498498Y1528853D03*
X493773D03*
X489049D03*
X488548Y1536063D03*
X494947Y1542641D03*
X485498D03*
X490222D03*
X499671D03*
X498379Y1592380D03*
X486319D03*
X494119D03*
X488079Y1602380D03*
X492359D03*
X498379Y1624292D03*
X488079Y1614292D03*
X486319Y1624292D03*
X494119D03*
X492359Y1614292D03*
X497440Y1684454D03*
Y1679920D03*
Y1675383D03*
Y1698627D03*
Y1694093D03*
Y1689556D03*
Y1712800D03*
Y1708266D03*
Y1703729D03*
Y1726974D03*
Y1722440D03*
Y1717903D03*
X502302Y1028056D03*
X513405D03*
X507853Y1037623D03*
X500452D03*
X502302Y1034434D03*
X507853Y1044001D03*
X500452D03*
X507853Y1031245D03*
X513405Y1034434D03*
Y1040812D03*
X507853Y1056757D03*
Y1050379D03*
X500452Y1056757D03*
X504153D03*
X500452Y1050379D03*
X502302Y1059946D03*
X506003D03*
X513405Y1053568D03*
Y1059946D03*
X507853Y1063135D03*
X500452D03*
X507853Y1069513D03*
X500452D03*
X502302Y1072702D03*
X513405D03*
X507853Y1075891D03*
X500452D03*
X507853Y1088647D03*
X500452D03*
X502302Y1085458D03*
X507853Y1082269D03*
X500452D03*
X513405Y1079080D03*
X507853Y1095025D03*
X500452D03*
X502302Y1098214D03*
X507853Y1101403D03*
X502302Y1104592D03*
X513405Y1091836D03*
Y1098214D03*
X507853Y1107781D03*
X500452D03*
X507853Y1114159D03*
X502302Y1117348D03*
X500452Y1114159D03*
X513405Y1110970D03*
Y1117348D03*
X507853Y1120537D03*
X500452D03*
X507853Y1126915D03*
X500452D03*
X507853Y1133293D03*
X500452D03*
X502302Y1130103D03*
X513405Y1130104D03*
X507853Y1139670D03*
X500452D03*
X502302Y1142859D03*
X507853Y1146048D03*
X500452D03*
X513405Y1136481D03*
Y1149237D03*
X511554Y1165182D03*
X509704Y1155615D03*
X507853Y1152426D03*
X502302Y1155615D03*
X507853Y1158804D03*
X504153D03*
X513405Y1155615D03*
X504396Y1507295D03*
X509120D03*
X513844D03*
X512120Y1521453D03*
X507396D03*
X502671D03*
X503001Y1514243D03*
X507726D03*
X512450D03*
X512671Y1528853D03*
X507947D03*
X503222D03*
X512170Y1536063D03*
X502721D03*
X513844Y1542641D03*
X504396D03*
X509120D03*
X510439Y1592380D03*
X506179D03*
X512199Y1602380D03*
X500139D03*
X504419D03*
X512199Y1614292D03*
X500139D03*
X506179Y1624292D03*
X510439D03*
X504419Y1614292D03*
X505314Y1679320D03*
Y1683857D03*
X513188Y1684454D03*
Y1679920D03*
Y1675383D03*
X505314Y1688391D03*
Y1693493D03*
Y1698030D03*
X513188Y1698627D03*
Y1694093D03*
Y1689556D03*
X505314Y1707666D03*
Y1712203D03*
X513188Y1712800D03*
Y1708266D03*
Y1703729D03*
X505314Y1716737D03*
Y1702564D03*
Y1721840D03*
Y1726377D03*
Y1730911D03*
X513188Y1726974D03*
Y1722440D03*
Y1717903D03*
X520806Y1028056D03*
X528208D03*
X526357Y1037623D03*
Y1044001D03*
Y1031245D03*
X515255D03*
X520806Y1040812D03*
Y1034434D03*
X515255Y1044001D03*
X528208Y1040812D03*
Y1034434D03*
X520806Y1047190D03*
X526357Y1050379D03*
Y1056757D03*
X520806Y1053568D03*
X515255Y1050379D03*
X518956Y1056757D03*
X520806Y1059946D03*
X517105D03*
X528208Y1047190D03*
Y1053568D03*
Y1059946D03*
X526357Y1063135D03*
X515255D03*
X526357Y1069513D03*
X520806Y1066324D03*
Y1072702D03*
X515255Y1069513D03*
X528208Y1066324D03*
Y1072702D03*
X526357Y1075891D03*
X520806Y1079080D03*
X526357Y1088647D03*
Y1082269D03*
X520806Y1085458D03*
X515255Y1088647D03*
Y1082269D03*
X528208Y1079080D03*
Y1085458D03*
X526357Y1095025D03*
X520806Y1091836D03*
X526357Y1101403D03*
X520806Y1104592D03*
Y1098214D03*
X515255Y1101403D03*
X528208Y1091836D03*
Y1104592D03*
Y1098214D03*
X526357Y1107781D03*
X520806Y1110970D03*
X515255Y1107781D03*
X526357Y1114159D03*
X520806Y1117348D03*
X528208Y1110970D03*
Y1117348D03*
Y1130104D03*
X526357Y1120537D03*
Y1126915D03*
X520806Y1123726D03*
X515255Y1120537D03*
Y1126915D03*
X526357Y1133293D03*
X520806Y1130103D03*
X528208Y1123726D03*
X515255Y1139670D03*
X520806Y1142859D03*
X526357Y1139670D03*
X520806Y1136481D03*
X526357Y1146048D03*
X520806Y1149237D03*
X515255Y1146048D03*
X528208Y1136481D03*
Y1142859D03*
Y1149237D03*
X526357Y1152426D03*
Y1158804D03*
X520806Y1155615D03*
X517105D03*
X522657Y1158804D03*
X515255D03*
X517105Y1161993D03*
X528208Y1155615D03*
X518569Y1507295D03*
X523293D03*
X526314Y1521453D03*
X521569D03*
X516845D03*
X521899Y1514243D03*
X522120Y1528853D03*
X517396D03*
X521619Y1536063D03*
X526950D03*
X523293Y1542641D03*
X518569D03*
X518239Y1592380D03*
X522499D03*
X524259Y1602380D03*
X528539D03*
X516479D03*
X524259Y1614292D03*
X518239Y1624292D03*
X522499D03*
X528539Y1614292D03*
X516479D03*
X521062Y1679320D03*
Y1683857D03*
X528936Y1684454D03*
Y1679920D03*
Y1675383D03*
X521062Y1688391D03*
Y1693493D03*
Y1698030D03*
X528936Y1698627D03*
Y1694093D03*
Y1689556D03*
X521062Y1716737D03*
Y1702564D03*
Y1707666D03*
Y1712203D03*
X528936Y1712800D03*
Y1708266D03*
Y1703729D03*
X521062Y1721840D03*
Y1726377D03*
Y1730911D03*
X528936Y1726974D03*
Y1722440D03*
Y1717903D03*
X539310Y1028056D03*
X541160Y1031245D03*
X533759D03*
X539310Y1034434D03*
Y1040812D03*
X533759Y1037623D03*
X541160Y1044001D03*
X533759D03*
X543011Y1059946D03*
X530058Y1056757D03*
X541160Y1050379D03*
X539310Y1053568D03*
X533759Y1050379D03*
Y1056757D03*
X539310Y1059946D03*
X531908D03*
X541160Y1063135D03*
X533759D03*
X541160Y1069513D03*
X539310Y1072702D03*
X533759Y1069513D03*
Y1075891D03*
X539310Y1079080D03*
X541160Y1088647D03*
X533759D03*
X541160Y1082269D03*
X533759D03*
X539310Y1091836D03*
X533759Y1095025D03*
X539310Y1098214D03*
X541160Y1101403D03*
X533759D03*
X541160Y1107781D03*
X533759D03*
X539310Y1110970D03*
Y1117348D03*
X533759Y1114159D03*
X541160Y1120537D03*
X533759D03*
X541160Y1126915D03*
X533759D03*
X539310Y1130103D03*
X533759Y1133293D03*
X541160Y1139670D03*
X539310Y1136481D03*
X533759Y1139670D03*
Y1146048D03*
X541160D03*
X539310Y1149237D03*
X543011Y1155615D03*
X533759Y1158804D03*
X530058D03*
X539310Y1155615D03*
X535609D03*
X533759Y1152426D03*
X543011Y1161993D03*
X542359Y1592380D03*
X530299D03*
X534559D03*
X536319Y1602380D03*
X540599D03*
X542359Y1624292D03*
X536319Y1614292D03*
X530299Y1624292D03*
X534559D03*
X540599Y1614292D03*
X536810Y1679320D03*
Y1683857D03*
X544684Y1684454D03*
Y1679920D03*
Y1675383D03*
X536810Y1688391D03*
Y1693493D03*
Y1698030D03*
X544684Y1698627D03*
Y1694093D03*
Y1689556D03*
X536810Y1716737D03*
Y1702564D03*
Y1707666D03*
Y1712203D03*
X544684Y1712800D03*
Y1708266D03*
Y1703729D03*
X536810Y1721840D03*
Y1726377D03*
Y1730911D03*
X544684Y1726974D03*
Y1722440D03*
Y1717903D03*
X554113Y1028056D03*
X546712D03*
Y1040812D03*
Y1034434D03*
X552263Y1031245D03*
X554113Y1040812D03*
X552263Y1037623D03*
X554113Y1034434D03*
X552263Y1044001D03*
X559664Y1031245D03*
Y1037623D03*
Y1044001D03*
X546712Y1047190D03*
X554113D03*
X544861Y1056757D03*
X546712Y1053568D03*
Y1059946D03*
X552263Y1056757D03*
X555964D03*
X554113Y1053568D03*
X552263Y1050379D03*
X554113Y1059946D03*
X557814D03*
X559664Y1050379D03*
Y1056757D03*
X552263Y1063135D03*
X546712Y1072702D03*
Y1066324D03*
X552263Y1069513D03*
X554113Y1066324D03*
Y1072702D03*
X559664Y1063135D03*
Y1069513D03*
X552263Y1075891D03*
X546712Y1079080D03*
X554113D03*
X546712Y1085458D03*
X552263Y1088647D03*
X554113Y1085458D03*
X552263Y1082269D03*
X559664Y1075891D03*
Y1088647D03*
Y1082269D03*
X546712Y1091836D03*
X554113D03*
X552263Y1095025D03*
Y1101403D03*
X554113Y1098214D03*
X546712Y1104592D03*
Y1098214D03*
X554113Y1104592D03*
X559664Y1095025D03*
Y1101403D03*
X552263Y1107781D03*
X554113Y1110970D03*
X546712D03*
X554113Y1117348D03*
X552263Y1114159D03*
X546712Y1117348D03*
X559664Y1107781D03*
Y1114159D03*
X546712Y1123726D03*
X554113D03*
X552263Y1120537D03*
Y1126915D03*
Y1133293D03*
X554113Y1130103D03*
X559664Y1120537D03*
Y1126915D03*
Y1133293D03*
X546712Y1130104D03*
X552263Y1139670D03*
X554113Y1136481D03*
X546712D03*
X554113Y1142859D03*
X546712D03*
Y1149237D03*
X552263Y1146048D03*
X554113Y1149237D03*
X559664Y1139670D03*
Y1146048D03*
X555964Y1165182D03*
X554113Y1155615D03*
X552263Y1152426D03*
X555964Y1158804D03*
X552263D03*
X548562D03*
X546712Y1155615D03*
X554113Y1161993D03*
X559664Y1152426D03*
Y1158804D03*
X558679Y1592380D03*
X546619D03*
X554419D03*
X548379Y1602380D03*
X552659D03*
X558679Y1624292D03*
X548379Y1614292D03*
X546619Y1624292D03*
X554419D03*
X552659Y1614292D03*
X552558Y1679320D03*
Y1683857D03*
Y1688391D03*
Y1693493D03*
Y1698030D03*
Y1716737D03*
Y1702564D03*
Y1707666D03*
Y1712203D03*
Y1721840D03*
Y1726377D03*
Y1730911D03*
X565216Y1028056D03*
X572617D03*
X567066Y1031245D03*
X565215Y1034434D03*
Y1040812D03*
X572617Y1034434D03*
Y1040812D03*
X567066Y1044001D03*
X565215Y1059946D03*
X572617Y1047190D03*
X567066Y1050379D03*
X572617Y1053568D03*
X570767Y1056757D03*
X565215Y1053568D03*
X572617Y1059946D03*
X568916D03*
X567066Y1063135D03*
X572617Y1066324D03*
Y1072702D03*
X567066Y1069513D03*
X565215Y1072702D03*
Y1079080D03*
X572617D03*
X567066Y1088647D03*
X572617Y1085458D03*
X567066Y1082269D03*
X572617Y1091836D03*
X565215D03*
X572617Y1104592D03*
Y1098214D03*
X567066Y1101403D03*
X565215Y1098214D03*
X567066Y1107781D03*
X572617Y1110970D03*
X565215D03*
X572617Y1117348D03*
X565215D03*
X572617Y1123726D03*
X567066Y1120537D03*
Y1126915D03*
X572617Y1130103D03*
X565215D03*
X572617Y1136481D03*
X565215Y1149237D03*
X572617D03*
X567066Y1146048D03*
X572617Y1142859D03*
X567066Y1139670D03*
X565215Y1136481D03*
X574467Y1158804D03*
X565215Y1155615D03*
X568916D03*
X572617D03*
X561515D03*
X565215Y1161993D03*
X569814Y1523810D03*
Y1528725D03*
X570739Y1592380D03*
X566479D03*
X572499Y1602380D03*
X560439D03*
X564719D03*
X572499Y1614292D03*
X570739Y1624292D03*
X560439Y1614292D03*
X566479Y1624292D03*
X564719Y1614292D03*
X572243Y1683857D03*
X564369Y1684454D03*
Y1679920D03*
Y1675383D03*
X572243Y1679320D03*
X564369Y1694093D03*
Y1689556D03*
X572243Y1688391D03*
Y1693493D03*
Y1698030D03*
X564369Y1698627D03*
X572243Y1702564D03*
Y1707666D03*
Y1712203D03*
X564369Y1712800D03*
Y1708266D03*
Y1703729D03*
X572243Y1716737D03*
Y1726377D03*
Y1730911D03*
X564369Y1726974D03*
Y1722440D03*
Y1717903D03*
X572243Y1721840D03*
X577728Y906182D03*
Y912560D03*
Y918938D03*
Y925316D03*
Y931694D03*
Y938072D03*
Y944450D03*
Y950828D03*
Y957206D03*
Y963584D03*
Y969962D03*
Y976340D03*
Y982718D03*
Y989096D03*
Y995474D03*
Y1008230D03*
Y1001852D03*
X578909Y1030198D03*
Y1036576D03*
Y1042954D03*
Y1049332D03*
Y1055710D03*
Y1062088D03*
Y1074844D03*
Y1068466D03*
Y1087600D03*
Y1081222D03*
Y1093978D03*
Y1100356D03*
Y1106734D03*
Y1113112D03*
Y1119490D03*
Y1125868D03*
Y1132246D03*
Y1138623D03*
Y1145001D03*
Y1151379D03*
X578168Y1158804D03*
X575182Y1507514D03*
X580489Y1507295D03*
X585214D03*
X588214Y1521453D03*
X583489D03*
X578765D03*
X579095Y1514243D03*
X583819D03*
X588544D03*
X577923Y1519195D03*
X588765Y1528853D03*
X584040D03*
X579316D03*
X588264Y1536063D03*
X583539D03*
X578814D03*
X585214Y1542641D03*
X580489D03*
X575286Y1542425D03*
X578539Y1592380D03*
X582799D03*
X584559Y1602380D03*
X588839D03*
X576779D03*
X584559Y1614292D03*
X582799Y1624292D03*
X578539D03*
X588839Y1614292D03*
X576779D03*
X587991Y1679320D03*
Y1683857D03*
X580117Y1684454D03*
Y1679920D03*
Y1675383D03*
X587991Y1688391D03*
Y1693493D03*
Y1698030D03*
X580117Y1698627D03*
Y1694093D03*
Y1689556D03*
X587991Y1716737D03*
Y1702564D03*
Y1707666D03*
Y1712203D03*
X580117Y1712800D03*
Y1708266D03*
Y1703729D03*
X587991Y1721840D03*
Y1726377D03*
Y1730911D03*
X580117Y1726974D03*
Y1722440D03*
Y1717903D03*
X589938Y1507295D03*
X594662D03*
X599387D03*
X604111D03*
X602387Y1521453D03*
X597662D03*
X592938D03*
X593268Y1514243D03*
X597993D03*
X602717D03*
X602938Y1528853D03*
X598213D03*
X593489D03*
X592988Y1536063D03*
X589938Y1542641D03*
X604111D03*
X599387D03*
X594662D03*
X602659Y1592380D03*
X590599D03*
X594859D03*
X596619Y1602380D03*
X600899D03*
X602659Y1624292D03*
X596619Y1614292D03*
X594859Y1624292D03*
X590599D03*
X600899Y1614292D03*
X603739Y1679320D03*
Y1683857D03*
X595865Y1684454D03*
Y1679920D03*
Y1675383D03*
X603739Y1688391D03*
Y1693493D03*
Y1698030D03*
X595865Y1698627D03*
Y1694093D03*
Y1689556D03*
X603739Y1716737D03*
Y1702564D03*
Y1707666D03*
Y1712203D03*
X595865Y1712800D03*
Y1708266D03*
Y1703729D03*
X603739Y1721840D03*
Y1726377D03*
Y1730911D03*
X595865Y1726974D03*
Y1722440D03*
Y1717903D03*
X608836Y1507295D03*
X613560D03*
X618284D03*
X616560Y1521453D03*
X611836D03*
X607111D03*
X607441Y1514243D03*
X612166D03*
X616890D03*
X617111Y1528853D03*
X612387D03*
X607662D03*
X607161Y1536063D03*
X616610D03*
X613560Y1542641D03*
X618284D03*
X608836D03*
X618979Y1592380D03*
X614719D03*
X606919D03*
X608679Y1602380D03*
X612959D03*
X618979Y1624292D03*
X608679Y1614292D03*
X606919Y1624292D03*
X614719D03*
X612959Y1614292D03*
X611613Y1684454D03*
Y1679920D03*
Y1675383D03*
Y1698627D03*
Y1694093D03*
Y1689556D03*
Y1712800D03*
Y1708266D03*
Y1703729D03*
Y1726974D03*
Y1722440D03*
Y1717903D03*
X623009Y1507295D03*
X627733D03*
X632458D03*
X630733Y1521453D03*
X626009D03*
X621284D03*
X621615Y1514243D03*
X626339D03*
X631063D03*
X631284Y1528853D03*
X626560D03*
X621835D03*
X630783Y1536063D03*
X632458Y1542641D03*
X627733D03*
X623009D03*
X631039Y1592380D03*
X626779D03*
X632799Y1602286D03*
X620739Y1602380D03*
X625019D03*
X631039Y1624292D03*
X632799Y1614292D03*
X626779Y1624292D03*
X620739Y1614292D03*
X625019D03*
X619487Y1679320D03*
Y1683857D03*
Y1688391D03*
Y1693493D03*
Y1698030D03*
Y1716737D03*
Y1702564D03*
Y1707666D03*
Y1712203D03*
Y1721840D03*
Y1726377D03*
Y1730911D03*
X637182Y1507295D03*
X641906D03*
X646631D03*
X644907Y1521453D03*
X640182D03*
X635458D03*
X635788Y1514243D03*
X640512D03*
X645458Y1528853D03*
X640733D03*
X636009D03*
X640232Y1536063D03*
X646631Y1542641D03*
X641906D03*
X637182D03*
X638839Y1592380D03*
X644869Y1602380D03*
X637079D03*
X644869Y1614292D03*
X638839Y1624292D03*
X637079Y1614292D03*
X651355Y1507295D03*
X654376Y1521453D03*
X649631D03*
X649961Y1514243D03*
X650182Y1528853D03*
X649681Y1536063D03*
X655012D03*
X651355Y1542641D03*
X1185452Y1556810D03*
Y1561725D03*
X1190820Y1540512D03*
X1194733Y1547243D03*
X1196127Y1540295D03*
X1199457Y1547243D03*
X1193561Y1552195D03*
X1199127Y1554453D03*
X1194403D03*
X1199678Y1561853D03*
X1194954D03*
X1199177Y1569063D03*
X1196127Y1575641D03*
X1194452Y1569063D03*
X1190924Y1575425D03*
X1193839Y1625380D03*
X1199879Y1635380D03*
Y1647292D03*
X1193839Y1657292D03*
X1200852Y1540295D03*
X1204182Y1547243D03*
X1205576Y1540295D03*
X1208906Y1547243D03*
X1210300Y1540295D03*
X1213631Y1547243D03*
X1215025Y1540295D03*
X1213300Y1554453D03*
X1208576D03*
X1203852D03*
X1213851Y1561853D03*
X1209127D03*
X1204403D03*
X1210300Y1575641D03*
X1208626Y1569063D03*
X1203902D03*
X1200852Y1575641D03*
X1205576D03*
X1215025D03*
X1205899Y1625380D03*
X1201639D03*
X1213699D03*
X1207659Y1635380D03*
X1211939D03*
X1207659Y1647292D03*
X1211939D03*
X1201639Y1657292D03*
X1205899D03*
X1213699D03*
X1218355Y1547243D03*
X1219749Y1540295D03*
X1223079Y1547243D03*
X1227804D03*
X1229198Y1540295D03*
X1224474D03*
X1227474Y1554453D03*
X1222749D03*
X1218025D03*
X1228025Y1561853D03*
X1223300D03*
X1218576D03*
X1222799Y1569063D03*
X1219749Y1575641D03*
X1224474D03*
X1229198D03*
X1217959Y1625380D03*
X1225759D03*
X1230019D03*
X1223999Y1635380D03*
X1219719D03*
X1223999Y1647292D03*
X1219719D03*
X1217959Y1657292D03*
X1230019D03*
X1225759D03*
X1232528Y1547243D03*
X1233922Y1540295D03*
X1237253Y1547243D03*
X1241977D03*
X1243371Y1540295D03*
X1238647D03*
X1241647Y1554453D03*
X1236922D03*
X1232198D03*
X1242198Y1561853D03*
X1237473D03*
X1232749D03*
X1238647Y1575641D03*
X1232248Y1569063D03*
X1233922Y1575641D03*
X1243371D03*
X1237819Y1625380D03*
X1242079D03*
X1231779Y1635380D03*
X1236059D03*
X1243839D03*
X1236059Y1647292D03*
X1231779D03*
X1243839D03*
X1237819Y1657292D03*
X1242079D03*
X1241140Y1684454D03*
Y1679920D03*
Y1675383D03*
Y1698627D03*
Y1694093D03*
Y1689556D03*
Y1712800D03*
Y1708266D03*
Y1703729D03*
Y1726974D03*
Y1722440D03*
Y1717903D03*
X1246701Y1547243D03*
X1248096Y1540295D03*
X1251426Y1547243D03*
X1252820Y1540295D03*
X1256150Y1547243D03*
X1257544Y1540295D03*
X1255820Y1554453D03*
X1251096D03*
X1246371D03*
X1256371Y1561853D03*
X1251647D03*
X1246922D03*
X1257544Y1575641D03*
X1255870Y1569063D03*
X1246421D03*
X1248096Y1575641D03*
X1252820D03*
X1249879Y1625380D03*
X1254139D03*
X1248119Y1635380D03*
X1255899D03*
X1260179D03*
X1248119Y1647292D03*
X1255899D03*
X1260179D03*
X1254139Y1657292D03*
X1249879D03*
X1249014Y1679320D03*
Y1683857D03*
X1256888Y1684454D03*
Y1679920D03*
Y1675383D03*
X1249014Y1688391D03*
Y1693493D03*
Y1698030D03*
X1256888Y1698627D03*
Y1694093D03*
Y1689556D03*
Y1703729D03*
X1249014Y1716737D03*
Y1702564D03*
Y1707666D03*
Y1712203D03*
X1256888Y1712800D03*
Y1708266D03*
X1249014Y1721840D03*
Y1726377D03*
Y1730911D03*
X1256888Y1726974D03*
Y1722440D03*
Y1717903D03*
X1262269Y1540295D03*
X1265599Y1547243D03*
X1266993Y1540295D03*
X1270014Y1554453D03*
X1265269D03*
X1260545D03*
X1265820Y1561853D03*
X1261096D03*
X1270650Y1569063D03*
X1266993Y1575641D03*
X1265319Y1569063D03*
X1262269Y1575641D03*
X1266199Y1625380D03*
X1261939D03*
X1273999D03*
X1267959Y1635380D03*
X1272239D03*
X1267959Y1647292D03*
X1272239D03*
X1266199Y1657292D03*
X1261939D03*
X1273999D03*
X1264762Y1679320D03*
Y1683857D03*
X1272636Y1684454D03*
Y1679920D03*
Y1675383D03*
X1264762Y1688391D03*
Y1693493D03*
Y1698030D03*
X1272636Y1698627D03*
Y1694093D03*
Y1689556D03*
X1264762Y1716737D03*
Y1702564D03*
Y1707666D03*
Y1712203D03*
X1272636Y1712800D03*
Y1708266D03*
Y1703729D03*
X1264762Y1721840D03*
Y1726377D03*
Y1730911D03*
X1272636Y1726974D03*
Y1722440D03*
Y1717903D03*
X1286028Y1028055D03*
Y1034433D03*
Y1040811D03*
Y1047189D03*
Y1053567D03*
X1287878Y1056756D03*
X1289729Y1059945D03*
X1286028D03*
Y1066323D03*
Y1072701D03*
Y1079079D03*
Y1085457D03*
Y1091835D03*
Y1098213D03*
Y1104591D03*
Y1110969D03*
Y1117347D03*
Y1123725D03*
Y1130102D03*
Y1136480D03*
Y1142858D03*
Y1149236D03*
X1289729Y1155614D03*
X1286028D03*
X1284178Y1158803D03*
X1287878Y1165181D03*
X1278259Y1625380D03*
X1286059D03*
X1280019Y1635380D03*
X1284299D03*
X1280019Y1647292D03*
X1284299D03*
X1278259Y1657292D03*
X1286059D03*
X1280510Y1679320D03*
Y1683857D03*
X1288384Y1684454D03*
Y1679920D03*
Y1675383D03*
X1280510Y1688391D03*
Y1693493D03*
Y1698030D03*
X1288384Y1698627D03*
Y1694093D03*
Y1689556D03*
X1280510Y1716737D03*
Y1702564D03*
Y1707666D03*
Y1712203D03*
X1288384Y1712800D03*
Y1708266D03*
Y1703729D03*
X1280510Y1721840D03*
Y1726377D03*
Y1730911D03*
X1288384Y1726974D03*
Y1722440D03*
Y1717903D03*
X1304532Y1028055D03*
X1293430Y1034433D03*
Y1040811D03*
X1298981Y1044000D03*
Y1037622D03*
X1304532Y1034433D03*
Y1040811D03*
X1298981Y1031244D03*
X1291579D03*
Y1044000D03*
X1304532Y1047189D03*
X1291579Y1050378D03*
X1293430Y1053567D03*
Y1059945D03*
X1304532Y1053567D03*
X1298981Y1050378D03*
X1302681Y1056756D03*
X1298981D03*
X1300831Y1059945D03*
X1304532D03*
X1298981Y1063134D03*
X1291579D03*
Y1069512D03*
X1293430Y1072701D03*
X1304532D03*
Y1066323D03*
X1298981Y1069512D03*
Y1075890D03*
X1293430Y1079079D03*
X1304532D03*
Y1085457D03*
X1298981Y1088646D03*
X1291579Y1082268D03*
X1298981D03*
X1291579Y1088646D03*
X1293430Y1091835D03*
X1304532D03*
X1298981Y1095024D03*
X1293430Y1098213D03*
X1298981Y1101402D03*
X1304532Y1098213D03*
Y1104591D03*
X1291579Y1101402D03*
X1298981Y1107780D03*
X1291579D03*
X1293430Y1110969D03*
X1304532D03*
X1293430Y1117347D03*
X1298981Y1114158D03*
X1304532Y1117347D03*
X1291579Y1120536D03*
X1298981D03*
X1304532Y1123725D03*
X1291579Y1126914D03*
X1298981D03*
X1304532Y1130102D03*
X1298981Y1133292D03*
X1293430Y1130102D03*
X1304532Y1136480D03*
X1298981Y1139669D03*
X1291579D03*
X1293430Y1136480D03*
X1304532Y1142858D03*
X1291579Y1146047D03*
X1293430Y1149236D03*
X1298981Y1146047D03*
X1304532Y1149236D03*
X1293430Y1155614D03*
X1304532D03*
X1298981Y1152425D03*
X1297130Y1155614D03*
X1302681Y1158803D03*
X1298981D03*
X1304532Y1161992D03*
X1297130D03*
X1298119Y1625380D03*
X1290319D03*
X1302379D03*
X1292079Y1635380D03*
X1296359D03*
X1304139D03*
X1296359Y1647292D03*
X1292079D03*
X1304139D03*
X1298119Y1657292D03*
X1290319D03*
X1302379D03*
X1296258Y1679320D03*
Y1683857D03*
Y1688391D03*
Y1693493D03*
Y1698030D03*
Y1716737D03*
Y1702564D03*
Y1707666D03*
Y1712203D03*
Y1721840D03*
Y1726377D03*
Y1730911D03*
X1311933Y1028055D03*
X1306382Y1044000D03*
Y1037622D03*
Y1031244D03*
X1319335Y1034433D03*
X1311933Y1040811D03*
X1319335D03*
X1317485Y1031244D03*
Y1044000D03*
X1311933Y1034433D03*
X1306382Y1050378D03*
Y1056756D03*
X1311933Y1047189D03*
X1313784Y1056756D03*
X1311933Y1059945D03*
X1315634D03*
X1319335D03*
X1317485Y1050378D03*
X1319335Y1053567D03*
X1311933D03*
X1306382Y1063134D03*
Y1069512D03*
X1317485Y1063134D03*
X1319335Y1072701D03*
X1317485Y1069512D03*
X1311933Y1066323D03*
Y1072701D03*
X1306382Y1075890D03*
Y1088646D03*
Y1082268D03*
X1319335Y1079079D03*
X1311933D03*
Y1085457D03*
X1317485Y1088646D03*
Y1082268D03*
X1306382Y1095024D03*
Y1101402D03*
X1319335Y1091835D03*
X1311933D03*
Y1098213D03*
X1319335D03*
X1317485Y1101402D03*
X1311933Y1104591D03*
X1306382Y1107780D03*
Y1114158D03*
X1317485Y1107780D03*
X1319335Y1110969D03*
X1311933D03*
Y1117347D03*
X1319335D03*
X1306382Y1120536D03*
Y1126914D03*
Y1133292D03*
X1317485Y1120536D03*
X1311933Y1123725D03*
X1317485Y1126914D03*
X1319335Y1130102D03*
X1311933Y1130103D03*
X1306382Y1139669D03*
Y1146047D03*
X1319335Y1136480D03*
X1317485Y1139669D03*
X1311933Y1136480D03*
Y1142858D03*
X1317485Y1146047D03*
X1319335Y1149236D03*
X1311933D03*
X1317485Y1158803D03*
X1313784D03*
X1319335Y1161992D03*
X1311933D03*
X1306382Y1165181D03*
X1313784D03*
X1306382Y1152425D03*
Y1158803D03*
X1319335Y1155614D03*
X1315634D03*
X1311933D03*
X1310083Y1158803D03*
X1318882Y1540514D03*
X1313514Y1556810D03*
Y1561725D03*
X1318986Y1575425D03*
X1310179Y1625380D03*
X1314439D03*
X1308419Y1635380D03*
X1316199D03*
X1308419Y1647292D03*
X1316199D03*
X1310179Y1657292D03*
X1314439D03*
X1315943Y1679320D03*
Y1683857D03*
X1308069Y1684454D03*
Y1679920D03*
Y1675383D03*
X1315943Y1688391D03*
Y1693493D03*
Y1698030D03*
X1308069Y1698627D03*
Y1694093D03*
Y1689556D03*
X1315943Y1716737D03*
Y1702564D03*
Y1707666D03*
Y1712203D03*
X1308069Y1712800D03*
Y1708266D03*
Y1703729D03*
X1315943Y1721840D03*
Y1726377D03*
Y1730911D03*
X1308069Y1726974D03*
Y1722440D03*
Y1717903D03*
X1330437Y1028055D03*
X1324886Y1031244D03*
X1332288D03*
X1324886Y1044000D03*
Y1037622D03*
X1332288Y1044000D03*
X1330437Y1034433D03*
X1332288Y1037622D03*
X1330437Y1040811D03*
Y1047189D03*
X1324886Y1050378D03*
Y1056756D03*
X1332288Y1050378D03*
X1330437Y1053567D03*
X1328587Y1056756D03*
X1332288D03*
X1326737Y1059945D03*
X1330437D03*
X1332288Y1063134D03*
X1324886D03*
Y1069512D03*
X1330437Y1066323D03*
X1332288Y1069512D03*
X1330437Y1072701D03*
X1324886Y1075890D03*
X1332288D03*
X1330437Y1079079D03*
X1324886Y1088646D03*
X1330437Y1085457D03*
X1332288Y1088646D03*
X1324886Y1082268D03*
X1332288D03*
X1330437Y1091835D03*
X1324886Y1095024D03*
X1332288D03*
X1324886Y1101402D03*
X1330437Y1098213D03*
X1332288Y1101402D03*
X1330437Y1104591D03*
X1324886Y1107780D03*
X1332288D03*
X1330437Y1110969D03*
X1324886Y1114158D03*
X1332288D03*
X1330437Y1117347D03*
X1324886Y1120536D03*
X1332288D03*
X1330437Y1123725D03*
X1324886Y1126914D03*
X1332288D03*
X1324886Y1133292D03*
X1332288D03*
X1330439Y1130102D03*
X1324886Y1139669D03*
X1330437Y1136480D03*
X1332288Y1139669D03*
X1330437Y1142858D03*
X1332288Y1146047D03*
X1330437Y1149236D03*
X1324886Y1146047D03*
X1332288Y1165181D03*
X1323036Y1155614D03*
Y1161992D03*
X1332288Y1152425D03*
X1330437Y1155614D03*
X1324886Y1152425D03*
X1332288Y1158803D03*
X1328587D03*
X1324886D03*
X1330437Y1161992D03*
X1324886Y1165181D03*
X1322795Y1547243D03*
X1324189Y1540295D03*
X1327519Y1547243D03*
X1328914Y1540295D03*
X1332244Y1547243D03*
X1333638Y1540295D03*
X1321623Y1552195D03*
X1331914Y1554453D03*
X1327189D03*
X1322465D03*
X1332465Y1561853D03*
X1327740D03*
X1323016D03*
X1333638Y1575641D03*
X1331964Y1569063D03*
X1328914Y1575641D03*
X1327239Y1569063D03*
X1324189Y1575641D03*
X1322514Y1569063D03*
X1326499Y1625380D03*
X1322239D03*
X1334299D03*
X1320479Y1635380D03*
X1328259D03*
X1332539D03*
X1328259Y1647292D03*
X1320479D03*
X1332539D03*
X1322239Y1657292D03*
X1326499D03*
X1334299D03*
X1331691Y1679320D03*
Y1683857D03*
X1323817Y1684454D03*
Y1679920D03*
Y1675383D03*
X1331691Y1688391D03*
Y1693493D03*
Y1698030D03*
X1323817Y1698627D03*
Y1694093D03*
Y1689556D03*
X1331691Y1716737D03*
Y1702564D03*
Y1707666D03*
Y1712203D03*
X1323817Y1712800D03*
Y1708266D03*
Y1703729D03*
X1331691Y1721840D03*
Y1726377D03*
Y1730911D03*
X1323817Y1726974D03*
Y1722440D03*
Y1717903D03*
X1337839Y1028055D03*
Y1040811D03*
Y1034433D03*
X1343390Y1031244D03*
Y1044000D03*
X1345241Y1040811D03*
Y1034433D03*
X1337839Y1047189D03*
Y1053567D03*
Y1059945D03*
X1339689Y1056756D03*
X1343390Y1050378D03*
X1345241Y1053567D03*
X1341540Y1059945D03*
X1345241D03*
X1337839Y1072701D03*
Y1066323D03*
X1343390Y1063134D03*
Y1069512D03*
X1345241Y1072701D03*
X1337839Y1079079D03*
Y1085457D03*
X1345241Y1079079D03*
X1343390Y1088646D03*
Y1082268D03*
X1337839Y1091835D03*
Y1098213D03*
Y1104591D03*
X1345241Y1091835D03*
X1343390Y1101402D03*
X1345241Y1098213D03*
X1337839Y1110969D03*
Y1117347D03*
X1343390Y1107780D03*
X1345241Y1110969D03*
Y1117347D03*
X1337839Y1123725D03*
Y1130102D03*
X1343390Y1120536D03*
Y1126914D03*
X1345241Y1130102D03*
X1337839Y1136480D03*
Y1142858D03*
Y1149236D03*
X1343390Y1139669D03*
X1345241Y1136480D03*
Y1149236D03*
X1343390Y1146047D03*
X1337839Y1155614D03*
X1335989Y1158803D03*
X1337839Y1161992D03*
X1341540Y1155614D03*
X1339689Y1158803D03*
X1348941Y1155614D03*
X1345241D03*
X1339689Y1165181D03*
X1336968Y1547243D03*
X1338362Y1540295D03*
X1341693Y1547243D03*
X1343087Y1540295D03*
X1346417Y1547243D03*
X1347811Y1540295D03*
X1346087Y1554453D03*
X1341362D03*
X1336638D03*
X1346638Y1561853D03*
X1341913D03*
X1337189D03*
X1347811Y1575641D03*
X1343087D03*
X1338362D03*
X1336688Y1569063D03*
X1338559Y1625380D03*
X1346359D03*
X1340319Y1635380D03*
X1344599D03*
X1340319Y1647292D03*
X1344599D03*
X1338559Y1657292D03*
X1346359D03*
X1347439Y1679320D03*
Y1683857D03*
X1339565Y1684454D03*
Y1679920D03*
Y1675383D03*
X1347439Y1688391D03*
Y1693493D03*
Y1698030D03*
X1339565Y1698627D03*
Y1694093D03*
Y1689556D03*
X1347439Y1716737D03*
Y1702564D03*
Y1707666D03*
Y1712203D03*
X1339565Y1712800D03*
Y1708266D03*
Y1703729D03*
X1347439Y1721840D03*
Y1726377D03*
Y1730911D03*
X1339565Y1726974D03*
Y1722440D03*
Y1717903D03*
X1356343Y1028055D03*
X1363745D03*
X1350792Y1031244D03*
Y1044000D03*
Y1037622D03*
X1356343Y1034433D03*
Y1040811D03*
X1363745Y1034433D03*
Y1040811D03*
X1361894Y1044000D03*
Y1037622D03*
Y1031244D03*
X1354493Y1056756D03*
X1350792D03*
Y1050378D03*
X1352642Y1059945D03*
X1356343Y1047189D03*
X1363745D03*
X1356343Y1053567D03*
X1361894Y1050378D03*
X1356343Y1059945D03*
X1363745Y1053567D03*
X1350792Y1063134D03*
Y1069512D03*
X1358193Y1063134D03*
X1356343Y1072701D03*
X1363745Y1066323D03*
X1358193Y1069512D03*
X1360044Y1066323D03*
X1350792Y1075890D03*
Y1082268D03*
Y1088646D03*
X1358193Y1075890D03*
X1363745Y1079079D03*
X1360044D03*
X1356343Y1085457D03*
X1358193Y1088646D03*
Y1082268D03*
X1350792Y1095024D03*
Y1101402D03*
X1356343Y1104591D03*
X1363745Y1091835D03*
X1360044D03*
X1358193Y1095024D03*
X1356343Y1098213D03*
X1363745Y1104591D03*
X1360044D03*
X1350792Y1107780D03*
Y1114158D03*
X1358193Y1107780D03*
X1360044Y1110969D03*
X1363745D03*
X1356343Y1117347D03*
X1358193Y1114158D03*
X1350792Y1120536D03*
Y1126914D03*
Y1133292D03*
X1358193Y1126914D03*
X1363745Y1123725D03*
X1360044D03*
X1358193Y1120536D03*
X1356343Y1130102D03*
X1358193Y1133292D03*
X1350792Y1139669D03*
Y1146047D03*
X1358193Y1139669D03*
X1363745Y1136480D03*
X1360044D03*
X1356343Y1142858D03*
X1363745Y1149236D03*
X1360044D03*
X1358193Y1146047D03*
X1354493Y1158803D03*
X1350792Y1152425D03*
Y1158803D03*
X1352642Y1161992D03*
X1356343Y1155614D03*
X1363745D03*
X1360044D03*
X1363745Y1161992D03*
X1351141Y1547243D03*
X1352536Y1540295D03*
X1355866Y1547243D03*
X1357260Y1540295D03*
X1360590Y1547243D03*
X1361984Y1540295D03*
X1360260Y1554453D03*
X1355536D03*
X1350811D03*
X1360811Y1561853D03*
X1356087D03*
X1351362D03*
X1361984Y1575641D03*
X1360310Y1569063D03*
X1352536Y1575641D03*
X1350861Y1569063D03*
X1357260Y1575641D03*
X1350619Y1625380D03*
X1358419D03*
X1362679D03*
X1352379Y1635380D03*
X1356659D03*
X1364439D03*
X1356659Y1647292D03*
X1352379D03*
X1364439D03*
X1358419Y1657292D03*
X1350619D03*
X1362679D03*
X1363187Y1679320D03*
Y1683857D03*
X1355313Y1684454D03*
Y1679920D03*
Y1675383D03*
Y1694093D03*
Y1689556D03*
X1363187Y1688391D03*
Y1693493D03*
Y1698030D03*
X1355313Y1698627D03*
X1363187Y1716737D03*
Y1702564D03*
Y1707666D03*
Y1712203D03*
X1355313Y1712800D03*
Y1708266D03*
Y1703729D03*
X1363187Y1726377D03*
Y1730911D03*
X1355313Y1726974D03*
Y1722440D03*
Y1717903D03*
X1363187Y1721840D03*
X1371146Y1028055D03*
X1374847D03*
X1369296Y1044000D03*
Y1037622D03*
Y1031244D03*
X1371146Y1034433D03*
X1376697Y1037622D03*
X1378548Y1040811D03*
X1371146D03*
X1374847Y1034433D03*
X1376697Y1031244D03*
Y1044000D03*
X1378548Y1053567D03*
X1376697Y1050378D03*
X1367445Y1059945D03*
X1369296Y1056756D03*
Y1050378D03*
X1371146Y1047189D03*
X1378548D03*
X1376697Y1056756D03*
X1371146Y1053567D03*
X1378548Y1059945D03*
X1369296Y1063134D03*
Y1069512D03*
X1367445Y1066323D03*
Y1072701D03*
X1371146Y1066323D03*
X1378548D03*
X1374847D03*
X1378548Y1072701D03*
X1369296Y1075890D03*
X1367445Y1079079D03*
X1369296Y1088646D03*
X1367445Y1085457D03*
X1369296Y1082268D03*
X1371146Y1079079D03*
X1378548D03*
X1374847D03*
X1378548Y1085457D03*
X1367445Y1091835D03*
X1369296Y1095024D03*
X1367445Y1104591D03*
Y1098213D03*
X1371146Y1091835D03*
X1378548D03*
X1374847D03*
X1371146Y1104591D03*
X1374847D03*
X1378548Y1098213D03*
Y1104591D03*
X1369296Y1107780D03*
X1367445Y1110969D03*
X1369296Y1114158D03*
X1367445Y1117347D03*
X1371146Y1110969D03*
X1378548D03*
X1374847D03*
X1378548Y1117347D03*
X1367445Y1130103D03*
X1369296Y1126914D03*
Y1120536D03*
X1367445Y1123725D03*
X1369296Y1133292D03*
X1374847Y1123725D03*
X1371146D03*
X1378548D03*
Y1130102D03*
X1369296Y1139669D03*
X1367445Y1136480D03*
Y1142858D03*
X1369296Y1146047D03*
X1374847Y1136480D03*
X1371146D03*
X1378548D03*
Y1142858D03*
X1371146Y1149236D03*
X1374847D03*
X1367445Y1155614D03*
X1365595Y1158803D03*
X1371146Y1155614D03*
X1378548D03*
X1374847D03*
X1376697Y1158803D03*
Y1165181D03*
X1374847Y1161992D03*
X1365315Y1547243D03*
X1366709Y1540295D03*
X1370039Y1547243D03*
X1371433Y1540295D03*
X1374763Y1547243D03*
X1376158Y1540295D03*
X1379488Y1547243D03*
X1379158Y1554453D03*
X1374433D03*
X1369709D03*
X1364984D03*
X1374984Y1561853D03*
X1370260D03*
X1365535D03*
X1371433Y1575641D03*
X1366709D03*
X1376158D03*
X1374483Y1569063D03*
X1370479Y1625380D03*
X1374740D03*
X1368719Y1635380D03*
X1376499Y1635286D03*
X1368719Y1647292D03*
X1376499D03*
X1370479Y1657292D03*
X1374739D03*
X1385937Y1028063D03*
Y1034441D03*
X1393339Y1040819D03*
X1385937D03*
X1385949Y1047189D03*
Y1053567D03*
X1384099Y1056756D03*
Y1050378D03*
X1393351Y1047189D03*
Y1053567D03*
X1389650Y1059945D03*
X1391500Y1056756D03*
Y1050378D03*
X1389650Y1066323D03*
X1391500Y1069512D03*
X1389650Y1072701D03*
X1380398Y1063134D03*
X1385949Y1066323D03*
X1382249D03*
X1380398Y1069512D03*
X1391500Y1063134D03*
X1393351Y1066323D03*
X1380398Y1075890D03*
X1385949Y1079079D03*
X1382249D03*
X1380398Y1088646D03*
Y1082268D03*
X1391500Y1075890D03*
X1393351Y1079079D03*
X1389650D03*
X1391500Y1088646D03*
X1389650Y1085457D03*
X1391500Y1082268D03*
X1385949Y1091835D03*
X1382249D03*
X1380398Y1095024D03*
X1393351Y1091835D03*
X1389650D03*
X1391500Y1095024D03*
Y1101402D03*
X1389650Y1098213D03*
X1393351Y1104591D03*
X1389650D03*
X1385949Y1110969D03*
X1382249D03*
X1380398Y1107780D03*
Y1114158D03*
X1393351Y1110969D03*
X1389650D03*
X1391500Y1107780D03*
X1389650Y1117347D03*
X1391500Y1114158D03*
X1385949Y1123725D03*
X1382249D03*
X1380398Y1120536D03*
Y1126914D03*
Y1133292D03*
X1393351Y1123725D03*
X1389650D03*
X1391500Y1120536D03*
Y1126914D03*
Y1133292D03*
X1389650Y1130102D03*
X1380398Y1139669D03*
X1385949Y1136480D03*
X1382249D03*
X1385949Y1149236D03*
X1382249D03*
X1380398Y1146047D03*
X1391500Y1139669D03*
X1393351Y1136480D03*
X1389650D03*
Y1142858D03*
X1393351Y1149236D03*
X1391500Y1146047D03*
X1385949Y1155614D03*
X1382249D03*
X1385949Y1161992D03*
X1387800Y1158803D03*
X1393351Y1155614D03*
X1389650D03*
X1380882Y1540295D03*
X1384212Y1547243D03*
X1385606Y1540295D03*
X1390331D03*
X1393661Y1547243D03*
X1393331Y1554453D03*
X1388607D03*
X1383882D03*
X1393882Y1561853D03*
X1389158D03*
X1384433D03*
X1379709D03*
X1385606Y1575641D03*
X1383932Y1569063D03*
X1380882Y1575641D03*
X1390331D03*
X1393381Y1569063D03*
X1382539Y1625380D03*
X1388569Y1635380D03*
X1380779D03*
Y1647292D03*
X1388569D03*
X1382539Y1657292D03*
X1400740Y1040819D03*
X1400752Y1047189D03*
X1398902Y1056756D03*
X1400752Y1053567D03*
Y1059945D03*
X1398902Y1050378D03*
X1408154Y1047189D03*
Y1053567D03*
X1406304Y1056756D03*
Y1050378D03*
X1402603Y1063134D03*
Y1069512D03*
X1397052Y1066323D03*
X1400752D03*
Y1072701D03*
X1406304Y1063134D03*
X1402603Y1075890D03*
X1400752Y1079079D03*
X1397052D03*
X1402603Y1088646D03*
Y1082268D03*
X1400752Y1085457D03*
X1406304Y1075890D03*
Y1088646D03*
X1402603Y1095024D03*
X1400752Y1091835D03*
X1397052D03*
X1402603Y1101402D03*
X1400752Y1104591D03*
X1397052D03*
X1400752Y1098213D03*
X1406304Y1101402D03*
X1402603Y1107780D03*
X1397052Y1110969D03*
X1400752D03*
X1402603Y1114158D03*
X1400752Y1117347D03*
X1406304Y1107780D03*
X1402603Y1120536D03*
Y1126914D03*
X1397052Y1123725D03*
X1400752D03*
X1402603Y1133292D03*
X1406304Y1120536D03*
Y1133292D03*
X1400752Y1130103D03*
X1402603Y1139669D03*
X1397052Y1136480D03*
X1400752D03*
Y1142858D03*
X1402603Y1146047D03*
X1397052Y1149236D03*
X1408154D03*
X1404453D03*
X1398902Y1158803D03*
X1397052Y1155614D03*
X1400752D03*
X1397052Y1161992D03*
X1398902Y1165181D03*
X1406304Y1158803D03*
X1395055Y1540295D03*
X1398076Y1554453D03*
X1395055Y1575641D03*
X1398712Y1569063D03*
X1411855Y1059945D03*
X1422932Y1047189D03*
Y1059945D03*
Y1053567D03*
X1410004Y1063134D03*
X1411855Y1066323D03*
Y1072701D03*
X1422932D03*
Y1066323D03*
X1410004Y1075890D03*
X1411855Y1079079D03*
Y1085457D03*
X1410004Y1088646D03*
X1422932Y1079079D03*
Y1085457D03*
Y1091835D03*
Y1104591D03*
Y1098213D03*
X1411855Y1091835D03*
Y1104591D03*
Y1098213D03*
X1410004Y1101402D03*
Y1107780D03*
X1411855Y1110969D03*
Y1117347D03*
X1422932Y1110969D03*
Y1117347D03*
X1411855Y1123725D03*
X1410004Y1120536D03*
X1411855Y1130102D03*
X1410004Y1133292D03*
X1422932Y1123725D03*
Y1130102D03*
X1411855Y1136480D03*
Y1142858D03*
Y1149236D03*
X1422932Y1136480D03*
Y1142858D03*
Y1149236D03*
X1411855Y1155614D03*
Y1161992D03*
X1422932Y1155614D03*
Y1161992D03*
X1430346Y1040819D03*
X1437748D03*
X1430334Y1047189D03*
X1424783Y1056756D03*
X1434035Y1059945D03*
X1432184Y1056756D03*
X1430334Y1053567D03*
X1424783Y1050378D03*
X1432184D03*
X1437735Y1047189D03*
Y1053567D03*
X1432184Y1063134D03*
X1428483D03*
X1424783D03*
X1432184Y1069512D03*
X1434035Y1072701D03*
Y1066323D03*
X1437735D03*
Y1079079D03*
X1428483Y1075890D03*
X1432184D03*
X1424783D03*
X1434035Y1079079D03*
X1424783Y1088646D03*
X1432184Y1082268D03*
X1428483Y1088646D03*
X1432184D03*
X1434035Y1085457D03*
X1432184Y1095024D03*
X1434035Y1091835D03*
Y1104591D03*
X1428483Y1101402D03*
X1432184D03*
X1434035Y1098213D03*
X1424783Y1101402D03*
X1437735Y1091835D03*
Y1104591D03*
X1428483Y1107780D03*
X1432184D03*
X1424783D03*
X1434035Y1110969D03*
Y1117347D03*
X1432184Y1114158D03*
X1437735Y1110969D03*
X1432184Y1126914D03*
Y1120536D03*
X1428483D03*
X1424783D03*
X1434035Y1123725D03*
X1424783Y1133292D03*
X1428483D03*
X1432184D03*
X1437735Y1123725D03*
X1434035Y1130103D03*
X1432184Y1139669D03*
X1434035Y1136480D03*
Y1142858D03*
X1430334Y1149236D03*
X1432184Y1146047D03*
X1426633Y1149236D03*
X1437735Y1136480D03*
Y1149236D03*
X1430333Y1155614D03*
X1435885Y1158803D03*
Y1152425D03*
X1452542Y1040819D03*
X1445149D03*
X1445137Y1047189D03*
X1446987Y1056756D03*
X1445137Y1059945D03*
X1439586Y1056756D03*
X1445137Y1053567D03*
X1439586Y1050378D03*
X1446987D03*
X1452539Y1047189D03*
Y1053567D03*
X1443287Y1063134D03*
X1445137Y1072701D03*
X1443287Y1069512D03*
X1448838Y1066323D03*
X1445137D03*
X1441436D03*
X1452539D03*
X1445137Y1079079D03*
X1448838D03*
X1441436D03*
X1443287Y1075890D03*
Y1088646D03*
X1445137Y1085457D03*
X1443287Y1082268D03*
X1452539Y1079079D03*
X1441436Y1091835D03*
X1448838D03*
X1445137D03*
X1443287Y1095024D03*
X1445137Y1104591D03*
X1443287Y1101402D03*
X1445137Y1098213D03*
X1441436Y1104591D03*
X1452539Y1091835D03*
X1441436Y1110969D03*
X1448838D03*
X1445137D03*
X1443287Y1107780D03*
X1445137Y1117347D03*
X1443287Y1114158D03*
X1452539Y1110969D03*
X1445137Y1123725D03*
X1448838D03*
X1443287Y1120536D03*
X1441436Y1123725D03*
X1443287Y1126914D03*
Y1133292D03*
X1445137Y1130102D03*
X1452539Y1123725D03*
X1448838Y1149236D03*
X1443287Y1146047D03*
X1441436Y1149236D03*
X1452539Y1136480D03*
Y1149236D03*
X1445137Y1142858D03*
X1443287Y1139669D03*
X1445137Y1136480D03*
X1448838D03*
X1441436D03*
X1446987Y1158803D03*
X1450688Y1152425D03*
X1441436Y1155614D03*
X1449626Y1556810D03*
Y1561725D03*
X1463641Y1028055D03*
X1456239D03*
X1459940Y1040811D03*
X1458090Y1031244D03*
X1463641Y1034433D03*
X1456239D03*
X1465491Y1031244D03*
X1454389Y1037622D03*
X1467342Y1040811D03*
X1454389Y1044000D03*
X1461791Y1037622D03*
Y1044000D03*
X1459940Y1047189D03*
X1456239Y1059945D03*
X1459940Y1053567D03*
X1454389Y1056756D03*
X1461791D03*
X1454389Y1050378D03*
X1461791D03*
X1467342Y1047189D03*
Y1059945D03*
Y1053567D03*
X1465491Y1063134D03*
X1454389D03*
X1456239Y1072701D03*
X1459940Y1066323D03*
X1463641D03*
X1465491Y1069512D03*
X1454389D03*
X1456239Y1066323D03*
X1467342Y1072701D03*
Y1066323D03*
X1459940Y1079079D03*
X1463641D03*
X1456239D03*
X1465491Y1075890D03*
X1454389D03*
X1465491Y1088646D03*
X1454389D03*
X1456239Y1085457D03*
X1465491Y1082268D03*
X1454389D03*
X1467342Y1079079D03*
Y1085457D03*
X1456239Y1098213D03*
X1467342Y1091835D03*
Y1104591D03*
Y1098213D03*
X1463641Y1091835D03*
X1459940D03*
X1456239D03*
X1465491Y1095024D03*
X1454389D03*
X1459940Y1104591D03*
X1463641D03*
X1456239D03*
X1465491Y1107780D03*
X1454389D03*
X1463641Y1110969D03*
X1459940D03*
X1456239D03*
Y1117347D03*
X1454389Y1114158D03*
X1465491D03*
X1467342Y1110969D03*
Y1117347D03*
X1454389Y1120536D03*
X1465491Y1126914D03*
X1454389D03*
X1459940Y1123725D03*
X1463641D03*
X1465491Y1120536D03*
X1456239Y1123725D03*
X1454389Y1133292D03*
X1456239Y1130102D03*
X1465491Y1133292D03*
X1467342Y1123725D03*
Y1130102D03*
X1456239Y1142858D03*
X1465491Y1139669D03*
X1459940Y1136480D03*
X1463641D03*
X1454389Y1139669D03*
X1456239Y1136480D03*
X1465491Y1146047D03*
X1459940Y1149236D03*
X1463641D03*
X1454389Y1146047D03*
X1467342Y1136480D03*
Y1142858D03*
X1463641Y1155614D03*
X1461791Y1152425D03*
X1458090Y1158803D03*
X1454994Y1540512D03*
X1458907Y1547243D03*
X1460301Y1540295D03*
X1463631Y1547243D03*
X1465026Y1540295D03*
X1468356Y1547243D03*
X1457735Y1552195D03*
X1468026Y1554453D03*
X1463301D03*
X1458577D03*
X1468577Y1561853D03*
X1463852D03*
X1459128D03*
X1455098Y1575425D03*
X1468076Y1569063D03*
X1463351D03*
X1460301Y1575641D03*
X1458626Y1569063D03*
X1465026Y1575641D03*
X1458013Y1625380D03*
X1465813D03*
X1464053Y1635380D03*
Y1647292D03*
X1465813Y1657292D03*
X1458013D03*
X1478444Y1028055D03*
X1471043D03*
X1472893Y1031244D03*
X1469192Y1037622D03*
Y1044000D03*
X1478444Y1034433D03*
X1476594Y1037622D03*
X1474743Y1040811D03*
X1476594Y1044000D03*
X1471043Y1034433D03*
X1474743Y1047189D03*
X1480295Y1056756D03*
X1482145Y1059945D03*
X1469192Y1050378D03*
X1476594D03*
Y1056756D03*
X1474743Y1053567D03*
X1478444Y1059945D03*
X1469192Y1056756D03*
X1476594Y1063134D03*
X1478444Y1072701D03*
X1476594Y1069512D03*
X1474743Y1066323D03*
X1471043D03*
X1476594Y1075890D03*
X1474743Y1079079D03*
X1471043D03*
X1478444Y1085457D03*
X1476594Y1088646D03*
Y1082268D03*
X1474743Y1091835D03*
X1471043D03*
X1476594Y1095024D03*
X1478444Y1098213D03*
Y1104591D03*
X1474743D03*
X1471043D03*
X1472893Y1101402D03*
X1476594Y1107780D03*
X1474743Y1110969D03*
X1471043D03*
X1476594Y1114158D03*
X1478444Y1117347D03*
X1476594Y1126914D03*
Y1120536D03*
X1474743Y1123725D03*
X1471043D03*
X1478444Y1130102D03*
X1476594Y1133292D03*
Y1139669D03*
X1474743Y1136480D03*
X1471043D03*
X1478444Y1142858D03*
X1476594Y1146047D03*
X1474743Y1149236D03*
X1471043D03*
X1474743Y1155614D03*
X1478444D03*
X1472893Y1152425D03*
X1480295Y1158803D03*
X1469192D03*
X1469750Y1540295D03*
X1473080Y1547243D03*
X1474474Y1540295D03*
X1477805Y1547243D03*
X1479199Y1540295D03*
X1482529Y1547243D03*
X1483923Y1540295D03*
X1482199Y1554453D03*
X1477474D03*
X1472750D03*
X1482750Y1561853D03*
X1478025D03*
X1473301D03*
X1469750Y1575641D03*
X1483923D03*
X1474474D03*
X1472800Y1569063D03*
X1479199Y1575641D03*
X1470073Y1625380D03*
X1482133D03*
X1477873D03*
X1471833Y1635380D03*
X1483893D03*
X1476113D03*
X1471833Y1647292D03*
X1483893D03*
X1476113D03*
X1470073Y1657292D03*
X1477873D03*
X1482133D03*
X1489547Y1028055D03*
X1496948D03*
X1483995Y1031244D03*
Y1037622D03*
Y1044000D03*
X1491397Y1031244D03*
X1489547Y1040811D03*
Y1034433D03*
X1491397Y1044000D03*
X1496948Y1034433D03*
Y1040811D03*
Y1047189D03*
X1483995Y1050378D03*
Y1056756D03*
X1489547Y1053567D03*
X1495098Y1056756D03*
X1491397Y1050378D03*
X1489547Y1059945D03*
X1493247D03*
X1496948Y1053567D03*
Y1059945D03*
X1483995Y1063134D03*
X1491397D03*
X1483995Y1069512D03*
X1489547Y1072701D03*
X1491397Y1069512D03*
X1496948Y1072701D03*
Y1066323D03*
X1483995Y1075890D03*
X1489547Y1079079D03*
X1496948D03*
X1483995Y1088646D03*
X1491397D03*
X1496948Y1085457D03*
X1483995Y1082268D03*
X1491397D03*
X1489547Y1091835D03*
X1496948D03*
X1483995Y1095024D03*
Y1101402D03*
X1489547Y1098213D03*
X1491397Y1101402D03*
X1496948Y1098213D03*
Y1104591D03*
X1489547Y1110969D03*
X1496948D03*
X1483995Y1107780D03*
X1491397D03*
X1483995Y1114158D03*
X1489547Y1117347D03*
X1496948D03*
X1483995Y1120536D03*
X1491397D03*
X1496948Y1123725D03*
X1483995Y1126914D03*
X1491397D03*
X1483995Y1133292D03*
X1496948Y1130102D03*
X1489547Y1130103D03*
X1483995Y1139669D03*
X1489547Y1136480D03*
X1491397Y1139669D03*
X1496948Y1136480D03*
Y1142858D03*
X1483995Y1146047D03*
X1489547Y1149236D03*
X1491397Y1146047D03*
X1496948Y1149236D03*
X1487696Y1165181D03*
X1498799Y1158803D03*
X1483995Y1152425D03*
X1485846Y1155614D03*
X1489547D03*
X1493247D03*
X1496948D03*
X1483995Y1158803D03*
X1491397D03*
X1493247Y1161992D03*
X1495111Y1165289D03*
X1491410D03*
X1498812D03*
X1488648Y1540295D03*
X1487253Y1547243D03*
X1491978D03*
X1493372Y1540295D03*
X1496702Y1547243D03*
X1498096Y1540295D03*
X1496372Y1554453D03*
X1491648D03*
X1486923D03*
X1496923Y1561853D03*
X1492199D03*
X1487474D03*
X1488648Y1575641D03*
X1493372D03*
X1498096D03*
X1496422Y1569063D03*
X1486973D03*
X1489933Y1625380D03*
X1494193D03*
X1495953Y1635380D03*
X1488173D03*
X1495953Y1647292D03*
X1488173D03*
X1494193Y1657292D03*
X1489933D03*
X1504350Y1028055D03*
X1502499Y1031244D03*
X1509901D03*
X1504350Y1040811D03*
X1502499Y1037622D03*
X1504350Y1034433D03*
X1502499Y1044000D03*
X1509901Y1037622D03*
Y1044000D03*
X1504350Y1047189D03*
Y1053567D03*
X1502499Y1050378D03*
X1509901Y1056756D03*
Y1050378D03*
X1504350Y1059945D03*
X1508050D03*
X1506200Y1056756D03*
X1502499D03*
Y1063134D03*
X1509901D03*
X1502499Y1069512D03*
X1504350Y1072701D03*
Y1066323D03*
X1509901Y1069512D03*
X1502499Y1075890D03*
X1509901D03*
X1504350Y1079079D03*
Y1085457D03*
X1502499Y1088646D03*
X1509901D03*
X1502499Y1082268D03*
X1509901D03*
X1504350Y1091835D03*
X1502499Y1095024D03*
X1509901D03*
X1504350Y1098213D03*
X1502499Y1101402D03*
X1509901D03*
X1504350Y1104591D03*
X1502499Y1107780D03*
X1509901D03*
X1504350Y1110969D03*
X1509901Y1114158D03*
X1504350Y1117347D03*
X1502499Y1114158D03*
Y1120536D03*
X1504350Y1123725D03*
X1509901Y1120536D03*
X1502499Y1126914D03*
X1509901D03*
Y1133292D03*
X1502499D03*
X1504350Y1130103D03*
X1502499Y1139669D03*
X1504350Y1136480D03*
X1509901Y1139669D03*
X1504350Y1142858D03*
Y1149236D03*
X1502499Y1146047D03*
X1509901D03*
X1504350Y1155614D03*
X1502499Y1152425D03*
X1509901D03*
X1511751Y1155614D03*
X1502499Y1158803D03*
X1506200D03*
X1509901D03*
X1509914Y1165289D03*
X1506213D03*
X1502821Y1540295D03*
X1501427Y1547243D03*
X1506151D03*
X1507545Y1540295D03*
X1510875Y1547243D03*
X1512270Y1540295D03*
X1510545Y1554453D03*
X1505821D03*
X1501096D03*
X1511096Y1561853D03*
X1506372D03*
X1501647D03*
X1507545Y1575641D03*
X1512270D03*
X1510595Y1569063D03*
X1502821Y1575641D03*
X1501993Y1625380D03*
X1506253D03*
X1508013Y1635380D03*
X1500233D03*
X1512293D03*
X1508013Y1647292D03*
X1500233D03*
X1512293D03*
X1501993Y1657292D03*
X1506253D03*
X1513187Y1679320D03*
Y1683857D03*
X1505313Y1684454D03*
Y1679920D03*
Y1675383D03*
X1513187Y1688391D03*
Y1693493D03*
Y1698030D03*
X1505313Y1698627D03*
Y1694093D03*
Y1689556D03*
X1513187Y1716737D03*
Y1702564D03*
Y1707666D03*
Y1712203D03*
X1505313Y1712800D03*
Y1708266D03*
Y1703729D03*
X1513187Y1721840D03*
Y1726377D03*
Y1730911D03*
X1505313Y1726974D03*
Y1722440D03*
Y1717903D03*
X1522854Y1028055D03*
X1515452D03*
X1522854Y1034433D03*
Y1040811D03*
X1517302Y1044000D03*
X1528405Y1037622D03*
Y1044000D03*
X1515452Y1040811D03*
Y1034433D03*
X1517302Y1031244D03*
X1528405D03*
X1515452Y1053567D03*
Y1059945D03*
X1522854Y1047189D03*
Y1053567D03*
X1521003Y1056756D03*
X1517302Y1050378D03*
X1522854Y1059945D03*
X1519153D03*
X1528405Y1050378D03*
Y1056756D03*
X1517302Y1063134D03*
X1528405D03*
X1515452Y1072701D03*
X1522854Y1066323D03*
Y1072701D03*
X1517302Y1069512D03*
X1528405D03*
Y1075890D03*
X1515452Y1079079D03*
X1522854D03*
X1517302Y1082268D03*
X1528405D03*
X1522854Y1085457D03*
X1517302Y1088646D03*
X1528405D03*
X1515452Y1091835D03*
X1522854D03*
X1528405Y1095024D03*
X1522854Y1104591D03*
X1528405Y1101402D03*
X1515452Y1098213D03*
X1522854D03*
X1517302Y1101402D03*
Y1107780D03*
X1528405D03*
X1522854Y1110969D03*
X1515452D03*
X1522854Y1117347D03*
X1528405Y1114158D03*
X1515452Y1117347D03*
X1522854Y1123725D03*
X1517302Y1120536D03*
X1528405D03*
X1517302Y1126914D03*
X1528405D03*
Y1133292D03*
X1515452Y1130102D03*
X1522854Y1130103D03*
Y1142858D03*
Y1136480D03*
X1517302Y1139669D03*
X1528405D03*
X1515452Y1136480D03*
X1528405Y1146047D03*
X1515452Y1149236D03*
X1522854D03*
X1517302Y1146047D03*
X1528405Y1152425D03*
X1524704Y1158803D03*
X1528405D03*
X1515452Y1155614D03*
X1519153D03*
X1522854D03*
X1519153Y1161992D03*
X1521718Y1540295D03*
X1515600Y1547243D03*
X1516994Y1540295D03*
X1520324Y1547243D03*
X1526443Y1540295D03*
X1524719Y1554453D03*
X1519994D03*
X1515270D03*
X1525270Y1561853D03*
X1520545D03*
X1515821D03*
X1516994Y1575641D03*
X1526443D03*
X1521718D03*
X1520044Y1569063D03*
X1514053Y1625380D03*
X1518313D03*
X1526113D03*
X1520073Y1635380D03*
X1524353D03*
X1520073Y1647292D03*
X1524353D03*
X1518313Y1657292D03*
X1514053D03*
X1526113D03*
X1521061Y1684454D03*
Y1679920D03*
Y1675383D03*
Y1698627D03*
Y1694093D03*
Y1689556D03*
Y1712800D03*
Y1708266D03*
Y1703729D03*
Y1726974D03*
Y1722440D03*
Y1717903D03*
X1530255Y1028055D03*
X1541358D03*
X1530255Y1034433D03*
Y1040811D03*
X1541357D03*
Y1034433D03*
X1543208Y1031244D03*
Y1044000D03*
X1535806Y1031244D03*
Y1037622D03*
Y1044000D03*
X1530255Y1047189D03*
Y1053567D03*
Y1059945D03*
X1541357Y1053567D03*
Y1059945D03*
X1543208Y1050378D03*
X1532106Y1056756D03*
X1535806D03*
Y1050378D03*
X1533956Y1059945D03*
X1530255Y1066323D03*
Y1072701D03*
X1543208Y1063134D03*
X1535806D03*
X1543208Y1069512D03*
X1541357Y1072701D03*
X1535806Y1069512D03*
X1530255Y1079079D03*
Y1085457D03*
X1535806Y1075890D03*
X1541357Y1079079D03*
X1543208Y1082268D03*
Y1088646D03*
X1535806D03*
Y1082268D03*
X1530255Y1098213D03*
Y1104591D03*
X1541357Y1091835D03*
X1535806Y1095024D03*
X1543208Y1101402D03*
X1541357Y1098213D03*
X1535806Y1101402D03*
X1530255Y1091835D03*
Y1110969D03*
Y1117347D03*
X1543208Y1107780D03*
X1535806D03*
X1541357Y1110969D03*
Y1117347D03*
X1535806Y1114158D03*
X1530255Y1123725D03*
Y1130102D03*
X1543208Y1120536D03*
X1535806D03*
X1543208Y1126914D03*
X1535806D03*
X1541357Y1130102D03*
X1535806Y1133292D03*
X1530255Y1142858D03*
Y1136480D03*
Y1149236D03*
X1541357Y1136480D03*
X1543208Y1139669D03*
X1535806D03*
X1543208Y1146047D03*
X1541357Y1149236D03*
X1535806Y1146047D03*
X1530255Y1155614D03*
X1537657D03*
X1541357D03*
X1535806Y1152425D03*
X1532106Y1158803D03*
X1535806D03*
X1541357Y1161992D03*
X1532106Y1165181D03*
X1531167Y1540295D03*
X1529773Y1547243D03*
X1534188Y1554453D03*
X1529443D03*
X1529994Y1561853D03*
X1534824Y1569063D03*
X1531167Y1575641D03*
X1529493Y1569063D03*
X1530373Y1625380D03*
X1542433D03*
X1538173D03*
X1532133Y1635380D03*
X1536413D03*
X1532133Y1647292D03*
X1536413D03*
X1530373Y1657292D03*
X1542433D03*
X1538173D03*
X1528935Y1679320D03*
Y1683857D03*
X1536809Y1684454D03*
Y1679920D03*
Y1675383D03*
X1528935Y1688391D03*
Y1693493D03*
Y1698030D03*
X1536809Y1698627D03*
Y1694093D03*
Y1689556D03*
X1528935Y1712203D03*
X1536809Y1712800D03*
Y1708266D03*
Y1703729D03*
X1528935Y1716737D03*
Y1702564D03*
Y1707666D03*
Y1721840D03*
Y1726377D03*
Y1730911D03*
X1536809Y1726974D03*
Y1722440D03*
Y1717903D03*
X1553870Y906181D03*
Y912559D03*
Y918937D03*
Y925315D03*
Y931693D03*
Y938071D03*
Y944449D03*
Y950827D03*
Y957205D03*
Y963583D03*
Y969961D03*
Y976339D03*
Y982717D03*
Y989095D03*
Y995473D03*
Y1008229D03*
Y1001851D03*
X1548759Y1028055D03*
X1555051Y1030197D03*
X1548759Y1040811D03*
Y1034433D03*
X1555051Y1042953D03*
Y1036575D03*
X1546909Y1056756D03*
X1545058Y1059945D03*
X1548759Y1047189D03*
X1555051Y1049331D03*
X1548759Y1053567D03*
Y1059945D03*
X1555051Y1055709D03*
Y1062087D03*
X1548759Y1072701D03*
Y1066323D03*
X1555051Y1068465D03*
Y1074843D03*
X1548759Y1079079D03*
X1555051Y1081221D03*
X1548759Y1085457D03*
X1555051Y1087599D03*
X1548759Y1091835D03*
X1555051Y1093977D03*
X1548759Y1098213D03*
Y1104591D03*
X1555051Y1100355D03*
Y1106733D03*
X1548759Y1110969D03*
X1555051Y1113111D03*
X1548759Y1117347D03*
X1555051Y1119489D03*
Y1132245D03*
X1548759Y1123725D03*
X1555051Y1125867D03*
X1548759Y1130102D03*
Y1136480D03*
X1555051Y1138622D03*
X1548759Y1142858D03*
X1555051Y1145000D03*
X1548759Y1149236D03*
X1545058Y1155614D03*
X1548759D03*
X1555051Y1151378D03*
X1550609Y1158803D03*
X1554310D03*
X1550233Y1625380D03*
X1554493D03*
X1544193Y1635380D03*
X1556253D03*
X1548473D03*
X1544193Y1647292D03*
X1556253D03*
X1548473D03*
X1554493Y1657292D03*
X1550233D03*
X1544683Y1679320D03*
Y1683857D03*
X1552557Y1684454D03*
Y1679920D03*
Y1675383D03*
X1544683Y1688391D03*
Y1693493D03*
Y1698030D03*
X1552557Y1698627D03*
Y1694093D03*
Y1689556D03*
X1544683Y1716737D03*
Y1702564D03*
Y1707666D03*
Y1712203D03*
X1552557Y1712800D03*
Y1708266D03*
Y1703729D03*
X1544683Y1721840D03*
Y1726377D03*
Y1730911D03*
X1552557Y1726974D03*
Y1722440D03*
Y1717903D03*
X1562293Y1625380D03*
X1566553D03*
X1568313Y1635380D03*
X1560533D03*
X1572593D03*
X1568313Y1647292D03*
X1560533D03*
X1572593D03*
X1562293Y1657292D03*
X1566553D03*
X1572243Y1684454D03*
Y1679920D03*
Y1675383D03*
X1560431Y1679320D03*
Y1683857D03*
X1572243Y1698627D03*
Y1694093D03*
Y1689556D03*
X1560431Y1688391D03*
Y1693493D03*
Y1698030D03*
X1572243Y1712800D03*
Y1708266D03*
Y1703729D03*
X1560431Y1716737D03*
Y1702564D03*
Y1707666D03*
Y1712203D03*
X1572243Y1726974D03*
Y1722440D03*
Y1717903D03*
X1560431Y1721840D03*
Y1726377D03*
Y1730911D03*
X1583056Y1540514D03*
X1586969Y1547243D03*
X1585797Y1552195D03*
X1586639Y1554453D03*
X1587190Y1561853D03*
X1577688Y1556810D03*
Y1561725D03*
X1586688Y1569063D03*
X1583160Y1575425D03*
X1574353Y1625380D03*
X1578613D03*
X1586413D03*
X1580373Y1635380D03*
X1584653D03*
X1580373Y1647292D03*
X1584653D03*
X1574353Y1657292D03*
X1578613D03*
X1586413D03*
X1580117Y1679320D03*
Y1683857D03*
X1587991Y1684454D03*
Y1679920D03*
Y1675383D03*
X1580117Y1688391D03*
Y1693493D03*
Y1698030D03*
X1587991Y1698627D03*
Y1694093D03*
Y1689556D03*
X1580117Y1716737D03*
Y1702564D03*
Y1707666D03*
Y1712203D03*
X1587991Y1712800D03*
Y1708266D03*
Y1703729D03*
X1580117Y1721840D03*
Y1726377D03*
Y1730911D03*
X1587991Y1726974D03*
Y1722440D03*
Y1717903D03*
X1588363Y1540295D03*
X1591693Y1547243D03*
X1593088Y1540295D03*
X1596418Y1547243D03*
X1597812Y1540295D03*
X1601142Y1547243D03*
X1602536Y1540295D03*
X1600812Y1554453D03*
X1596088D03*
X1591363D03*
X1601363Y1561853D03*
X1596639D03*
X1591914D03*
X1602536Y1575641D03*
X1600862Y1569063D03*
X1597812Y1575641D03*
X1596138Y1569063D03*
X1593088Y1575641D03*
X1591413Y1569063D03*
X1588363Y1575641D03*
X1590673Y1625380D03*
X1602733D03*
X1598473D03*
X1592433Y1635380D03*
X1596713D03*
X1592433Y1647292D03*
X1596713D03*
X1590673Y1657292D03*
X1598473D03*
X1602733D03*
X1595865Y1679320D03*
Y1683857D03*
Y1688391D03*
Y1693493D03*
Y1698030D03*
Y1716737D03*
Y1702564D03*
Y1707666D03*
Y1712203D03*
Y1721840D03*
Y1726377D03*
Y1730911D03*
X1605867Y1547243D03*
X1607261Y1540295D03*
X1610591Y1547243D03*
X1611985Y1540295D03*
X1615315Y1547243D03*
X1616710Y1540295D03*
X1614985Y1554453D03*
X1610261D03*
X1605536D03*
X1615536Y1561853D03*
X1610812D03*
X1606087D03*
X1616710Y1575641D03*
X1615035Y1569063D03*
X1611985Y1575641D03*
X1607261D03*
X1610533Y1625380D03*
X1614793D03*
X1604493Y1635380D03*
X1616553D03*
X1608773D03*
X1604493Y1647292D03*
X1616553D03*
X1608773D03*
X1614793Y1657292D03*
X1610533D03*
X1611613Y1679320D03*
Y1683857D03*
X1603739Y1684454D03*
Y1679920D03*
Y1675383D03*
X1611613Y1688391D03*
Y1693493D03*
Y1698030D03*
X1603739Y1698627D03*
Y1694093D03*
Y1689556D03*
X1611613Y1702564D03*
Y1707666D03*
Y1712203D03*
X1603739Y1712800D03*
Y1708266D03*
Y1703729D03*
X1611613Y1716737D03*
Y1721840D03*
Y1726377D03*
Y1730911D03*
X1603739Y1726974D03*
Y1722440D03*
Y1717903D03*
X1620040Y1547243D03*
X1621434Y1540295D03*
X1624764Y1547243D03*
X1626158Y1540295D03*
X1629489Y1547243D03*
X1630883Y1540295D03*
X1629158Y1554453D03*
X1624434D03*
X1619710D03*
X1629709Y1561853D03*
X1624985D03*
X1620261D03*
X1630883Y1575641D03*
X1626158D03*
X1624484Y1569063D03*
X1621434Y1575641D03*
X1622593Y1625380D03*
X1626853D03*
X1628613Y1635380D03*
X1620833D03*
X1632893D03*
X1628613Y1647292D03*
X1620833D03*
X1632893D03*
X1622593Y1657292D03*
X1626853D03*
X1627361Y1679320D03*
Y1683857D03*
X1619487Y1684454D03*
Y1679920D03*
Y1675383D03*
X1627361Y1688391D03*
Y1693493D03*
Y1698030D03*
X1619487Y1698627D03*
Y1694093D03*
Y1689556D03*
Y1708266D03*
Y1703729D03*
X1627361Y1716737D03*
Y1702564D03*
Y1707666D03*
Y1712203D03*
X1619487Y1712800D03*
X1627361Y1721840D03*
Y1726377D03*
Y1730911D03*
X1619487Y1726974D03*
Y1722440D03*
Y1717903D03*
X1634213Y1547243D03*
X1635607Y1540295D03*
X1638937Y1547243D03*
X1640332Y1540295D03*
X1643662Y1547243D03*
X1645056Y1540295D03*
X1643332Y1554453D03*
X1638607D03*
X1633883D03*
X1643883Y1561853D03*
X1639158D03*
X1634434D03*
X1645056Y1575641D03*
X1640332D03*
X1638657Y1569063D03*
X1635607Y1575641D03*
X1634653Y1625380D03*
X1638923D03*
X1646713D03*
X1640673Y1635286D03*
X1644953Y1635380D03*
X1640673Y1647292D03*
X1644953D03*
X1634653Y1657292D03*
X1638913D03*
X1646713D03*
X1648386Y1547243D03*
X1649780Y1540295D03*
X1654505D03*
X1657835Y1547243D03*
X1659229Y1540295D03*
X1662250Y1554453D03*
X1657505D03*
X1652781D03*
X1648056D03*
X1658056Y1561853D03*
X1653332D03*
X1648607D03*
X1649780Y1575641D03*
X1648106Y1569063D03*
X1654505Y1575641D03*
X1657555Y1569063D03*
X1659229Y1575641D03*
X1652743Y1635380D03*
Y1647292D03*
X1662886Y1569063D03*
G54D36*
X274913Y1019214D03*
X320189Y838505D03*
Y1199923D03*
X561133Y838505D03*
Y1199923D03*
X606409Y1019214D03*
X841240Y1420331D03*
X1016240D03*
X1251055Y1019213D03*
X1296331Y838504D03*
Y1199922D03*
X1537275Y838504D03*
Y1199922D03*
X1582551Y1019213D03*
G54D44*
X393287Y-28508D03*
Y-18508D03*
X731757Y-20090D03*
X735010Y-20104D03*
X728717Y-18895D03*
X734995Y-17589D03*
X731742Y-17575D03*
X735041Y-14717D03*
X735026Y-12202D03*
X734996Y-7172D03*
X728718Y-8478D03*
X735011Y-9687D03*
X731743Y-7158D03*
X731758Y-9673D03*
X844766Y-24648D03*
Y5352D03*
Y15352D03*
X1180124Y-35569D03*
X1183149Y-34249D03*
X1183164Y-36764D03*
X1183139Y-26179D03*
X1180099Y-14984D03*
X1183124Y-13664D03*
X1183139Y-16179D03*
X1183124Y-23664D03*
X1180099Y-24984D03*
X1183139Y-6179D03*
X1183124Y-3664D03*
X1180099Y-4984D03*
Y15016D03*
X1183124Y16336D03*
X1183139Y13821D03*
X1180099Y5016D03*
X1183124Y6336D03*
X1183139Y3821D03*
X1183140Y24187D03*
X1183125Y26702D03*
X1180100Y25382D03*
X1186402Y-34263D03*
X1186417Y-36778D03*
X1186448Y-31442D03*
X1186433Y-28927D03*
X1186392Y-26193D03*
X1186377Y-13678D03*
X1186392Y-16193D03*
X1186377Y-23678D03*
X1186392Y-6193D03*
X1186377Y-3678D03*
Y16322D03*
X1186392Y13807D03*
X1186377Y6322D03*
X1186392Y3807D03*
X1186423Y19143D03*
X1186408Y21658D03*
X1186393Y24173D03*
X1186378Y26688D03*
X1248286Y-34648D03*
Y-4648D03*
Y5352D03*
X1438983Y-35569D03*
X1438959Y25382D03*
X1445292Y-28927D03*
X1445307Y-31442D03*
X1442023Y-36764D03*
X1442008Y-34249D03*
X1445276Y-36778D03*
X1445261Y-34263D03*
X1441909Y-19948D03*
X1445171D03*
X1441909Y-9948D03*
X1445171D03*
X1441909Y52D03*
X1445171D03*
X1441909Y10052D03*
X1445171D03*
X1445237Y26688D03*
X1445252Y24173D03*
X1441984Y26702D03*
X1441999Y24187D03*
X1445267Y21658D03*
X1445282Y19143D03*
X1541580Y-38849D03*
Y-28849D03*
X1735374Y-27916D03*
X1732349Y-29236D03*
X1735389Y-30431D03*
X1735390Y-20014D03*
X1735375Y-17499D03*
X1732350Y-18819D03*
X1738627Y-27930D03*
X1738642Y-30445D03*
X1738643Y-20028D03*
X1738628Y-17513D03*
X1738673Y-25058D03*
X1738658Y-22543D03*
G54D78*
X1900275Y-39973D03*
X1910275D03*
X1931395Y572237D03*
X1921395D03*
X1929766Y1198160D03*
X1919766D03*
X1942395Y-39783D03*
X1952395D03*
X1963362Y572379D03*
X1961856Y1198170D03*
X1973362Y572379D03*
X1971856Y1198170D03*
X1984482Y-39811D03*
X1994482D03*
X2005452Y572389D03*
X2003823Y1198312D03*
X2015452Y572389D03*
X2013823Y1198312D03*
X2036452Y-39631D03*
X2026452D03*
X2047419Y572531D03*
X2057419D03*
G54D21*
X57646Y12480D03*
X137272D03*
X186622D03*
X266858D03*
X315598D03*
X502528Y33267D03*
X582154D03*
X631504D03*
X711740D03*
X760480D03*
X1532055Y12480D03*
X1611681D03*
X1661031D03*
X1741267D03*
X1790007D03*
G54D40*
X326731Y663237D03*
X363731D03*
X754645Y1436735D03*
X1166535Y1422322D03*
X1291146Y1385558D03*
X1320516D03*
X1487677Y649988D03*
X1524437Y650208D03*
X1701285Y208455D03*
X1700840Y1434362D03*
X1731660Y208455D03*
X1770442Y294777D03*
X1800002D03*
G54D62*
X1077638Y133866D03*
G54D26*
X77394Y734588D03*
Y1021399D03*
Y1277698D03*
X107095Y734588D03*
Y1021399D03*
Y1277698D03*
X136795Y734588D03*
Y1021399D03*
Y1277698D03*
X166496Y734588D03*
Y1021399D03*
Y1277698D03*
X196197Y734588D03*
Y1021399D03*
Y1277698D03*
X225898Y734588D03*
Y1021399D03*
Y1277698D03*
X655425Y734588D03*
Y1021399D03*
Y1277698D03*
X685126Y734588D03*
Y1021399D03*
Y1277698D03*
X714827Y734588D03*
Y1021399D03*
Y1277698D03*
X744528Y734588D03*
Y1021399D03*
Y1277698D03*
X774229Y734588D03*
Y1021399D03*
Y1277698D03*
X803929Y734588D03*
Y1021399D03*
Y1277698D03*
X1053536Y734587D03*
Y1021398D03*
Y1277697D03*
X1083237Y734587D03*
Y1021398D03*
Y1277697D03*
X1112937Y734587D03*
Y1021398D03*
Y1277697D03*
X1142638Y734587D03*
Y1021398D03*
Y1277697D03*
X1172339Y734587D03*
Y1021398D03*
Y1277697D03*
X1202040Y734587D03*
Y1021398D03*
Y1277697D03*
X1631567Y734587D03*
Y1021398D03*
Y1277697D03*
X1661268Y734587D03*
Y1021398D03*
Y1277697D03*
X1690969Y734587D03*
Y1021398D03*
Y1277697D03*
X1720670Y734587D03*
Y1021398D03*
Y1277697D03*
X1750371Y734587D03*
Y1021398D03*
Y1277697D03*
X1780071Y734587D03*
Y1021398D03*
Y1277697D03*
G54D56*
X887519Y1528191D03*
G54D68*
X1299439Y112812D03*
G54D69*
X1454797Y87432D03*
G54D70*
X1550377Y581353D03*
G54D48*
X549016Y274272D03*
G54D57*
X900197Y175177D03*
X944685Y155197D03*
G54D77*
X1864706Y1722195D03*
X1887340Y424013D03*
X1887240Y796658D03*
X1887579Y1171532D03*
G54D75*
X1865648Y796913D03*
X1866790Y1171255D03*
X1886177Y1722507D03*
X2076128Y424013D03*
%LPC*%
G75*
G54D82*
G01X-476840Y-884638D02*
Y2768362D01*
X5911000D01*
Y-884638D01*
X-476840D01*
G01X8000Y-625138D02*
Y-630138D01*
G01X6543Y-625138D02*
X9457D01*
G01X14367Y-630138D02*
X11833D01*
Y-625138D01*
X14367D01*
G01X13353Y-627555D02*
X11833D01*
G01X16933Y-625138D02*
Y-630138D01*
X19467D01*
G01X23300Y-630305D02*
X23173Y-630221D01*
Y-630055D01*
X23300Y-629971D01*
X23427Y-630055D01*
Y-630221D01*
X23300Y-630305D01*
G01Y-628055D02*
X23173Y-627971D01*
Y-627805D01*
X23300Y-627721D01*
X23427Y-627805D01*
Y-627971D01*
X23300Y-628055D01*
G01X28083Y-631805D02*
X27450Y-630971D01*
X27133Y-630138D01*
Y-626805D01*
X27450Y-625971D01*
X28083Y-625138D01*
G01X33500D02*
X32993Y-625305D01*
X32613Y-625721D01*
X32360Y-626221D01*
X32170Y-626888D01*
X32107Y-627638D01*
X32170Y-628388D01*
X32360Y-629055D01*
X32613Y-629555D01*
X32993Y-629971D01*
X33500Y-630138D01*
X34007Y-629971D01*
X34387Y-629555D01*
X34640Y-629055D01*
X34830Y-628388D01*
X34893Y-627638D01*
X34830Y-626888D01*
X34640Y-626221D01*
X34387Y-625721D01*
X34007Y-625305D01*
X33500Y-625138D01*
G01X37207Y-629138D02*
X37587Y-629721D01*
X38093Y-630055D01*
X38663Y-630138D01*
X39170Y-630055D01*
X39677Y-629638D01*
X39993Y-629138D01*
X40057Y-628638D01*
X39930Y-628055D01*
X39487Y-627638D01*
X39043Y-627471D01*
X38473D01*
G01X39043D02*
X39423Y-627221D01*
X39740Y-626805D01*
X39867Y-626305D01*
X39740Y-625805D01*
X39423Y-625388D01*
X38853Y-625138D01*
X38283Y-625221D01*
X37713Y-625555D01*
G01X44017Y-631805D02*
X44650Y-630971D01*
X44967Y-630138D01*
Y-626805D01*
X44650Y-625971D01*
X44017Y-625138D01*
G01X47407Y-629138D02*
X47787Y-629721D01*
X48293Y-630055D01*
X48863Y-630138D01*
X49370Y-630055D01*
X49877Y-629638D01*
X50193Y-629138D01*
X50257Y-628638D01*
X50130Y-628055D01*
X49687Y-627638D01*
X49243Y-627471D01*
X48673D01*
G01X49243D02*
X49623Y-627221D01*
X49940Y-626805D01*
X50067Y-626305D01*
X49940Y-625805D01*
X49623Y-625388D01*
X49053Y-625138D01*
X48483Y-625221D01*
X47913Y-625555D01*
G01X52697Y-625971D02*
X53077Y-625471D01*
X53520Y-625221D01*
X54027Y-625138D01*
X54660Y-625305D01*
X55103Y-625721D01*
X55230Y-626221D01*
X55167Y-626721D01*
X54913Y-627138D01*
X53647Y-627971D01*
X53077Y-628555D01*
X52697Y-629388D01*
X52570Y-630138D01*
X55230D01*
G01X58873D02*
X59000Y-629055D01*
X59190Y-628138D01*
X59443Y-627305D01*
X59760Y-626388D01*
X60267Y-625138D01*
X57733D01*
G01X63277Y-628471D02*
X64923D01*
G01X67997Y-625971D02*
X68377Y-625471D01*
X68820Y-625221D01*
X69327Y-625138D01*
X69960Y-625305D01*
X70403Y-625721D01*
X70530Y-626221D01*
X70467Y-626721D01*
X70213Y-627138D01*
X68947Y-627971D01*
X68377Y-628555D01*
X67997Y-629388D01*
X67870Y-630138D01*
X70530D01*
G01X72907Y-629138D02*
X73287Y-629721D01*
X73793Y-630055D01*
X74363Y-630138D01*
X74870Y-630055D01*
X75377Y-629638D01*
X75693Y-629138D01*
X75757Y-628638D01*
X75630Y-628055D01*
X75187Y-627638D01*
X74743Y-627471D01*
X74173D01*
G01X74743D02*
X75123Y-627221D01*
X75440Y-626805D01*
X75567Y-626305D01*
X75440Y-625805D01*
X75123Y-625388D01*
X74553Y-625138D01*
X73983Y-625221D01*
X73413Y-625555D01*
G01X80160Y-630138D02*
Y-625138D01*
X77817Y-628721D01*
X80983D01*
G01X83107Y-629388D02*
X83487Y-629805D01*
X83930Y-630055D01*
X84500Y-630138D01*
X85070Y-629971D01*
X85513Y-629638D01*
X85830Y-629055D01*
X85893Y-628388D01*
X85767Y-627721D01*
X85450Y-627305D01*
X85007Y-626971D01*
X84563Y-626888D01*
X84120Y-626971D01*
X83550Y-627305D01*
X83740Y-625138D01*
X85450D01*
G01X93497Y-630138D02*
Y-625138D01*
X95903D01*
G01X95017Y-627555D02*
X93497D01*
G01X98217Y-630138D02*
X99800Y-625138D01*
X101383Y-630138D01*
G01X100813Y-628388D02*
X98787D01*
G01X103570Y-630138D02*
X106230Y-625138D01*
G01X103570D02*
X106230Y-630138D01*
G01X110000Y-630305D02*
X109873Y-630221D01*
Y-630055D01*
X110000Y-629971D01*
X110127Y-630055D01*
Y-630221D01*
X110000Y-630305D01*
G01Y-628055D02*
X109873Y-627971D01*
Y-627805D01*
X110000Y-627721D01*
X110127Y-627805D01*
Y-627971D01*
X110000Y-628055D01*
G01X114783Y-631805D02*
X114150Y-630971D01*
X113833Y-630138D01*
Y-626805D01*
X114150Y-625971D01*
X114783Y-625138D01*
G01X120200D02*
X119693Y-625305D01*
X119313Y-625721D01*
X119060Y-626221D01*
X118870Y-626888D01*
X118807Y-627638D01*
X118870Y-628388D01*
X119060Y-629055D01*
X119313Y-629555D01*
X119693Y-629971D01*
X120200Y-630138D01*
X120707Y-629971D01*
X121087Y-629555D01*
X121340Y-629055D01*
X121530Y-628388D01*
X121593Y-627638D01*
X121530Y-626888D01*
X121340Y-626221D01*
X121087Y-625721D01*
X120707Y-625305D01*
X120200Y-625138D01*
G01X123907Y-629138D02*
X124287Y-629721D01*
X124793Y-630055D01*
X125363Y-630138D01*
X125870Y-630055D01*
X126377Y-629638D01*
X126693Y-629138D01*
X126757Y-628638D01*
X126630Y-628055D01*
X126187Y-627638D01*
X125743Y-627471D01*
X125173D01*
G01X125743D02*
X126123Y-627221D01*
X126440Y-626805D01*
X126567Y-626305D01*
X126440Y-625805D01*
X126123Y-625388D01*
X125553Y-625138D01*
X124983Y-625221D01*
X124413Y-625555D01*
G01X130717Y-631805D02*
X131350Y-630971D01*
X131667Y-630138D01*
Y-626805D01*
X131350Y-625971D01*
X130717Y-625138D01*
G01X134107Y-629138D02*
X134487Y-629721D01*
X134993Y-630055D01*
X135563Y-630138D01*
X136070Y-630055D01*
X136577Y-629638D01*
X136893Y-629138D01*
X136957Y-628638D01*
X136830Y-628055D01*
X136387Y-627638D01*
X135943Y-627471D01*
X135373D01*
G01X135943D02*
X136323Y-627221D01*
X136640Y-626805D01*
X136767Y-626305D01*
X136640Y-625805D01*
X136323Y-625388D01*
X135753Y-625138D01*
X135183Y-625221D01*
X134613Y-625555D01*
G01X139523Y-629555D02*
X139967Y-629971D01*
X140473Y-630138D01*
X140980Y-629971D01*
X141423Y-629471D01*
X141740Y-628721D01*
X141867Y-627971D01*
Y-627055D01*
X141740Y-626305D01*
X141423Y-625638D01*
X141043Y-625305D01*
X140600Y-625138D01*
X140093Y-625305D01*
X139713Y-625638D01*
X139460Y-626138D01*
X139333Y-626805D01*
X139460Y-627388D01*
X139777Y-627971D01*
X140157Y-628305D01*
X140600Y-628388D01*
X141107Y-628221D01*
X141487Y-627805D01*
X141867Y-627055D01*
G01X145573Y-630138D02*
X145700Y-629055D01*
X145890Y-628138D01*
X146143Y-627305D01*
X146460Y-626388D01*
X146967Y-625138D01*
X144433D01*
G01X149977Y-628471D02*
X151623D01*
G01X154507Y-629138D02*
X154887Y-629721D01*
X155393Y-630055D01*
X155963Y-630138D01*
X156470Y-630055D01*
X156977Y-629638D01*
X157293Y-629138D01*
X157357Y-628638D01*
X157230Y-628055D01*
X156787Y-627638D01*
X156343Y-627471D01*
X155773D01*
G01X156343D02*
X156723Y-627221D01*
X157040Y-626805D01*
X157167Y-626305D01*
X157040Y-625805D01*
X156723Y-625388D01*
X156153Y-625138D01*
X155583Y-625221D01*
X155013Y-625555D01*
G01X159797Y-628055D02*
X160240Y-627471D01*
X160620Y-627138D01*
X161127Y-626971D01*
X161570Y-627138D01*
X161887Y-627471D01*
X162140Y-627971D01*
X162203Y-628555D01*
X162140Y-629055D01*
X161887Y-629555D01*
X161507Y-629971D01*
X161063Y-630138D01*
X160557Y-629971D01*
X160113Y-629471D01*
X159860Y-628721D01*
X159797Y-627888D01*
X159923Y-626805D01*
X160113Y-626221D01*
X160430Y-625638D01*
X160873Y-625221D01*
X161317Y-625138D01*
X161760Y-625305D01*
X162077Y-625721D01*
G01X166100Y-630138D02*
Y-625138D01*
X165340Y-626138D01*
G01Y-630138D02*
X166860D01*
G01X171960D02*
Y-625138D01*
X169617Y-628721D01*
X172783D01*
G01X-4000Y-560138D02*
Y-635138D01*
X496000D01*
Y-560138D01*
X-4000D01*
G01X191000D02*
Y-635138D01*
G01Y-610138D02*
X294000D01*
Y-585138D01*
G01X191000D02*
X294000D01*
G01X296000Y-560138D02*
Y-635138D01*
G01X294000Y-560138D02*
Y-635138D01*
G01X301507Y-620138D02*
Y-615138D01*
X302773D01*
X303280Y-615388D01*
X303660Y-615721D01*
X303977Y-616221D01*
X304230Y-616805D01*
X304293Y-617638D01*
X304230Y-618471D01*
X303977Y-619055D01*
X303660Y-619555D01*
X303280Y-619888D01*
X302773Y-620138D01*
X301507D01*
G01X306417D02*
X308000Y-615138D01*
X309583Y-620138D01*
G01X309013Y-618388D02*
X306987D01*
G01X313100Y-615138D02*
Y-620138D01*
G01X311643Y-615138D02*
X314557D01*
G01X319467Y-620138D02*
X316933D01*
Y-615138D01*
X319467D01*
G01X318453Y-617555D02*
X316933D01*
G01X323300Y-620305D02*
X323173Y-620221D01*
Y-620055D01*
X323300Y-619971D01*
X323427Y-620055D01*
Y-620221D01*
X323300Y-620305D01*
G01Y-618055D02*
X323173Y-617971D01*
Y-617805D01*
X323300Y-617721D01*
X323427Y-617805D01*
Y-617971D01*
X323300Y-618055D01*
G01X296000Y-610138D02*
X496000D01*
G01X301633Y-595138D02*
Y-590138D01*
X303153D01*
X303660Y-590388D01*
X304040Y-590971D01*
X304167Y-591638D01*
X304040Y-592305D01*
X303723Y-592805D01*
X303153Y-593055D01*
X301633D01*
G01X306860Y-595305D02*
X309140Y-590138D01*
G01X311643Y-595138D02*
Y-590138D01*
X314557Y-595138D01*
Y-590138D01*
G01X318200Y-595305D02*
X318073Y-595221D01*
Y-595055D01*
X318200Y-594971D01*
X318327Y-595055D01*
Y-595221D01*
X318200Y-595305D01*
G01Y-593055D02*
X318073Y-592971D01*
Y-592805D01*
X318200Y-592721D01*
X318327Y-592805D01*
Y-592971D01*
X318200Y-593055D01*
G01X296000Y-585138D02*
X496000D01*
G01X301633Y-570138D02*
Y-565138D01*
X303153D01*
X303660Y-565388D01*
X304040Y-565971D01*
X304167Y-566638D01*
X304040Y-567305D01*
X303723Y-567805D01*
X303153Y-568055D01*
X301633D01*
G01X306733Y-570138D02*
Y-565138D01*
X308317D01*
X308823Y-565388D01*
X309140Y-565721D01*
X309267Y-566388D01*
X309140Y-567055D01*
X308760Y-567471D01*
X308317Y-567721D01*
X306733D01*
G01X308317D02*
X309267Y-570138D01*
G01X313100D02*
X312593Y-570055D01*
X312150Y-569721D01*
X311770Y-569221D01*
X311517Y-568638D01*
X311390Y-567971D01*
Y-567305D01*
X311517Y-566638D01*
X311770Y-566055D01*
X312150Y-565555D01*
X312593Y-565221D01*
X313100Y-565138D01*
X313607Y-565221D01*
X314050Y-565555D01*
X314430Y-566055D01*
X314683Y-566638D01*
X314810Y-567305D01*
Y-567971D01*
X314683Y-568638D01*
X314430Y-569221D01*
X314050Y-569721D01*
X313607Y-570055D01*
X313100Y-570138D01*
G01X316933Y-569138D02*
X317250Y-569638D01*
X317630Y-569971D01*
X318073Y-570138D01*
X318580Y-569971D01*
X318960Y-569638D01*
X319340Y-569138D01*
X319467Y-568471D01*
Y-565138D01*
G01X324567Y-570138D02*
X322033D01*
Y-565138D01*
X324567D01*
G01X323553Y-567555D02*
X322033D01*
G01X329793Y-565555D02*
X329413Y-565305D01*
X328970Y-565138D01*
X328463D01*
X327893Y-565388D01*
X327450Y-565805D01*
X327133Y-566305D01*
X326880Y-567138D01*
X326817Y-567888D01*
X326943Y-568638D01*
X327133Y-569138D01*
X327513Y-569638D01*
X327957Y-569971D01*
X328400Y-570138D01*
X328843D01*
X329287Y-569971D01*
X329667Y-569721D01*
X329983Y-569388D01*
G01X333500Y-565138D02*
Y-570138D01*
G01X332043Y-565138D02*
X334957D01*
G01X338600Y-570305D02*
X338473Y-570221D01*
Y-570055D01*
X338600Y-569971D01*
X338727Y-570055D01*
Y-570221D01*
X338600Y-570305D01*
G01Y-568055D02*
X338473Y-567971D01*
Y-567805D01*
X338600Y-567721D01*
X338727Y-567805D01*
Y-567971D01*
X338600Y-568055D01*
G01X411000Y-610138D02*
Y-635138D01*
G01X413633Y-612638D02*
Y-617638D01*
X416167D01*
G01X419240Y-612638D02*
X420760D01*
G01X420000D02*
Y-617638D01*
G01X419240D02*
X420760D01*
G01X425607Y-614971D02*
X425860Y-614721D01*
X426050Y-614305D01*
X426177Y-613721D01*
X426050Y-613221D01*
X425797Y-612888D01*
X425353Y-612638D01*
X423643D01*
Y-617638D01*
X425733D01*
X426177Y-617305D01*
X426430Y-616805D01*
X426557Y-616221D01*
X426430Y-615638D01*
X426050Y-615138D01*
X425607Y-614971D01*
X423643D01*
G01X430200Y-617805D02*
X430073Y-617721D01*
Y-617555D01*
X430200Y-617471D01*
X430327Y-617555D01*
Y-617721D01*
X430200Y-617805D01*
G01Y-615555D02*
X430073Y-615471D01*
Y-615305D01*
X430200Y-615221D01*
X430327Y-615305D01*
Y-615471D01*
X430200Y-615555D01*
G01X454000Y-610138D02*
Y-635138D01*
G01Y-585138D02*
Y-610138D01*
G01X459013Y-637305D02*
X459120Y-637180D01*
X459200Y-636971D01*
X459253Y-636680D01*
X459200Y-636430D01*
X459093Y-636263D01*
X458907Y-636138D01*
X458187D01*
Y-638638D01*
X459067D01*
X459253Y-638471D01*
X459360Y-638221D01*
X459413Y-637930D01*
X459360Y-637638D01*
X459200Y-637388D01*
X459013Y-637305D01*
X458187D01*
G01X461480Y-638638D02*
Y-636971D01*
G01Y-637263D02*
X461373Y-637096D01*
X461213Y-637013D01*
X461027Y-636971D01*
X460840Y-637055D01*
X460680Y-637221D01*
X460573Y-637471D01*
X460520Y-637805D01*
X460573Y-638138D01*
X460680Y-638388D01*
X460840Y-638555D01*
X461027Y-638638D01*
X461213Y-638596D01*
X461373Y-638471D01*
X461480Y-638305D01*
G01X462800Y-638346D02*
X462933Y-638513D01*
X463120Y-638638D01*
X463280D01*
X463440Y-638555D01*
X463547Y-638430D01*
X463600Y-638263D01*
X463573Y-638013D01*
X463467Y-637888D01*
X462987Y-637638D01*
X462880Y-637346D01*
X462933Y-637138D01*
X463040Y-637013D01*
X463200Y-636971D01*
X463360Y-637013D01*
X463520Y-637138D01*
G01X465000Y-637513D02*
X465853D01*
X465773Y-637221D01*
X465640Y-637055D01*
X465453Y-636971D01*
X465267Y-637013D01*
X465107Y-637138D01*
X465000Y-637430D01*
X464947Y-637680D01*
Y-637930D01*
X465000Y-638180D01*
X465133Y-638430D01*
X465293Y-638596D01*
X465480Y-638638D01*
X465667Y-638555D01*
X465853Y-638305D01*
G01X467120Y-638638D02*
Y-636138D01*
G01Y-637388D02*
X467253Y-637138D01*
X467413Y-637013D01*
X467573Y-636971D01*
X467813Y-637055D01*
X467973Y-637221D01*
X468080Y-637513D01*
Y-637846D01*
X468027Y-638180D01*
X467920Y-638430D01*
X467733Y-638596D01*
X467573Y-638638D01*
X467413Y-638596D01*
X467253Y-638471D01*
X467120Y-638263D01*
G01X469800Y-638638D02*
X469640Y-638596D01*
X469480Y-638430D01*
X469373Y-638138D01*
X469320Y-637805D01*
X469373Y-637471D01*
X469480Y-637180D01*
X469640Y-637013D01*
X469800Y-636971D01*
X469960Y-637013D01*
X470120Y-637180D01*
X470227Y-637471D01*
X470253Y-637805D01*
X470227Y-638138D01*
X470120Y-638430D01*
X469960Y-638596D01*
X469800Y-638638D01*
G01X472480D02*
Y-636971D01*
G01Y-637263D02*
X472373Y-637096D01*
X472213Y-637013D01*
X472027Y-636971D01*
X471840Y-637055D01*
X471680Y-637221D01*
X471573Y-637471D01*
X471520Y-637805D01*
X471573Y-638138D01*
X471680Y-638388D01*
X471840Y-638555D01*
X472027Y-638638D01*
X472213Y-638596D01*
X472373Y-638471D01*
X472480Y-638305D01*
G01X473827Y-638638D02*
Y-636971D01*
G01Y-637305D02*
X473960Y-637138D01*
X474093Y-637013D01*
X474280Y-636971D01*
X474413Y-637013D01*
X474573Y-637138D01*
G01X476880Y-636138D02*
Y-638638D01*
G01Y-638263D02*
X476773Y-638471D01*
X476613Y-638596D01*
X476427Y-638638D01*
X476213Y-638555D01*
X476053Y-638346D01*
X475947Y-638096D01*
X475920Y-637805D01*
X475947Y-637513D01*
X476053Y-637263D01*
X476213Y-637055D01*
X476427Y-636971D01*
X476613Y-637013D01*
X476747Y-637096D01*
X476880Y-637263D01*
G01X480267Y-638638D02*
Y-636138D01*
X480933D01*
X481147Y-636263D01*
X481280Y-636430D01*
X481333Y-636763D01*
X481280Y-637096D01*
X481120Y-637305D01*
X480933Y-637430D01*
X480267D01*
G01X480933D02*
X481333Y-638638D01*
G01X482600Y-637513D02*
X483453D01*
X483373Y-637221D01*
X483240Y-637055D01*
X483053Y-636971D01*
X482867Y-637013D01*
X482707Y-637138D01*
X482600Y-637430D01*
X482547Y-637680D01*
Y-637930D01*
X482600Y-638180D01*
X482733Y-638430D01*
X482893Y-638596D01*
X483080Y-638638D01*
X483267Y-638555D01*
X483453Y-638305D01*
G01X484720Y-636971D02*
X485200Y-638638D01*
X485680Y-636971D01*
G01X487400Y-638721D02*
X487347Y-638680D01*
Y-638596D01*
X487400Y-638555D01*
X487453Y-638596D01*
Y-638680D01*
X487400Y-638721D01*
G01X489147Y-638346D02*
X489333Y-638555D01*
X489547Y-638638D01*
X489760Y-638555D01*
X489947Y-638305D01*
X490080Y-637930D01*
X490133Y-637555D01*
Y-637096D01*
X490080Y-636721D01*
X489947Y-636388D01*
X489787Y-636221D01*
X489600Y-636138D01*
X489387Y-636221D01*
X489227Y-636388D01*
X489120Y-636638D01*
X489067Y-636971D01*
X489120Y-637263D01*
X489253Y-637555D01*
X489413Y-637721D01*
X489600Y-637763D01*
X489813Y-637680D01*
X489973Y-637471D01*
X490133Y-637096D01*
G01X492013Y-637305D02*
X492120Y-637180D01*
X492200Y-636971D01*
X492253Y-636680D01*
X492200Y-636430D01*
X492093Y-636263D01*
X491907Y-636138D01*
X491187D01*
Y-638638D01*
X492067D01*
X492253Y-638471D01*
X492360Y-638221D01*
X492413Y-637930D01*
X492360Y-637638D01*
X492200Y-637388D01*
X492013Y-637305D01*
X491187D01*
G01X457900Y-612638D02*
Y-617638D01*
G01X456443Y-612638D02*
X459357D01*
G01X463000Y-617638D02*
X462620Y-617555D01*
X462240Y-617221D01*
X461987Y-616638D01*
X461860Y-615971D01*
X461987Y-615305D01*
X462240Y-614721D01*
X462620Y-614388D01*
X463000Y-614305D01*
X463380Y-614388D01*
X463760Y-614721D01*
X464013Y-615305D01*
X464077Y-615971D01*
X464013Y-616638D01*
X463760Y-617221D01*
X463380Y-617555D01*
X463000Y-617638D01*
G01X468100D02*
X467720Y-617555D01*
X467340Y-617221D01*
X467087Y-616638D01*
X466960Y-615971D01*
X467087Y-615305D01*
X467340Y-614721D01*
X467720Y-614388D01*
X468100Y-614305D01*
X468480Y-614388D01*
X468860Y-614721D01*
X469113Y-615305D01*
X469177Y-615971D01*
X469113Y-616638D01*
X468860Y-617221D01*
X468480Y-617555D01*
X468100Y-617638D01*
G01X473200D02*
Y-612638D01*
G01X478300Y-617805D02*
X478173Y-617721D01*
Y-617555D01*
X478300Y-617471D01*
X478427Y-617555D01*
Y-617721D01*
X478300Y-617805D01*
G01Y-615555D02*
X478173Y-615471D01*
Y-615305D01*
X478300Y-615221D01*
X478427Y-615305D01*
Y-615471D01*
X478300Y-615555D01*
G01X456633Y-592638D02*
Y-587638D01*
X458217D01*
X458723Y-587888D01*
X459040Y-588221D01*
X459167Y-588888D01*
X459040Y-589555D01*
X458660Y-589971D01*
X458217Y-590221D01*
X456633D01*
G01X458217D02*
X459167Y-592638D01*
G01X464267D02*
X461733D01*
Y-587638D01*
X464267D01*
G01X463253Y-590055D02*
X461733D01*
G01X466517Y-587638D02*
X468100Y-592638D01*
X469683Y-587638D01*
G01X473200Y-592805D02*
X473073Y-592721D01*
Y-592555D01*
X473200Y-592471D01*
X473327Y-592555D01*
Y-592721D01*
X473200Y-592805D01*
G01Y-590555D02*
X473073Y-590471D01*
Y-590305D01*
X473200Y-590221D01*
X473327Y-590305D01*
Y-590471D01*
X473200Y-590555D01*
G01X-476840Y-884638D02*
Y2768362D01*
X5911000D01*
Y-884638D01*
X-476840D01*
G01X8820Y-607488D02*
X10387D01*
Y-609378D01*
X9917Y-610008D01*
X9368Y-610428D01*
X8585Y-610638D01*
X7802Y-610428D01*
X7253Y-610008D01*
X6783Y-609378D01*
X6470Y-608643D01*
X6313Y-607803D01*
Y-607068D01*
X6470Y-606438D01*
X6783Y-605703D01*
X7253Y-605073D01*
X7723Y-604653D01*
X8350Y-604338D01*
X8898D01*
X9525Y-604548D01*
X9995Y-604968D01*
G01X12927Y-604338D02*
Y-608853D01*
X13240Y-609798D01*
X13867Y-610428D01*
X14650Y-610638D01*
X15433Y-610428D01*
X16060Y-609798D01*
X16373Y-608853D01*
Y-604338D01*
G01X20010D02*
X21890D01*
G01X20950D02*
Y-610638D01*
G01X20010D02*
X21890D01*
G01X25605Y-609798D02*
X26232Y-610323D01*
X26937Y-610638D01*
X27563D01*
X28190Y-610323D01*
X28660Y-609798D01*
X28895Y-609063D01*
X28738Y-608328D01*
X28347Y-607698D01*
X27642Y-607278D01*
X26702Y-607068D01*
X26153Y-606648D01*
X25918Y-605913D01*
X26075Y-605178D01*
X26467Y-604653D01*
X27015Y-604338D01*
X27563D01*
X28112Y-604548D01*
X28582Y-605073D01*
G01X31905Y-610638D02*
Y-604338D01*
G01X35195D02*
Y-610638D01*
G01Y-607488D02*
X31905D01*
G01X37892Y-610638D02*
X39850Y-604338D01*
X41808Y-610638D01*
G01X41103Y-608433D02*
X38597D01*
G01X44348Y-610638D02*
Y-604338D01*
X47952Y-610638D01*
Y-604338D01*
G01X57027Y-610638D02*
Y-604338D01*
X58593D01*
X59220Y-604653D01*
X59690Y-605073D01*
X60082Y-605703D01*
X60395Y-606438D01*
X60473Y-607488D01*
X60395Y-608538D01*
X60082Y-609273D01*
X59690Y-609903D01*
X59220Y-610323D01*
X58593Y-610638D01*
X57027D01*
G01X64110Y-604338D02*
X65990D01*
G01X65050D02*
Y-610638D01*
G01X64110D02*
X65990D01*
G01X69705Y-609798D02*
X70332Y-610323D01*
X71037Y-610638D01*
X71663D01*
X72290Y-610323D01*
X72760Y-609798D01*
X72995Y-609063D01*
X72838Y-608328D01*
X72447Y-607698D01*
X71742Y-607278D01*
X70802Y-607068D01*
X70253Y-606648D01*
X70018Y-605913D01*
X70175Y-605178D01*
X70567Y-604653D01*
X71115Y-604338D01*
X71663D01*
X72212Y-604548D01*
X72682Y-605073D01*
G01X77650Y-604338D02*
Y-610638D01*
G01X75848Y-604338D02*
X79452D01*
G01X83950Y-610848D02*
X83793Y-610743D01*
Y-610533D01*
X83950Y-610428D01*
X84107Y-610533D01*
Y-610743D01*
X83950Y-610848D01*
G01X90093Y-611793D02*
X90407Y-610428D01*
G01X96550Y-604338D02*
Y-610638D01*
G01X94748Y-604338D02*
X98352D01*
G01X100892Y-610638D02*
X102850Y-604338D01*
X104808Y-610638D01*
G01X104103Y-608433D02*
X101597D01*
G01X109150Y-610638D02*
X108523Y-610533D01*
X107975Y-610113D01*
X107505Y-609483D01*
X107192Y-608748D01*
X107035Y-607908D01*
Y-607068D01*
X107192Y-606228D01*
X107505Y-605493D01*
X107975Y-604863D01*
X108523Y-604443D01*
X109150Y-604338D01*
X109777Y-604443D01*
X110325Y-604863D01*
X110795Y-605493D01*
X111108Y-606228D01*
X111265Y-607068D01*
Y-607908D01*
X111108Y-608748D01*
X110795Y-609483D01*
X110325Y-610113D01*
X109777Y-610533D01*
X109150Y-610638D01*
G01X115450D02*
Y-607803D01*
X113883Y-604338D01*
G01X117017D02*
X115450Y-607803D01*
G01X120027Y-604338D02*
Y-608853D01*
X120340Y-609798D01*
X120967Y-610428D01*
X121750Y-610638D01*
X122533Y-610428D01*
X123160Y-609798D01*
X123473Y-608853D01*
Y-604338D01*
G01X126092Y-610638D02*
X128050Y-604338D01*
X130008Y-610638D01*
G01X129303Y-608433D02*
X126797D01*
G01X132548Y-610638D02*
Y-604338D01*
X136152Y-610638D01*
Y-604338D01*
G01X10073Y-614863D02*
X9603Y-614548D01*
X9055Y-614338D01*
X8428D01*
X7723Y-614653D01*
X7175Y-615178D01*
X6783Y-615808D01*
X6470Y-616858D01*
X6392Y-617803D01*
X6548Y-618748D01*
X6783Y-619378D01*
X7253Y-620008D01*
X7802Y-620428D01*
X8350Y-620638D01*
X8898D01*
X9447Y-620428D01*
X9917Y-620113D01*
X10308Y-619693D01*
G01X13710Y-614338D02*
X15590D01*
G01X14650D02*
Y-620638D01*
G01X13710D02*
X15590D01*
G01X20950Y-614338D02*
Y-620638D01*
G01X19148Y-614338D02*
X22752D01*
G01X27250Y-620638D02*
Y-617803D01*
X25683Y-614338D01*
G01X28817D02*
X27250Y-617803D01*
G01X38127Y-619378D02*
X38597Y-620113D01*
X39223Y-620533D01*
X39928Y-620638D01*
X40555Y-620533D01*
X41182Y-620008D01*
X41573Y-619378D01*
X41652Y-618748D01*
X41495Y-618013D01*
X40947Y-617488D01*
X40398Y-617278D01*
X39693D01*
G01X40398D02*
X40868Y-616963D01*
X41260Y-616438D01*
X41417Y-615808D01*
X41260Y-615178D01*
X40868Y-614653D01*
X40163Y-614338D01*
X39458Y-614443D01*
X38753Y-614863D01*
G01X44427Y-619378D02*
X44897Y-620113D01*
X45523Y-620533D01*
X46228Y-620638D01*
X46855Y-620533D01*
X47482Y-620008D01*
X47873Y-619378D01*
X47952Y-618748D01*
X47795Y-618013D01*
X47247Y-617488D01*
X46698Y-617278D01*
X45993D01*
G01X46698D02*
X47168Y-616963D01*
X47560Y-616438D01*
X47717Y-615808D01*
X47560Y-615178D01*
X47168Y-614653D01*
X46463Y-614338D01*
X45758Y-614443D01*
X45053Y-614863D01*
G01X50727Y-619378D02*
X51197Y-620113D01*
X51823Y-620533D01*
X52528Y-620638D01*
X53155Y-620533D01*
X53782Y-620008D01*
X54173Y-619378D01*
X54252Y-618748D01*
X54095Y-618013D01*
X53547Y-617488D01*
X52998Y-617278D01*
X52293D01*
G01X52998D02*
X53468Y-616963D01*
X53860Y-616438D01*
X54017Y-615808D01*
X53860Y-615178D01*
X53468Y-614653D01*
X52763Y-614338D01*
X52058Y-614443D01*
X51353Y-614863D01*
G01X58593Y-620638D02*
X58750Y-619273D01*
X58985Y-618118D01*
X59298Y-617068D01*
X59690Y-615913D01*
X60317Y-614338D01*
X57183D01*
G01X64893Y-620638D02*
X65050Y-619273D01*
X65285Y-618118D01*
X65598Y-617068D01*
X65990Y-615913D01*
X66617Y-614338D01*
X63483D01*
G01X71193Y-621793D02*
X71507Y-620428D01*
G01X77650Y-614338D02*
Y-620638D01*
G01X75848Y-614338D02*
X79452D01*
G01X81992Y-620638D02*
X83950Y-614338D01*
X85908Y-620638D01*
G01X85203Y-618433D02*
X82697D01*
G01X89310Y-614338D02*
X91190D01*
G01X90250D02*
Y-620638D01*
G01X89310D02*
X91190D01*
G01X94200Y-614338D02*
X95297Y-620638D01*
X96550Y-614338D01*
X97803Y-620638D01*
X98900Y-614338D01*
G01X100892Y-620638D02*
X102850Y-614338D01*
X104808Y-620638D01*
G01X104103Y-618433D02*
X101597D01*
G01X107348Y-620638D02*
Y-614338D01*
X110952Y-620638D01*
Y-614338D01*
G01X121358Y-622738D02*
X120575Y-621688D01*
X120183Y-620638D01*
Y-616438D01*
X120575Y-615388D01*
X121358Y-614338D01*
G01X132783Y-620638D02*
Y-614338D01*
X134742D01*
X135368Y-614653D01*
X135760Y-615073D01*
X135917Y-615913D01*
X135760Y-616753D01*
X135290Y-617278D01*
X134742Y-617593D01*
X132783D01*
G01X134742D02*
X135917Y-620638D01*
G01X140650Y-620848D02*
X140493Y-620743D01*
Y-620533D01*
X140650Y-620428D01*
X140807Y-620533D01*
Y-620743D01*
X140650Y-620848D01*
G01X146950Y-620638D02*
X146323Y-620533D01*
X145775Y-620113D01*
X145305Y-619483D01*
X144992Y-618748D01*
X144835Y-617908D01*
Y-617068D01*
X144992Y-616228D01*
X145305Y-615493D01*
X145775Y-614863D01*
X146323Y-614443D01*
X146950Y-614338D01*
X147577Y-614443D01*
X148125Y-614863D01*
X148595Y-615493D01*
X148908Y-616228D01*
X149065Y-617068D01*
Y-617908D01*
X148908Y-618748D01*
X148595Y-619483D01*
X148125Y-620113D01*
X147577Y-620533D01*
X146950Y-620638D01*
G01X153250Y-620848D02*
X153093Y-620743D01*
Y-620533D01*
X153250Y-620428D01*
X153407Y-620533D01*
Y-620743D01*
X153250Y-620848D01*
G01X161273Y-614863D02*
X160803Y-614548D01*
X160255Y-614338D01*
X159628D01*
X158923Y-614653D01*
X158375Y-615178D01*
X157983Y-615808D01*
X157670Y-616858D01*
X157592Y-617803D01*
X157748Y-618748D01*
X157983Y-619378D01*
X158453Y-620008D01*
X159002Y-620428D01*
X159550Y-620638D01*
X160098D01*
X160647Y-620428D01*
X161117Y-620113D01*
X161508Y-619693D01*
G01X165850Y-620848D02*
X165693Y-620743D01*
Y-620533D01*
X165850Y-620428D01*
X166007Y-620533D01*
Y-620743D01*
X165850Y-620848D01*
G01X172542Y-622738D02*
X173325Y-621688D01*
X173717Y-620638D01*
Y-616438D01*
X173325Y-615388D01*
X172542Y-614338D01*
G01X6548Y-600638D02*
Y-594338D01*
X10152Y-600638D01*
Y-594338D01*
G01X14650Y-600638D02*
X14023Y-600533D01*
X13475Y-600113D01*
X13005Y-599483D01*
X12692Y-598748D01*
X12535Y-597908D01*
Y-597068D01*
X12692Y-596228D01*
X13005Y-595493D01*
X13475Y-594863D01*
X14023Y-594443D01*
X14650Y-594338D01*
X15277Y-594443D01*
X15825Y-594863D01*
X16295Y-595493D01*
X16608Y-596228D01*
X16765Y-597068D01*
Y-597908D01*
X16608Y-598748D01*
X16295Y-599483D01*
X15825Y-600113D01*
X15277Y-600533D01*
X14650Y-600638D01*
G01X20950Y-600848D02*
X20793Y-600743D01*
Y-600533D01*
X20950Y-600428D01*
X21107Y-600533D01*
Y-600743D01*
X20950Y-600848D01*
G01X25762Y-595388D02*
X26232Y-594758D01*
X26780Y-594443D01*
X27407Y-594338D01*
X28190Y-594548D01*
X28738Y-595073D01*
X28895Y-595703D01*
X28817Y-596333D01*
X28503Y-596858D01*
X26937Y-597908D01*
X26232Y-598643D01*
X25762Y-599693D01*
X25605Y-600638D01*
X28895D01*
G01X33550D02*
Y-594338D01*
X32610Y-595598D01*
G01Y-600638D02*
X34490D01*
G01X39850D02*
Y-594338D01*
X38910Y-595598D01*
G01Y-600638D02*
X40790D01*
G01X45993Y-601793D02*
X46307Y-600428D01*
G01X50100Y-594338D02*
X51197Y-600638D01*
X52450Y-594338D01*
X53703Y-600638D01*
X54800Y-594338D01*
G01X60317Y-600638D02*
X57183D01*
Y-594338D01*
X60317D01*
G01X59063Y-597383D02*
X57183D01*
G01X63248Y-600638D02*
Y-594338D01*
X66852Y-600638D01*
Y-594338D01*
G01X69705Y-600638D02*
Y-594338D01*
G01X72995D02*
Y-600638D01*
G01Y-597488D02*
X69705D01*
G01X75927Y-594338D02*
Y-598853D01*
X76240Y-599798D01*
X76867Y-600428D01*
X77650Y-600638D01*
X78433Y-600428D01*
X79060Y-599798D01*
X79373Y-598853D01*
Y-594338D01*
G01X81992Y-600638D02*
X83950Y-594338D01*
X85908Y-600638D01*
G01X85203Y-598433D02*
X82697D01*
G01X95062Y-595388D02*
X95532Y-594758D01*
X96080Y-594443D01*
X96707Y-594338D01*
X97490Y-594548D01*
X98038Y-595073D01*
X98195Y-595703D01*
X98117Y-596333D01*
X97803Y-596858D01*
X96237Y-597908D01*
X95532Y-598643D01*
X95062Y-599693D01*
X94905Y-600638D01*
X98195D01*
G01X101048D02*
Y-594338D01*
X104652Y-600638D01*
Y-594338D01*
G01X107427Y-600638D02*
Y-594338D01*
X108993D01*
X109620Y-594653D01*
X110090Y-595073D01*
X110482Y-595703D01*
X110795Y-596438D01*
X110873Y-597488D01*
X110795Y-598538D01*
X110482Y-599273D01*
X110090Y-599903D01*
X109620Y-600323D01*
X108993Y-600638D01*
X107427D01*
G01X120183D02*
Y-594338D01*
X122142D01*
X122768Y-594653D01*
X123160Y-595073D01*
X123317Y-595913D01*
X123160Y-596753D01*
X122690Y-597278D01*
X122142Y-597593D01*
X120183D01*
G01X122142D02*
X123317Y-600638D01*
G01X126327D02*
Y-594338D01*
X127893D01*
X128520Y-594653D01*
X128990Y-595073D01*
X129382Y-595703D01*
X129695Y-596438D01*
X129773Y-597488D01*
X129695Y-598538D01*
X129382Y-599273D01*
X128990Y-599903D01*
X128520Y-600323D01*
X127893Y-600638D01*
X126327D01*
G01X134350Y-600848D02*
X134193Y-600743D01*
Y-600533D01*
X134350Y-600428D01*
X134507Y-600533D01*
Y-600743D01*
X134350Y-600848D01*
G01X30650Y-589938D02*
X28130Y-589521D01*
X25925Y-587855D01*
X24035Y-585355D01*
X22775Y-582438D01*
X22145Y-579105D01*
Y-575771D01*
X22775Y-572438D01*
X24035Y-569521D01*
X25925Y-567022D01*
X28130Y-565355D01*
X30650Y-564938D01*
X33170Y-565355D01*
X35375Y-567022D01*
X37265Y-569521D01*
X38525Y-572438D01*
X39155Y-575771D01*
Y-579105D01*
X38525Y-582438D01*
X37265Y-585355D01*
X35375Y-587855D01*
X33170Y-589521D01*
X30650Y-589938D01*
G01X33170Y-583271D02*
X36950Y-589938D01*
G01X50495Y-573272D02*
Y-584938D01*
X51755Y-587855D01*
X53645Y-589521D01*
X55850Y-589938D01*
X58055Y-589521D01*
X59945Y-587855D01*
X61205Y-584938D01*
G01Y-589938D02*
Y-573272D01*
G01X86720Y-589938D02*
Y-573272D01*
G01Y-576188D02*
X85460Y-574522D01*
X83570Y-573688D01*
X81365Y-573272D01*
X79160Y-574105D01*
X77270Y-575771D01*
X76010Y-578272D01*
X75380Y-581605D01*
X76010Y-584938D01*
X77270Y-587439D01*
X79160Y-589105D01*
X81365Y-589938D01*
X83570Y-589521D01*
X85460Y-588272D01*
X86720Y-586605D01*
G01X100895Y-589938D02*
Y-573272D01*
G01Y-577438D02*
X102155Y-575355D01*
X104045Y-573688D01*
X106565Y-573272D01*
X108770Y-573688D01*
X110660Y-575355D01*
X111605Y-578272D01*
Y-589938D01*
G01X131450Y-564938D02*
Y-589938D01*
G01X127040Y-573272D02*
X135860D01*
G01X162320Y-589938D02*
Y-573272D01*
G01Y-576188D02*
X161060Y-574522D01*
X159170Y-573688D01*
X156965Y-573272D01*
X154760Y-574105D01*
X152870Y-575771D01*
X151610Y-578272D01*
X150980Y-581605D01*
X151610Y-584938D01*
X152870Y-587439D01*
X154760Y-589105D01*
X156965Y-589938D01*
X159170Y-589521D01*
X161060Y-588272D01*
X162320Y-586605D01*
G01X202000Y-569638D02*
Y-577638D01*
X206000D01*
G01X213800D02*
Y-572305D01*
G01Y-573238D02*
X213400Y-572705D01*
X212800Y-572438D01*
X212100Y-572305D01*
X211400Y-572571D01*
X210800Y-573105D01*
X210400Y-573905D01*
X210200Y-574971D01*
X210400Y-576038D01*
X210800Y-576838D01*
X211400Y-577371D01*
X212100Y-577638D01*
X212800Y-577505D01*
X213400Y-577105D01*
X213800Y-576572D01*
G01X217900Y-580038D02*
X218500Y-580305D01*
X219300Y-580038D01*
X219800Y-579505D01*
X220200Y-578838D01*
X220800Y-576705D01*
X222100Y-572305D01*
G01X218900D02*
X220800Y-576705D01*
G01X226500Y-574038D02*
X229700D01*
X229400Y-573105D01*
X228900Y-572571D01*
X228200Y-572305D01*
X227500Y-572438D01*
X226900Y-572838D01*
X226500Y-573771D01*
X226300Y-574572D01*
Y-575371D01*
X226500Y-576171D01*
X227000Y-576971D01*
X227600Y-577505D01*
X228300Y-577638D01*
X229000Y-577371D01*
X229700Y-576572D01*
G01X234600Y-577638D02*
Y-572305D01*
G01Y-573371D02*
X235100Y-572838D01*
X235600Y-572438D01*
X236300Y-572305D01*
X236800Y-572438D01*
X237400Y-572838D01*
G01X226000Y-626038D02*
X226500Y-626838D01*
X227100Y-627371D01*
X227800Y-627638D01*
X228600Y-627371D01*
X229200Y-626838D01*
X229800Y-626038D01*
X230000Y-624971D01*
Y-619638D01*
G01X237800Y-627638D02*
Y-622305D01*
G01Y-623238D02*
X237400Y-622705D01*
X236800Y-622438D01*
X236100Y-622305D01*
X235400Y-622571D01*
X234800Y-623105D01*
X234400Y-623905D01*
X234200Y-624971D01*
X234400Y-626038D01*
X234800Y-626838D01*
X235400Y-627371D01*
X236100Y-627638D01*
X236800Y-627505D01*
X237400Y-627105D01*
X237800Y-626572D01*
G01X245600Y-622971D02*
X244900Y-622438D01*
X244300Y-622305D01*
X243500Y-622571D01*
X242900Y-623105D01*
X242500Y-624038D01*
X242400Y-624971D01*
X242500Y-625905D01*
X242900Y-626705D01*
X243500Y-627371D01*
X244300Y-627638D01*
X245000Y-627371D01*
X245600Y-626838D01*
G01X250300Y-627638D02*
Y-619638D01*
G01X253500Y-622305D02*
X250300Y-625371D01*
G01X251600Y-624171D02*
X253700Y-627638D01*
G01X236100Y-598638D02*
X238100D01*
Y-601038D01*
X237500Y-601838D01*
X236800Y-602371D01*
X235800Y-602638D01*
X234800Y-602371D01*
X234100Y-601838D01*
X233500Y-601038D01*
X233100Y-600105D01*
X232900Y-599038D01*
Y-598105D01*
X233100Y-597305D01*
X233500Y-596371D01*
X234100Y-595571D01*
X234700Y-595038D01*
X235500Y-594638D01*
X236200D01*
X237000Y-594905D01*
X237600Y-595438D01*
G01X241200Y-602638D02*
Y-594638D01*
X245800Y-602638D01*
Y-594638D01*
G01X249300Y-602638D02*
Y-594638D01*
X251300D01*
X252100Y-595038D01*
X252700Y-595571D01*
X253200Y-596371D01*
X253600Y-597305D01*
X253700Y-598638D01*
X253600Y-599971D01*
X253200Y-600905D01*
X252700Y-601705D01*
X252100Y-602238D01*
X251300Y-602638D01*
X249300D01*
G01X257600Y-595971D02*
X258200Y-595171D01*
X258900Y-594771D01*
X259700Y-594638D01*
X260700Y-594905D01*
X261400Y-595571D01*
X261600Y-596371D01*
X261500Y-597172D01*
X261100Y-597838D01*
X259100Y-599171D01*
X258200Y-600105D01*
X257600Y-601438D01*
X257400Y-602638D01*
X261600D01*
G01X261100Y-574305D02*
X261800Y-573371D01*
X262400Y-572838D01*
X263200Y-572571D01*
X263900Y-572838D01*
X264400Y-573371D01*
X264800Y-574171D01*
X264900Y-575105D01*
X264800Y-575905D01*
X264400Y-576705D01*
X263800Y-577371D01*
X263100Y-577638D01*
X262300Y-577371D01*
X261600Y-576572D01*
X261200Y-575371D01*
X261100Y-574038D01*
X261300Y-572305D01*
X261600Y-571371D01*
X262100Y-570438D01*
X262800Y-569771D01*
X263500Y-569638D01*
X264200Y-569905D01*
X264700Y-570571D01*
G01X328600Y-620971D02*
X329200Y-620171D01*
X329900Y-619771D01*
X330700Y-619638D01*
X331700Y-619905D01*
X332400Y-620571D01*
X332600Y-621371D01*
X332500Y-622172D01*
X332100Y-622838D01*
X330100Y-624171D01*
X329200Y-625105D01*
X328600Y-626438D01*
X328400Y-627638D01*
X332600D01*
G01X338500Y-619638D02*
X337700Y-619905D01*
X337100Y-620571D01*
X336700Y-621371D01*
X336400Y-622438D01*
X336300Y-623638D01*
X336400Y-624838D01*
X336700Y-625905D01*
X337100Y-626705D01*
X337700Y-627371D01*
X338500Y-627638D01*
X339300Y-627371D01*
X339900Y-626705D01*
X340300Y-625905D01*
X340600Y-624838D01*
X340700Y-623638D01*
X340600Y-622438D01*
X340300Y-621371D01*
X339900Y-620571D01*
X339300Y-619905D01*
X338500Y-619638D01*
G01X344600Y-620971D02*
X345200Y-620171D01*
X345900Y-619771D01*
X346700Y-619638D01*
X347700Y-619905D01*
X348400Y-620571D01*
X348600Y-621371D01*
X348500Y-622172D01*
X348100Y-622838D01*
X346100Y-624171D01*
X345200Y-625105D01*
X344600Y-626438D01*
X344400Y-627638D01*
X348600D01*
G01X352300Y-626038D02*
X352900Y-626971D01*
X353700Y-627505D01*
X354600Y-627638D01*
X355400Y-627505D01*
X356200Y-626838D01*
X356700Y-626038D01*
X356800Y-625238D01*
X356600Y-624305D01*
X355900Y-623638D01*
X355200Y-623371D01*
X354300D01*
G01X355200D02*
X355800Y-622971D01*
X356300Y-622305D01*
X356500Y-621505D01*
X356300Y-620705D01*
X355800Y-620038D01*
X354900Y-619638D01*
X354000Y-619771D01*
X353100Y-620305D01*
G01X360700Y-627905D02*
X364300Y-619638D01*
G01X370500D02*
X369700Y-619905D01*
X369100Y-620571D01*
X368700Y-621371D01*
X368400Y-622438D01*
X368300Y-623638D01*
X368400Y-624838D01*
X368700Y-625905D01*
X369100Y-626705D01*
X369700Y-627371D01*
X370500Y-627638D01*
X371300Y-627371D01*
X371900Y-626705D01*
X372300Y-625905D01*
X372600Y-624838D01*
X372700Y-623638D01*
X372600Y-622438D01*
X372300Y-621371D01*
X371900Y-620571D01*
X371300Y-619905D01*
X370500Y-619638D01*
G01X379700Y-627638D02*
Y-619638D01*
X376000Y-625371D01*
X381000D01*
G01X384700Y-627905D02*
X388300Y-619638D01*
G01X394500Y-627638D02*
Y-619638D01*
X393300Y-621238D01*
G01Y-627638D02*
X395700D01*
G01X402300D02*
X402500Y-625905D01*
X402800Y-624438D01*
X403200Y-623105D01*
X403700Y-621638D01*
X404500Y-619638D01*
X400500D01*
G01X328300Y-602638D02*
Y-594638D01*
X330300D01*
X331100Y-595038D01*
X331700Y-595571D01*
X332200Y-596371D01*
X332600Y-597305D01*
X332700Y-598638D01*
X332600Y-599971D01*
X332200Y-600905D01*
X331700Y-601705D01*
X331100Y-602238D01*
X330300Y-602638D01*
X328300D01*
G01X336000D02*
X338500Y-594638D01*
X341000Y-602638D01*
G01X340100Y-599838D02*
X336900D01*
G01X344600Y-602638D02*
Y-594638D01*
X348400D01*
G01X347000Y-598505D02*
X344600D01*
G01X354500Y-594638D02*
X353700Y-594905D01*
X353100Y-595571D01*
X352700Y-596371D01*
X352400Y-597438D01*
X352300Y-598638D01*
X352400Y-599838D01*
X352700Y-600905D01*
X353100Y-601705D01*
X353700Y-602371D01*
X354500Y-602638D01*
X355300Y-602371D01*
X355900Y-601705D01*
X356300Y-600905D01*
X356600Y-599838D01*
X356700Y-598638D01*
X356600Y-597438D01*
X356300Y-596371D01*
X355900Y-595571D01*
X355300Y-594905D01*
X354500Y-594638D01*
G01X362500D02*
Y-602638D01*
G01X360200Y-594638D02*
X364800D01*
G01X367900Y-602638D02*
Y-594638D01*
X370500Y-601305D01*
X373100Y-594638D01*
Y-602638D01*
G01X379300Y-598371D02*
X379700Y-597971D01*
X380000Y-597305D01*
X380200Y-596371D01*
X380000Y-595571D01*
X379600Y-595038D01*
X378900Y-594638D01*
X376200D01*
Y-602638D01*
X379500D01*
X380200Y-602105D01*
X380600Y-601305D01*
X380800Y-600371D01*
X380600Y-599438D01*
X380000Y-598638D01*
X379300Y-598371D01*
X376200D01*
G01X384300Y-601038D02*
X384900Y-601971D01*
X385700Y-602505D01*
X386600Y-602638D01*
X387400Y-602505D01*
X388200Y-601838D01*
X388700Y-601038D01*
X388800Y-600238D01*
X388600Y-599305D01*
X387900Y-598638D01*
X387200Y-598371D01*
X386300D01*
G01X387200D02*
X387800Y-597971D01*
X388300Y-597305D01*
X388500Y-596505D01*
X388300Y-595705D01*
X387800Y-595038D01*
X386900Y-594638D01*
X386000Y-594771D01*
X385100Y-595305D01*
G01X393300Y-594638D02*
X395700D01*
G01X394500D02*
Y-602638D01*
G01X393300D02*
X395700D01*
G01X404700Y-595305D02*
X404100Y-594905D01*
X403400Y-594638D01*
X402600D01*
X401700Y-595038D01*
X401000Y-595705D01*
X400500Y-596505D01*
X400100Y-597838D01*
X400000Y-599038D01*
X400200Y-600238D01*
X400500Y-601038D01*
X401100Y-601838D01*
X401800Y-602371D01*
X402500Y-602638D01*
X403200D01*
X403900Y-602371D01*
X404500Y-601971D01*
X405000Y-601438D01*
G01X410500Y-594638D02*
X409700Y-594905D01*
X409100Y-595571D01*
X408700Y-596371D01*
X408400Y-597438D01*
X408300Y-598638D01*
X408400Y-599838D01*
X408700Y-600905D01*
X409100Y-601705D01*
X409700Y-602371D01*
X410500Y-602638D01*
X411300Y-602371D01*
X411900Y-601705D01*
X412300Y-600905D01*
X412600Y-599838D01*
X412700Y-598638D01*
X412600Y-597438D01*
X412300Y-596371D01*
X411900Y-595571D01*
X411300Y-594905D01*
X410500Y-594638D01*
G01X346100Y-577638D02*
Y-569638D01*
X349900D01*
G01X348500Y-573505D02*
X346100D01*
G01X356000Y-569638D02*
X355200Y-569905D01*
X354600Y-570571D01*
X354200Y-571371D01*
X353900Y-572438D01*
X353800Y-573638D01*
X353900Y-574838D01*
X354200Y-575905D01*
X354600Y-576705D01*
X355200Y-577371D01*
X356000Y-577638D01*
X356800Y-577371D01*
X357400Y-576705D01*
X357800Y-575905D01*
X358100Y-574838D01*
X358200Y-573638D01*
X358100Y-572438D01*
X357800Y-571371D01*
X357400Y-570571D01*
X356800Y-569905D01*
X356000Y-569638D01*
G01X364000D02*
Y-577638D01*
G01X361700Y-569638D02*
X366300D01*
G01X372600Y-573638D02*
X374600D01*
Y-576038D01*
X374000Y-576838D01*
X373300Y-577371D01*
X372300Y-577638D01*
X371300Y-577371D01*
X370600Y-576838D01*
X370000Y-576038D01*
X369600Y-575105D01*
X369400Y-574038D01*
Y-573105D01*
X369600Y-572305D01*
X370000Y-571371D01*
X370600Y-570571D01*
X371200Y-570038D01*
X372000Y-569638D01*
X372700D01*
X373500Y-569905D01*
X374100Y-570438D01*
G01X377000Y-580305D02*
X383000D01*
G01X385400Y-577638D02*
Y-569638D01*
X388000Y-576305D01*
X390600Y-569638D01*
Y-577638D01*
G01X396800Y-573371D02*
X397200Y-572971D01*
X397500Y-572305D01*
X397700Y-571371D01*
X397500Y-570571D01*
X397100Y-570038D01*
X396400Y-569638D01*
X393700D01*
Y-577638D01*
X397000D01*
X397700Y-577105D01*
X398100Y-576305D01*
X398300Y-575371D01*
X398100Y-574438D01*
X397500Y-573638D01*
X396800Y-573371D01*
X393700D01*
G01X417000Y-630638D02*
Y-622638D01*
X415800Y-624238D01*
G01Y-630638D02*
X418200D01*
G01X423100Y-627305D02*
X423800Y-626371D01*
X424400Y-625838D01*
X425200Y-625571D01*
X425900Y-625838D01*
X426400Y-626371D01*
X426800Y-627171D01*
X426900Y-628105D01*
X426800Y-628905D01*
X426400Y-629705D01*
X425800Y-630371D01*
X425100Y-630638D01*
X424300Y-630371D01*
X423600Y-629572D01*
X423200Y-628371D01*
X423100Y-627038D01*
X423300Y-625305D01*
X423600Y-624371D01*
X424100Y-623438D01*
X424800Y-622771D01*
X425500Y-622638D01*
X426200Y-622905D01*
X426700Y-623571D01*
G01X433000Y-630905D02*
X432800Y-630771D01*
Y-630505D01*
X433000Y-630371D01*
X433200Y-630505D01*
Y-630771D01*
X433000Y-630905D01*
G01X439100Y-627305D02*
X439800Y-626371D01*
X440400Y-625838D01*
X441200Y-625571D01*
X441900Y-625838D01*
X442400Y-626371D01*
X442800Y-627171D01*
X442900Y-628105D01*
X442800Y-628905D01*
X442400Y-629705D01*
X441800Y-630371D01*
X441100Y-630638D01*
X440300Y-630371D01*
X439600Y-629572D01*
X439200Y-628371D01*
X439100Y-627038D01*
X439300Y-625305D01*
X439600Y-624371D01*
X440100Y-623438D01*
X440800Y-622771D01*
X441500Y-622638D01*
X442200Y-622905D01*
X442700Y-623571D01*
G01X462000Y-630638D02*
Y-622638D01*
X460800Y-624238D01*
G01Y-630638D02*
X463200D01*
G01X469800D02*
X470000Y-628905D01*
X470300Y-627438D01*
X470700Y-626105D01*
X471200Y-624638D01*
X472000Y-622638D01*
X468000D01*
G01X478000Y-630905D02*
X477800Y-630771D01*
Y-630505D01*
X478000Y-630371D01*
X478200Y-630505D01*
Y-630771D01*
X478000Y-630905D01*
G01X484100Y-623971D02*
X484700Y-623171D01*
X485400Y-622771D01*
X486200Y-622638D01*
X487200Y-622905D01*
X487900Y-623571D01*
X488100Y-624371D01*
X488000Y-625172D01*
X487600Y-625838D01*
X485600Y-627171D01*
X484700Y-628105D01*
X484100Y-629438D01*
X483900Y-630638D01*
X488100D01*
G01X486200Y-598305D02*
X485600Y-597905D01*
X484900Y-597638D01*
X484100D01*
X483200Y-598038D01*
X482500Y-598705D01*
X482000Y-599505D01*
X481600Y-600838D01*
X481500Y-602038D01*
X481700Y-603238D01*
X482000Y-604038D01*
X482600Y-604838D01*
X483300Y-605371D01*
X484000Y-605638D01*
X484700D01*
X485400Y-605371D01*
X486000Y-604971D01*
X486500Y-604438D01*
M02*
